(kicad_pcb
	(version 20260206)
	(generator "pcbnew")
	(generator_version "10.0")
	(general
		(thickness 1.6)
		(legacy_teardrops no)
	)
	(paper "A4")
	(layers
		(0 "F.Cu" signal "TOP")
		(4 "In1.Cu" signal "L2GND")
		(6 "In2.Cu" signal "L3")
		(8 "In3.Cu" signal "L4")
		(10 "In4.Cu" signal "L5GND")
		(2 "B.Cu" signal "BOTTOM")
		(9 "F.Adhes" user "F.Adhesive")
		(11 "B.Adhes" user "B.Adhesive")
		(13 "F.Paste" user "Package Geometry/Pastemask Top")
		(15 "B.Paste" user "Package Geometry/Pastemask Bottom")
		(5 "F.SilkS" user "Ref Des/Silkscreen Top")
		(7 "B.SilkS" user "Ref Des/Silkscreen Bottom")
		(1 "F.Mask" user "Board Geometry/Soldermask Top")
		(3 "B.Mask" user "Board Geometry/Soldermask Bottom")
		(17 "Dwgs.User" user "User.Drawings")
		(19 "Cmts.User" user "User.Comments")
		(21 "Eco1.User" user "User.Eco1")
		(23 "Eco2.User" user "User.Eco2")
		(25 "Edge.Cuts" user "Board Geometry/Outline")
		(27 "Margin" user)
		(31 "F.CrtYd" user "Package Geometry/Place Bound Top")
		(29 "B.CrtYd" user "Package Geometry/Place Bound Bottom")
		(35 "F.Fab" user "Ref Des/Assembly Top")
		(33 "B.Fab" user "Ref Des/Assembly Bottom")
	)
	(setup
		(pad_to_mask_clearance 0)
		(allow_soldermask_bridges_in_footprints no)
		(tenting
			(front yes)
			(back yes)
		)
		(covering
			(front no)
			(back no)
		)
		(plugging
			(front no)
			(back no)
		)
		(capping no)
		(filling no)
		(pcbplotparams
			(layerselection 0x00000000_00000000_55555555_5755f5ff)
			(plot_on_all_layers_selection 0x00000000_00000000_00000000_00000000)
			(disableapertmacros no)
			(usegerberextensions no)
			(usegerberattributes yes)
			(usegerberadvancedattributes yes)
			(creategerberjobfile yes)
			(dashed_line_dash_ratio 12)
			(dashed_line_gap_ratio 3)
			(svgprecision 4)
			(plotframeref no)
			(mode 1)
			(useauxorigin no)
			(pdf_front_fp_property_popups yes)
			(pdf_back_fp_property_popups yes)
			(pdf_metadata yes)
			(pdf_single_document no)
			(dxfpolygonmode yes)
			(dxfimperialunits yes)
			(dxfusepcbnewfont yes)
			(psnegative no)
			(psa4output no)
			(plot_black_and_white yes)
			(sketchpadsonfab no)
			(plotpadnumbers no)
			(hidednponfab no)
			(sketchdnponfab yes)
			(crossoutdnponfab yes)
			(subtractmaskfromsilk no)
			(outputformat 1)
			(mirror no)
			(drillshape 1)
			(scaleselection 1)
			(outputdirectory "")
		)
	)
	(footprint ""
		(layer "F.Cu")
		(at 43.688 -2.9591 90)
		(property "Reference" "C27"
			(at 0 0 90)
			(layer "F.SilkS")
			(hide yes)
			(effects
				(font
					(size 1.27 1.27)
				)
			)
		)
		(property "Value" "SC10U6D3V3MX-7-GP-U"
			(at 0 -2.8194 90)
			(unlocked yes)
			(layer "F.Fab")
			(hide yes)
			(effects
				(font
					(size 1.016 1.016)
					(thickness 0.1524)
				)
			)
		)
		(property "Device Type" "C603H40"
			(at 0 -4.3434 90)
			(unlocked yes)
			(layer "F.Fab")
			(hide yes)
			(effects
				(font
					(size 1.016 1.016)
					(thickness 0.1524)
				)
			)
		)
		(duplicate_pad_numbers_are_jumpers no)
		(fp_line
			(start 0.508 0)
			(end -0.508 0)
			(stroke
				(width 0.2032)
				(type default)
			)
			(layer "F.SilkS")
		)
		(fp_rect
			(start -0.5842 1.3335)
			(end 0.5842 -1.3335)
			(stroke
				(width 0)
				(type default)
			)
			(fill no)
			(layer "F.CrtYd")
		)
		(fp_rect
			(start -0.5842 1.3335)
			(end 0.5842 -1.3335)
			(stroke
				(width 0)
				(type default)
			)
			(fill no)
			(layer "F.Fab")
		)
		(pad "1" smd custom
			(at 0 -0.762 90)
			(size 0.2159 0.2159)
			(layers "F.Cu" "F.Mask" "F.Paste")
			(net "P3V3_STBY")
			(options
				(clearance outline)
				(anchor circle)
			)
			(primitives
				(gr_poly
					(pts
						(arc
							(start -0.3302 -0.4318)
							(mid -0.402042 -0.402042)
							(end -0.4318 -0.3302)
						)
						(arc
							(start -0.4318 0.3302)
							(mid -0.402042 0.402042)
							(end -0.3302 0.4318)
						)
						(arc
							(start 0.3302 0.4318)
							(mid 0.402042 0.402042)
							(end 0.4318 0.3302)
						)
						(arc
							(start 0.4318 -0.3302)
							(mid 0.402042 -0.402042)
							(end 0.3302 -0.4318)
						)
					)
					(width 0)
					(fill yes)
				)
			)
		)
		(pad "2" smd custom
			(at 0 0.762 90)
			(size 0.2159 0.2159)
			(layers "F.Cu" "F.Mask" "F.Paste")
			(net "GND")
			(options
				(clearance outline)
				(anchor circle)
			)
			(primitives
				(gr_poly
					(pts
						(arc
							(start -0.3302 -0.4318)
							(mid -0.402042 -0.402042)
							(end -0.4318 -0.3302)
						)
						(arc
							(start -0.4318 0.3302)
							(mid -0.402042 0.402042)
							(end -0.3302 0.4318)
						)
						(arc
							(start 0.3302 0.4318)
							(mid 0.402042 0.402042)
							(end 0.4318 0.3302)
						)
						(arc
							(start 0.4318 -0.3302)
							(mid 0.402042 -0.402042)
							(end 0.3302 -0.4318)
						)
					)
					(width 0)
					(fill yes)
				)
			)
		)
	)
	(footprint ""
		(layer "F.Cu")
		(at 83.3628 -21.1328)
		(property "Reference" "R43"
			(at 0 0 0)
			(layer "F.SilkS")
			(hide yes)
			(effects
				(font
					(size 1.27 1.27)
				)
			)
		)
		(property "Value" "3K3R2F-2-GP"
			(at 0.064008 -3.993896 0)
			(unlocked yes)
			(layer "F.Fab")
			(hide yes)
			(effects
				(font
					(size 1.016 1.016)
					(thickness 0.1524)
				)
			)
		)
		(property "Device Type" "R402H16"
			(at 0.064008 -5.517896 0)
			(unlocked yes)
			(layer "F.Fab")
			(hide yes)
			(effects
				(font
					(size 1.016 1.016)
					(thickness 0.1524)
				)
			)
		)
		(duplicate_pad_numbers_are_jumpers no)
		(fp_line
			(start -0.508 -0.9398)
			(end -0.508 0.9398)
			(stroke
				(width 0.1524)
				(type default)
			)
			(layer "F.SilkS")
		)
		(fp_line
			(start 0.508 -0.9398)
			(end -0.508 -0.9398)
			(stroke
				(width 0.1524)
				(type default)
			)
			(layer "F.SilkS")
		)
		(fp_rect
			(start -0.508 0.9398)
			(end 0.508 -0.9398)
			(stroke
				(width 0)
				(type default)
			)
			(fill no)
			(layer "F.CrtYd")
		)
		(fp_rect
			(start -0.508 0.9398)
			(end 0.508 -0.9398)
			(stroke
				(width 0)
				(type default)
			)
			(fill no)
			(layer "F.Fab")
		)
		(pad "1" smd custom
			(at 0 -0.4445)
			(size 0.1397 0.1397)
			(layers "F.Cu" "F.Mask" "F.Paste")
			(net "RESET_IN")
			(options
				(clearance outline)
				(anchor circle)
			)
			(primitives
				(gr_poly
					(pts
						(arc
							(start -0.1778 -0.2794)
							(mid -0.249642 -0.249642)
							(end -0.2794 -0.1778)
						)
						(arc
							(start -0.2794 0.1778)
							(mid -0.249642 0.249642)
							(end -0.1778 0.2794)
						)
						(arc
							(start 0.1778 0.2794)
							(mid 0.249642 0.249642)
							(end 0.2794 0.1778)
						)
						(arc
							(start 0.2794 -0.1778)
							(mid 0.249642 -0.249642)
							(end 0.1778 -0.2794)
						)
					)
					(width 0)
					(fill yes)
				)
			)
		)
		(pad "2" smd custom
			(at 0 0.4445)
			(size 0.1397 0.1397)
			(layers "F.Cu" "F.Mask" "F.Paste")
			(net "GND")
			(options
				(clearance outline)
				(anchor circle)
			)
			(primitives
				(gr_poly
					(pts
						(arc
							(start -0.1778 -0.2794)
							(mid -0.249642 -0.249642)
							(end -0.2794 -0.1778)
						)
						(arc
							(start -0.2794 0.1778)
							(mid -0.249642 0.249642)
							(end -0.1778 0.2794)
						)
						(arc
							(start 0.1778 0.2794)
							(mid 0.249642 0.249642)
							(end 0.2794 0.1778)
						)
						(arc
							(start 0.2794 -0.1778)
							(mid 0.249642 -0.249642)
							(end 0.1778 -0.2794)
						)
					)
					(width 0)
					(fill yes)
				)
			)
		)
	)
	(footprint ""
		(layer "F.Cu")
		(at 118.7958 -33.4264 90)
		(property "Reference" "RU26"
			(at 0 0 90)
			(layer "F.SilkS")
			(hide yes)
			(effects
				(font
					(size 1.27 1.27)
				)
			)
		)
		(property "Value" "10KR2F-2-GP"
			(at 0.064008 -3.993896 90)
			(unlocked yes)
			(layer "F.Fab")
			(hide yes)
			(effects
				(font
					(size 1.016 1.016)
					(thickness 0.1524)
				)
			)
		)
		(property "Device Type" "R402H16"
			(at 0.064008 -5.517896 90)
			(unlocked yes)
			(layer "F.Fab")
			(hide yes)
			(effects
				(font
					(size 1.016 1.016)
					(thickness 0.1524)
				)
			)
		)
		(duplicate_pad_numbers_are_jumpers no)
		(fp_line
			(start 0.508 -0.9398)
			(end -0.508 -0.9398)
			(stroke
				(width 0.1524)
				(type default)
			)
			(layer "F.SilkS")
		)
		(fp_line
			(start -0.508 -0.9398)
			(end -0.508 0.9398)
			(stroke
				(width 0.1524)
				(type default)
			)
			(layer "F.SilkS")
		)
		(fp_rect
			(start -0.508 0.9398)
			(end 0.508 -0.9398)
			(stroke
				(width 0)
				(type default)
			)
			(fill no)
			(layer "F.CrtYd")
		)
		(fp_rect
			(start -0.508 0.9398)
			(end 0.508 -0.9398)
			(stroke
				(width 0)
				(type default)
			)
			(fill no)
			(layer "F.Fab")
		)
		(pad "1" smd custom
			(at 0 -0.4445 90)
			(size 0.1397 0.1397)
			(layers "F.Cu" "F.Mask" "F.Paste")
			(net "P3V3_USB_HUB")
			(options
				(clearance outline)
				(anchor circle)
			)
			(primitives
				(gr_poly
					(pts
						(arc
							(start -0.1778 -0.2794)
							(mid -0.249642 -0.249642)
							(end -0.2794 -0.1778)
						)
						(arc
							(start -0.2794 0.1778)
							(mid -0.249642 0.249642)
							(end -0.1778 0.2794)
						)
						(arc
							(start 0.1778 0.2794)
							(mid 0.249642 0.249642)
							(end 0.2794 0.1778)
						)
						(arc
							(start 0.2794 -0.1778)
							(mid 0.249642 -0.249642)
							(end 0.1778 -0.2794)
						)
					)
					(width 0)
					(fill yes)
				)
			)
		)
		(pad "2" smd custom
			(at 0 0.4445 90)
			(size 0.1397 0.1397)
			(layers "F.Cu" "F.Mask" "F.Paste")
			(net "USB_DN2")
			(options
				(clearance outline)
				(anchor circle)
			)
			(primitives
				(gr_poly
					(pts
						(arc
							(start -0.1778 -0.2794)
							(mid -0.249642 -0.249642)
							(end -0.2794 -0.1778)
						)
						(arc
							(start -0.2794 0.1778)
							(mid -0.249642 0.249642)
							(end -0.1778 0.2794)
						)
						(arc
							(start 0.1778 0.2794)
							(mid 0.249642 0.249642)
							(end 0.2794 0.1778)
						)
						(arc
							(start 0.2794 -0.1778)
							(mid 0.249642 -0.249642)
							(end 0.1778 -0.2794)
						)
					)
					(width 0)
					(fill yes)
				)
			)
		)
	)
	(footprint ""
		(layer "F.Cu")
		(at 42.7482 -0.1651 90)
		(property "Reference" "Q1"
			(at 0 0 90)
			(layer "F.SilkS")
			(hide yes)
			(effects
				(font
					(size 1.27 1.27)
				)
			)
		)
		(property "Value" "2N7002KDW-1-GP"
			(at -2.3622 -8.2042 90)
			(unlocked yes)
			(layer "F.Fab")
			(hide yes)
			(effects
				(font
					(size 1.016 1.016)
					(thickness 0.1524)
				)
			)
		)
		(property "Device Type" "SOT-363H44"
			(at -2.3622 -10.1092 90)
			(unlocked yes)
			(layer "F.Fab")
			(hide yes)
			(effects
				(font
					(size 1.016 1.016)
					(thickness 0.1524)
				)
			)
		)
		(duplicate_pad_numbers_are_jumpers no)
		(fp_line
			(start 1.4478 -1.7018)
			(end -1.4478 -1.7018)
			(stroke
				(width 0.1524)
				(type default)
			)
			(layer "F.SilkS")
		)
		(fp_line
			(start -1.4478 -1.7018)
			(end -1.4478 1.7018)
			(stroke
				(width 0.1524)
				(type default)
			)
			(layer "F.SilkS")
		)
		(fp_line
			(start -1.27 1.524)
			(end -1.27 0.6604)
			(stroke
				(width 0.4826)
				(type default)
			)
			(layer "F.SilkS")
		)
		(fp_line
			(start 1.4478 1.7018)
			(end 1.4478 -1.7018)
			(stroke
				(width 0.1524)
				(type default)
			)
			(layer "F.SilkS")
		)
		(fp_line
			(start -1.4478 1.7018)
			(end 1.4478 1.7018)
			(stroke
				(width 0.1524)
				(type default)
			)
			(layer "F.SilkS")
		)
		(fp_poly
			(pts
				(xy -1.524 -1.778) (xy 1.524 -1.778) (xy 1.524 1.778) (xy -1.524 1.778)
			)
			(stroke
				(width 0)
				(type default)
			)
			(fill no)
			(layer "F.CrtYd")
		)
		(fp_poly
			(pts
				(xy -1.524 -1.778) (xy 1.524 -1.778) (xy 1.524 1.778) (xy -1.524 1.778)
			)
			(stroke
				(width 0)
				(type default)
			)
			(fill no)
			(layer "F.Fab")
		)
		(pad "1" smd rect
			(at -0.65024 0.9398 90)
			(size 0.4064 1.016)
			(layers "F.Cu" "F.Mask" "F.Paste")
			(net "GND")
		)
		(pad "2" smd rect
			(at 0 0.9398 90)
			(size 0.4064 1.016)
			(layers "F.Cu" "F.Mask" "F.Paste")
			(net "SMB_PCH_ALERT_N")
		)
		(pad "3" smd rect
			(at 0.65024 0.9398 90)
			(size 0.4064 1.016)
			(layers "F.Cu" "F.Mask" "F.Paste")
			(net "SMB_PCH_ALERT_R_N")
		)
		(pad "4" smd rect
			(at 0.65024 -0.9398 90)
			(size 0.4064 1.016)
			(layers "F.Cu" "F.Mask" "F.Paste")
			(net "GND")
		)
		(pad "5" smd rect
			(at 0 -0.9398 90)
			(size 0.4064 1.016)
			(layers "F.Cu" "F.Mask" "F.Paste")
			(net "SMB_PCH_ALERT")
		)
		(pad "6" smd rect
			(at -0.65024 -0.9398 90)
			(size 0.4064 1.016)
			(layers "F.Cu" "F.Mask" "F.Paste")
			(net "SMB_PCH_ALERT")
		)
	)
	(footprint ""
		(layer "F.Cu")
		(at 32.40024 -24.08682 180)
		(property "Reference" "R113"
			(at 0 0 180)
			(layer "F.SilkS")
			(hide yes)
			(effects
				(font
					(size 1.27 1.27)
				)
			)
		)
		(property "Value" "0R2F-1-GP"
			(at 0.064008 -3.993896 180)
			(unlocked yes)
			(layer "F.Fab")
			(hide yes)
			(effects
				(font
					(size 1.016 1.016)
					(thickness 0.1524)
				)
			)
		)
		(property "Device Type" "R402H16"
			(at 0.064008 -5.517896 180)
			(unlocked yes)
			(layer "F.Fab")
			(hide yes)
			(effects
				(font
					(size 1.016 1.016)
					(thickness 0.1524)
				)
			)
		)
		(duplicate_pad_numbers_are_jumpers no)
		(fp_line
			(start 0.508 -0.9398)
			(end -0.508 -0.9398)
			(stroke
				(width 0.1524)
				(type default)
			)
			(layer "F.SilkS")
		)
		(fp_line
			(start -0.508 -0.9398)
			(end -0.508 0.9398)
			(stroke
				(width 0.1524)
				(type default)
			)
			(layer "F.SilkS")
		)
		(fp_rect
			(start -0.508 0.9398)
			(end 0.508 -0.9398)
			(stroke
				(width 0)
				(type default)
			)
			(fill no)
			(layer "F.CrtYd")
		)
		(fp_rect
			(start -0.508 0.9398)
			(end 0.508 -0.9398)
			(stroke
				(width 0)
				(type default)
			)
			(fill no)
			(layer "F.Fab")
		)
		(pad "1" smd custom
			(at 0 -0.4445 180)
			(size 0.1397 0.1397)
			(layers "F.Cu" "F.Mask" "F.Paste")
			(net "SMCLK_PCH_SLOT3")
			(options
				(clearance outline)
				(anchor circle)
			)
			(primitives
				(gr_poly
					(pts
						(arc
							(start -0.1778 -0.2794)
							(mid -0.249642 -0.249642)
							(end -0.2794 -0.1778)
						)
						(arc
							(start -0.2794 0.1778)
							(mid -0.249642 0.249642)
							(end -0.1778 0.2794)
						)
						(arc
							(start 0.1778 0.2794)
							(mid 0.249642 0.249642)
							(end 0.2794 0.1778)
						)
						(arc
							(start 0.2794 -0.1778)
							(mid 0.249642 -0.249642)
							(end 0.1778 -0.2794)
						)
					)
					(width 0)
					(fill yes)
				)
			)
		)
		(pad "2" smd custom
			(at 0 0.4445 180)
			(size 0.1397 0.1397)
			(layers "F.Cu" "F.Mask" "F.Paste")
			(net "SMCLK_PCH_SLOT3_R")
			(options
				(clearance outline)
				(anchor circle)
			)
			(primitives
				(gr_poly
					(pts
						(arc
							(start -0.1778 -0.2794)
							(mid -0.249642 -0.249642)
							(end -0.2794 -0.1778)
						)
						(arc
							(start -0.2794 0.1778)
							(mid -0.249642 0.249642)
							(end -0.1778 0.2794)
						)
						(arc
							(start 0.1778 0.2794)
							(mid 0.249642 0.249642)
							(end 0.2794 0.1778)
						)
						(arc
							(start 0.2794 -0.1778)
							(mid 0.249642 -0.249642)
							(end 0.1778 -0.2794)
						)
					)
					(width 0)
					(fill yes)
				)
			)
		)
	)
	(footprint ""
		(layer "F.Cu")
		(at 107.7468 3.1496)
		(property "Reference" "R14"
			(at 0 0 0)
			(layer "F.SilkS")
			(hide yes)
			(effects
				(font
					(size 1.27 1.27)
				)
			)
		)
		(property "Value" "10KR2F-2-GP"
			(at 0.064008 -3.993896 0)
			(unlocked yes)
			(layer "F.Fab")
			(hide yes)
			(effects
				(font
					(size 1.016 1.016)
					(thickness 0.1524)
				)
			)
		)
		(property "Device Type" "R402H16"
			(at 0.064008 -5.517896 0)
			(unlocked yes)
			(layer "F.Fab")
			(hide yes)
			(effects
				(font
					(size 1.016 1.016)
					(thickness 0.1524)
				)
			)
		)
		(duplicate_pad_numbers_are_jumpers no)
		(fp_line
			(start -0.508 -0.9398)
			(end -0.508 0.9398)
			(stroke
				(width 0.1524)
				(type default)
			)
			(layer "F.SilkS")
		)
		(fp_line
			(start 0.508 -0.9398)
			(end -0.508 -0.9398)
			(stroke
				(width 0.1524)
				(type default)
			)
			(layer "F.SilkS")
		)
		(fp_rect
			(start -0.508 0.9398)
			(end 0.508 -0.9398)
			(stroke
				(width 0)
				(type default)
			)
			(fill no)
			(layer "F.CrtYd")
		)
		(fp_rect
			(start -0.508 0.9398)
			(end 0.508 -0.9398)
			(stroke
				(width 0)
				(type default)
			)
			(fill no)
			(layer "F.Fab")
		)
		(pad "1" smd custom
			(at 0 -0.4445)
			(size 0.1397 0.1397)
			(layers "F.Cu" "F.Mask" "F.Paste")
			(net "SMB_B_HUB_A1")
			(options
				(clearance outline)
				(anchor circle)
			)
			(primitives
				(gr_poly
					(pts
						(arc
							(start -0.1778 -0.2794)
							(mid -0.249642 -0.249642)
							(end -0.2794 -0.1778)
						)
						(arc
							(start -0.2794 0.1778)
							(mid -0.249642 0.249642)
							(end -0.1778 0.2794)
						)
						(arc
							(start 0.1778 0.2794)
							(mid 0.249642 0.249642)
							(end 0.2794 0.1778)
						)
						(arc
							(start 0.2794 -0.1778)
							(mid 0.249642 -0.249642)
							(end 0.1778 -0.2794)
						)
					)
					(width 0)
					(fill yes)
				)
			)
		)
		(pad "2" smd custom
			(at 0 0.4445)
			(size 0.1397 0.1397)
			(layers "F.Cu" "F.Mask" "F.Paste")
			(net "GND")
			(options
				(clearance outline)
				(anchor circle)
			)
			(primitives
				(gr_poly
					(pts
						(arc
							(start -0.1778 -0.2794)
							(mid -0.249642 -0.249642)
							(end -0.2794 -0.1778)
						)
						(arc
							(start -0.2794 0.1778)
							(mid -0.249642 0.249642)
							(end -0.1778 0.2794)
						)
						(arc
							(start 0.1778 0.2794)
							(mid 0.249642 0.249642)
							(end 0.2794 0.1778)
						)
						(arc
							(start 0.2794 -0.1778)
							(mid 0.249642 -0.249642)
							(end 0.1778 -0.2794)
						)
					)
					(width 0)
					(fill yes)
				)
			)
		)
	)
	(footprint ""
		(layer "F.Cu")
		(at 126.619 -21.1582 180)
		(property "Reference" "C41"
			(at 0 0 180)
			(layer "F.SilkS")
			(hide yes)
			(effects
				(font
					(size 1.27 1.27)
				)
			)
		)
		(property "Value" "SCD1U16V2KX-3GP"
			(at 1.1811 -2.7051 180)
			(unlocked yes)
			(layer "F.Fab")
			(hide yes)
			(effects
				(font
					(size 1.016 1.016)
					(thickness 0.1524)
				)
			)
		)
		(property "Device Type" "C402H22"
			(at 1.1811 -4.2291 180)
			(unlocked yes)
			(layer "F.Fab")
			(hide yes)
			(effects
				(font
					(size 1.016 1.016)
					(thickness 0.1524)
				)
			)
		)
		(duplicate_pad_numbers_are_jumpers no)
		(fp_rect
			(start -0.4318 0.9525)
			(end 0.4318 -0.9525)
			(stroke
				(width 0)
				(type default)
			)
			(fill no)
			(layer "F.CrtYd")
		)
		(fp_rect
			(start -0.4318 0.9525)
			(end 0.4318 -0.9525)
			(stroke
				(width 0)
				(type default)
			)
			(fill no)
			(layer "F.Fab")
		)
		(pad "1" smd custom
			(at 0 -0.4445 180)
			(size 0.1524 0.1524)
			(layers "F.Cu" "F.Mask" "F.Paste")
			(net "P3V3_STBY")
			(options
				(clearance outline)
				(anchor circle)
			)
			(primitives
				(gr_poly
					(pts
						(arc
							(start 0.3048 -0.2032)
							(mid 0.275042 -0.275042)
							(end 0.2032 -0.3048)
						)
						(arc
							(start -0.2032 -0.3048)
							(mid -0.275042 -0.275042)
							(end -0.3048 -0.2032)
						)
						(arc
							(start -0.3048 0.2032)
							(mid -0.275042 0.275042)
							(end -0.2032 0.3048)
						)
						(arc
							(start 0.2032 0.3048)
							(mid 0.275042 0.275042)
							(end 0.3048 0.2032)
						)
					)
					(width 0)
					(fill yes)
				)
			)
		)
		(pad "2" smd custom
			(at 0 0.4445 180)
			(size 0.1524 0.1524)
			(layers "F.Cu" "F.Mask" "F.Paste")
			(net "GND")
			(options
				(clearance outline)
				(anchor circle)
			)
			(primitives
				(gr_poly
					(pts
						(arc
							(start 0.3048 -0.2032)
							(mid 0.275042 -0.275042)
							(end 0.2032 -0.3048)
						)
						(arc
							(start -0.2032 -0.3048)
							(mid -0.275042 -0.275042)
							(end -0.3048 -0.2032)
						)
						(arc
							(start -0.3048 0.2032)
							(mid -0.275042 0.275042)
							(end -0.2032 0.3048)
						)
						(arc
							(start 0.2032 0.3048)
							(mid 0.275042 0.275042)
							(end 0.3048 0.2032)
						)
					)
					(width 0)
					(fill yes)
				)
			)
		)
	)
	(footprint ""
		(layer "F.Cu")
		(at 31.25724 -24.06142 180)
		(property "Reference" "R33"
			(at 0 0 180)
			(layer "F.SilkS")
			(hide yes)
			(effects
				(font
					(size 1.27 1.27)
				)
			)
		)
		(property "Value" "0R2F-1-GP"
			(at 0.064008 -3.993896 180)
			(unlocked yes)
			(layer "F.Fab")
			(hide yes)
			(effects
				(font
					(size 1.016 1.016)
					(thickness 0.1524)
				)
			)
		)
		(property "Device Type" "R402H16"
			(at 0.064008 -5.517896 180)
			(unlocked yes)
			(layer "F.Fab")
			(hide yes)
			(effects
				(font
					(size 1.016 1.016)
					(thickness 0.1524)
				)
			)
		)
		(duplicate_pad_numbers_are_jumpers no)
		(fp_line
			(start 0.508 -0.9398)
			(end -0.508 -0.9398)
			(stroke
				(width 0.1524)
				(type default)
			)
			(layer "F.SilkS")
		)
		(fp_line
			(start -0.508 -0.9398)
			(end -0.508 0.9398)
			(stroke
				(width 0.1524)
				(type default)
			)
			(layer "F.SilkS")
		)
		(fp_rect
			(start -0.508 0.9398)
			(end 0.508 -0.9398)
			(stroke
				(width 0)
				(type default)
			)
			(fill no)
			(layer "F.CrtYd")
		)
		(fp_rect
			(start -0.508 0.9398)
			(end 0.508 -0.9398)
			(stroke
				(width 0)
				(type default)
			)
			(fill no)
			(layer "F.Fab")
		)
		(pad "1" smd custom
			(at 0 -0.4445 180)
			(size 0.1397 0.1397)
			(layers "F.Cu" "F.Mask" "F.Paste")
			(net "SMDAT_BMC_SLOT3")
			(options
				(clearance outline)
				(anchor circle)
			)
			(primitives
				(gr_poly
					(pts
						(arc
							(start -0.1778 -0.2794)
							(mid -0.249642 -0.249642)
							(end -0.2794 -0.1778)
						)
						(arc
							(start -0.2794 0.1778)
							(mid -0.249642 0.249642)
							(end -0.1778 0.2794)
						)
						(arc
							(start 0.1778 0.2794)
							(mid 0.249642 0.249642)
							(end 0.2794 0.1778)
						)
						(arc
							(start 0.2794 -0.1778)
							(mid 0.249642 -0.249642)
							(end 0.1778 -0.2794)
						)
					)
					(width 0)
					(fill yes)
				)
			)
		)
		(pad "2" smd custom
			(at 0 0.4445 180)
			(size 0.1397 0.1397)
			(layers "F.Cu" "F.Mask" "F.Paste")
			(net "SMDAT_BMC_SLOT3_R")
			(options
				(clearance outline)
				(anchor circle)
			)
			(primitives
				(gr_poly
					(pts
						(arc
							(start -0.1778 -0.2794)
							(mid -0.249642 -0.249642)
							(end -0.2794 -0.1778)
						)
						(arc
							(start -0.2794 0.1778)
							(mid -0.249642 0.249642)
							(end -0.1778 0.2794)
						)
						(arc
							(start 0.1778 0.2794)
							(mid 0.249642 0.249642)
							(end 0.2794 0.1778)
						)
						(arc
							(start 0.2794 -0.1778)
							(mid 0.249642 -0.249642)
							(end 0.1778 -0.2794)
						)
					)
					(width 0)
					(fill yes)
				)
			)
		)
	)
	(footprint ""
		(layer "F.Cu")
		(at 91.7956 -17.8308 90)
		(property "Reference" "U10"
			(at 0 0 90)
			(layer "F.SilkS")
			(hide yes)
			(effects
				(font
					(size 1.27 1.27)
				)
			)
		)
		(property "Value" "SN74LVC1G08DCKR-GP"
			(at -2.3368 -8.6868 90)
			(unlocked yes)
			(layer "F.Fab")
			(hide yes)
			(effects
				(font
					(size 1.016 1.016)
					(thickness 0.1524)
				)
			)
		)
		(property "Device Type" "SC70-5H44"
			(at -2.3114 -10.414 90)
			(unlocked yes)
			(layer "F.Fab")
			(hide yes)
			(effects
				(font
					(size 1.016 1.016)
					(thickness 0.1524)
				)
			)
		)
		(duplicate_pad_numbers_are_jumpers no)
		(fp_line
			(start 1.3843 -1.8034)
			(end 1.3843 -1.1176)
			(stroke
				(width 0.3302)
				(type default)
			)
			(layer "F.SilkS")
		)
		(fp_line
			(start 0.6604 -1.8034)
			(end 1.3843 -1.8034)
			(stroke
				(width 0.3302)
				(type default)
			)
			(layer "F.SilkS")
		)
		(fp_line
			(start 1.27 -1.7018)
			(end 1.27 1.7018)
			(stroke
				(width 0.1524)
				(type default)
			)
			(layer "F.SilkS")
		)
		(fp_line
			(start -1.27 -1.7018)
			(end 1.27 -1.7018)
			(stroke
				(width 0.1524)
				(type default)
			)
			(layer "F.SilkS")
		)
		(fp_line
			(start 1.27 1.7018)
			(end -1.27 1.7018)
			(stroke
				(width 0.1524)
				(type default)
			)
			(layer "F.SilkS")
		)
		(fp_line
			(start -1.27 1.7018)
			(end -1.27 -1.7018)
			(stroke
				(width 0.1524)
				(type default)
			)
			(layer "F.SilkS")
		)
		(fp_rect
			(start -1.524 1.9558)
			(end 1.524 -1.9558)
			(stroke
				(width 0)
				(type default)
			)
			(fill no)
			(layer "F.CrtYd")
		)
		(fp_poly
			(pts
				(xy -1.524 -1.9558) (xy 1.524 -1.9558) (xy 1.524 1.9558) (xy -1.524 1.9558)
			)
			(stroke
				(width 0)
				(type default)
			)
			(fill no)
			(layer "F.Fab")
		)
		(pad "1" smd rect
			(at 0.65024 -0.8255 90)
			(size 0.4064 1.2192)
			(layers "F.Cu" "F.Mask" "F.Paste")
			(net "PERST_N")
		)
		(pad "2" smd rect
			(at 0 -0.8255 90)
			(size 0.4064 1.2192)
			(layers "F.Cu" "F.Mask" "F.Paste")
			(net "PERST_N_1_R")
		)
		(pad "3" smd rect
			(at -0.65024 -0.8255 90)
			(size 0.4064 1.2192)
			(layers "F.Cu" "F.Mask" "F.Paste")
			(net "GND")
		)
		(pad "4" smd rect
			(at -0.65024 0.8255 90)
			(size 0.4064 1.2192)
			(layers "F.Cu" "F.Mask" "F.Paste")
			(net "PERST_SLOT_N")
		)
		(pad "5" smd rect
			(at 0.65024 0.8255 90)
			(size 0.4064 1.2192)
			(layers "F.Cu" "F.Mask" "F.Paste")
			(net "P3V3_STBY")
		)
	)
	(footprint ""
		(layer "F.Cu")
		(at 87.6554 -17.272 -90)
		(property "Reference" "R71"
			(at 0 0 270)
			(layer "F.SilkS")
			(hide yes)
			(effects
				(font
					(size 1.27 1.27)
				)
			)
		)
		(property "Value" "0R2F-1-GP"
			(at 0.064008 -3.993896 270)
			(unlocked yes)
			(layer "F.Fab")
			(hide yes)
			(effects
				(font
					(size 1.016 1.016)
					(thickness 0.1524)
				)
			)
		)
		(property "Device Type" "R402H16"
			(at 0.064008 -5.517896 270)
			(unlocked yes)
			(layer "F.Fab")
			(hide yes)
			(effects
				(font
					(size 1.016 1.016)
					(thickness 0.1524)
				)
			)
		)
		(duplicate_pad_numbers_are_jumpers no)
		(fp_line
			(start -0.508 -0.9398)
			(end -0.508 0.9398)
			(stroke
				(width 0.1524)
				(type default)
			)
			(layer "F.SilkS")
		)
		(fp_line
			(start 0.508 -0.9398)
			(end -0.508 -0.9398)
			(stroke
				(width 0.1524)
				(type default)
			)
			(layer "F.SilkS")
		)
		(fp_rect
			(start -0.508 0.9398)
			(end 0.508 -0.9398)
			(stroke
				(width 0)
				(type default)
			)
			(fill no)
			(layer "F.CrtYd")
		)
		(fp_rect
			(start -0.508 0.9398)
			(end 0.508 -0.9398)
			(stroke
				(width 0)
				(type default)
			)
			(fill no)
			(layer "F.Fab")
		)
		(pad "1" smd custom
			(at 0 -0.4445 270)
			(size 0.1397 0.1397)
			(layers "F.Cu" "F.Mask" "F.Paste")
			(net "RESET_O_1")
			(options
				(clearance outline)
				(anchor circle)
			)
			(primitives
				(gr_poly
					(pts
						(arc
							(start -0.1778 -0.2794)
							(mid -0.249642 -0.249642)
							(end -0.2794 -0.1778)
						)
						(arc
							(start -0.2794 0.1778)
							(mid -0.249642 0.249642)
							(end -0.1778 0.2794)
						)
						(arc
							(start 0.1778 0.2794)
							(mid 0.249642 0.249642)
							(end 0.2794 0.1778)
						)
						(arc
							(start 0.2794 -0.1778)
							(mid 0.249642 -0.249642)
							(end 0.1778 -0.2794)
						)
					)
					(width 0)
					(fill yes)
				)
			)
		)
		(pad "2" smd custom
			(at 0 0.4445 270)
			(size 0.1397 0.1397)
			(layers "F.Cu" "F.Mask" "F.Paste")
			(net "PERST_O_1_R")
			(options
				(clearance outline)
				(anchor circle)
			)
			(primitives
				(gr_poly
					(pts
						(arc
							(start -0.1778 -0.2794)
							(mid -0.249642 -0.249642)
							(end -0.2794 -0.1778)
						)
						(arc
							(start -0.2794 0.1778)
							(mid -0.249642 0.249642)
							(end -0.1778 0.2794)
						)
						(arc
							(start 0.1778 0.2794)
							(mid 0.249642 0.249642)
							(end 0.2794 0.1778)
						)
						(arc
							(start 0.2794 -0.1778)
							(mid 0.249642 -0.249642)
							(end 0.1778 -0.2794)
						)
					)
					(width 0)
					(fill yes)
				)
			)
		)
	)
	(footprint ""
		(layer "F.Cu")
		(at 116.5606 -19.05)
		(property "Reference" "R131"
			(at 0 0 0)
			(layer "F.SilkS")
			(hide yes)
			(effects
				(font
					(size 1.27 1.27)
				)
			)
		)
		(property "Value" "10KR2F-2-GP"
			(at 0.064008 -3.993896 0)
			(unlocked yes)
			(layer "F.Fab")
			(hide yes)
			(effects
				(font
					(size 1.016 1.016)
					(thickness 0.1524)
				)
			)
		)
		(property "Device Type" "R402H16"
			(at 0.064008 -5.517896 0)
			(unlocked yes)
			(layer "F.Fab")
			(hide yes)
			(effects
				(font
					(size 1.016 1.016)
					(thickness 0.1524)
				)
			)
		)
		(duplicate_pad_numbers_are_jumpers no)
		(fp_line
			(start -0.508 -0.9398)
			(end -0.508 0.9398)
			(stroke
				(width 0.1524)
				(type default)
			)
			(layer "F.SilkS")
		)
		(fp_line
			(start 0.508 -0.9398)
			(end -0.508 -0.9398)
			(stroke
				(width 0.1524)
				(type default)
			)
			(layer "F.SilkS")
		)
		(fp_rect
			(start -0.508 0.9398)
			(end 0.508 -0.9398)
			(stroke
				(width 0)
				(type default)
			)
			(fill no)
			(layer "F.CrtYd")
		)
		(fp_rect
			(start -0.508 0.9398)
			(end 0.508 -0.9398)
			(stroke
				(width 0)
				(type default)
			)
			(fill no)
			(layer "F.Fab")
		)
		(pad "1" smd custom
			(at 0 -0.4445)
			(size 0.1397 0.1397)
			(layers "F.Cu" "F.Mask" "F.Paste")
			(net "P3V3_STBY")
			(options
				(clearance outline)
				(anchor circle)
			)
			(primitives
				(gr_poly
					(pts
						(arc
							(start -0.1778 -0.2794)
							(mid -0.249642 -0.249642)
							(end -0.2794 -0.1778)
						)
						(arc
							(start -0.2794 0.1778)
							(mid -0.249642 0.249642)
							(end -0.1778 0.2794)
						)
						(arc
							(start 0.1778 0.2794)
							(mid 0.249642 0.249642)
							(end 0.2794 0.1778)
						)
						(arc
							(start 0.2794 -0.1778)
							(mid 0.249642 -0.249642)
							(end 0.1778 -0.2794)
						)
					)
					(width 0)
					(fill yes)
				)
			)
		)
		(pad "2" smd custom
			(at 0 0.4445)
			(size 0.1397 0.1397)
			(layers "F.Cu" "F.Mask" "F.Paste")
			(net "GPIO_B_EXP_A2")
			(options
				(clearance outline)
				(anchor circle)
			)
			(primitives
				(gr_poly
					(pts
						(arc
							(start -0.1778 -0.2794)
							(mid -0.249642 -0.249642)
							(end -0.2794 -0.1778)
						)
						(arc
							(start -0.2794 0.1778)
							(mid -0.249642 0.249642)
							(end -0.1778 0.2794)
						)
						(arc
							(start 0.1778 0.2794)
							(mid 0.249642 0.249642)
							(end 0.2794 0.1778)
						)
						(arc
							(start 0.2794 -0.1778)
							(mid 0.249642 -0.249642)
							(end 0.1778 -0.2794)
						)
					)
					(width 0)
					(fill yes)
				)
			)
		)
	)
	(footprint ""
		(layer "F.Cu")
		(at 94.5134 -16.8656)
		(property "Reference" "R70"
			(at 0 0 0)
			(layer "F.SilkS")
			(hide yes)
			(effects
				(font
					(size 1.27 1.27)
				)
			)
		)
		(property "Value" "0R2F-1-GP"
			(at 0.064008 -3.993896 0)
			(unlocked yes)
			(layer "F.Fab")
			(hide yes)
			(effects
				(font
					(size 1.016 1.016)
					(thickness 0.1524)
				)
			)
		)
		(property "Device Type" "R402H16"
			(at 0.064008 -5.517896 0)
			(unlocked yes)
			(layer "F.Fab")
			(hide yes)
			(effects
				(font
					(size 1.016 1.016)
					(thickness 0.1524)
				)
			)
		)
		(duplicate_pad_numbers_are_jumpers no)
		(fp_line
			(start -0.508 -0.9398)
			(end -0.508 0.9398)
			(stroke
				(width 0.1524)
				(type default)
			)
			(layer "F.SilkS")
		)
		(fp_line
			(start 0.508 -0.9398)
			(end -0.508 -0.9398)
			(stroke
				(width 0.1524)
				(type default)
			)
			(layer "F.SilkS")
		)
		(fp_rect
			(start -0.508 0.9398)
			(end 0.508 -0.9398)
			(stroke
				(width 0)
				(type default)
			)
			(fill no)
			(layer "F.CrtYd")
		)
		(fp_rect
			(start -0.508 0.9398)
			(end 0.508 -0.9398)
			(stroke
				(width 0)
				(type default)
			)
			(fill no)
			(layer "F.Fab")
		)
		(pad "1" smd custom
			(at 0 -0.4445)
			(size 0.1397 0.1397)
			(layers "F.Cu" "F.Mask" "F.Paste")
			(net "PERST_SLOT_N")
			(options
				(clearance outline)
				(anchor circle)
			)
			(primitives
				(gr_poly
					(pts
						(arc
							(start -0.1778 -0.2794)
							(mid -0.249642 -0.249642)
							(end -0.2794 -0.1778)
						)
						(arc
							(start -0.2794 0.1778)
							(mid -0.249642 0.249642)
							(end -0.1778 0.2794)
						)
						(arc
							(start 0.1778 0.2794)
							(mid 0.249642 0.249642)
							(end 0.2794 0.1778)
						)
						(arc
							(start 0.2794 -0.1778)
							(mid 0.249642 -0.249642)
							(end 0.1778 -0.2794)
						)
					)
					(width 0)
					(fill yes)
				)
			)
		)
		(pad "2" smd custom
			(at 0 0.4445)
			(size 0.1397 0.1397)
			(layers "F.Cu" "F.Mask" "F.Paste")
			(net "RESET_BUF_N_SLOT3")
			(options
				(clearance outline)
				(anchor circle)
			)
			(primitives
				(gr_poly
					(pts
						(arc
							(start -0.1778 -0.2794)
							(mid -0.249642 -0.249642)
							(end -0.2794 -0.1778)
						)
						(arc
							(start -0.2794 0.1778)
							(mid -0.249642 0.249642)
							(end -0.1778 0.2794)
						)
						(arc
							(start 0.1778 0.2794)
							(mid 0.249642 0.249642)
							(end 0.2794 0.1778)
						)
						(arc
							(start 0.2794 -0.1778)
							(mid 0.249642 -0.249642)
							(end 0.1778 -0.2794)
						)
					)
					(width 0)
					(fill yes)
				)
			)
		)
	)
	(footprint ""
		(layer "F.Cu")
		(at 21.5646 -19.2786 180)
		(property "Reference" "U14"
			(at 0 0 180)
			(layer "F.SilkS")
			(hide yes)
			(effects
				(font
					(size 1.27 1.27)
				)
			)
		)
		(property "Value" "INA230AIRGTR-GP"
			(at -5.6388 -6.1468 180)
			(unlocked yes)
			(layer "F.Fab")
			(hide yes)
			(effects
				(font
					(size 1.016 1.016)
					(thickness 0.1524)
				)
			)
		)
		(property "Device Type" "QFN16-G1D8-UH40"
			(at -5.6388 -7.6708 180)
			(unlocked yes)
			(layer "F.Fab")
			(hide yes)
			(effects
				(font
					(size 1.016 1.016)
					(thickness 0.1524)
				)
			)
		)
		(duplicate_pad_numbers_are_jumpers no)
		(fp_line
			(start 2.5146 2.5146)
			(end 2.5146 1.2446)
			(stroke
				(width 0.1524)
				(type default)
			)
			(layer "F.SilkS")
		)
		(fp_line
			(start 2.287524 -0.260604)
			(end 2.795524 -0.260604)
			(stroke
				(width 0.1524)
				(type default)
			)
			(layer "F.SilkS")
		)
		(fp_line
			(start 1.2446 2.5146)
			(end 2.5146 2.5146)
			(stroke
				(width 0.1524)
				(type default)
			)
			(layer "F.SilkS")
		)
		(fp_line
			(start -0.248666 2.287524)
			(end -0.248666 3.049524)
			(stroke
				(width 0.1524)
				(type default)
			)
			(layer "F.SilkS")
		)
		(fp_line
			(start -1.2446 -2.5146)
			(end -2.5146 -2.5146)
			(stroke
				(width 0.1524)
				(type default)
			)
			(layer "F.SilkS")
		)
		(fp_line
			(start -2.287524 -0.753364)
			(end -2.795524 -0.753364)
			(stroke
				(width 0.1524)
				(type default)
			)
			(layer "F.SilkS")
		)
		(fp_line
			(start -2.5146 2.5146)
			(end -1.2446 2.5146)
			(stroke
				(width 0.1524)
				(type default)
			)
			(layer "F.SilkS")
		)
		(fp_line
			(start -2.5146 1.2446)
			(end -2.5146 2.5146)
			(stroke
				(width 0.1524)
				(type default)
			)
			(layer "F.SilkS")
		)
		(fp_line
			(start -2.5146 -2.5146)
			(end -2.5146 -1.2446)
			(stroke
				(width 0.1524)
				(type default)
			)
			(layer "F.SilkS")
		)
		(fp_poly
			(pts
				(xy 1.2446 -2.5146) (xy 2.5146 -2.5146) (xy 2.5146 -1.2446)
			)
			(stroke
				(width 0)
				(type default)
			)
			(fill yes)
			(layer "F.SilkS")
		)
		(fp_rect
			(start -1.4986 1.4986)
			(end 1.4986 -1.4986)
			(stroke
				(width 0)
				(type default)
			)
			(fill no)
			(layer "F.CrtYd")
		)
		(fp_poly
			(pts
				(xy -1.4986 -1.4986) (xy -2.5146 -1.4986) (xy -2.5146 -2.5146) (xy 2.5146 -2.5146) (xy 2.5146 2.5146)
				(xy -2.5146 2.5146) (xy -2.5146 -1.4859) (xy -1.4986 -1.4859) (xy -1.4986 1.4986) (xy 1.4986 1.4986)
				(xy 1.4986 -1.4986)
			)
			(stroke
				(width 0)
				(type default)
			)
			(fill no)
			(layer "F.CrtYd")
		)
		(fp_rect
			(start -2.5146 2.5146)
			(end 2.5146 -2.5146)
			(stroke
				(width 0)
				(type default)
			)
			(fill no)
			(layer "F.Fab")
		)
		(pad "1" smd rect
			(at 0.750062 -1.550924 180)
			(size 0.3048 0.9144)
			(layers "F.Cu" "F.Mask" "F.Paste")
			(net "SLOT2_VMONITOR_A1")
		)
		(pad "2" smd rect
			(at 0.249936 -1.550924 180)
			(size 0.3048 0.9144)
			(layers "F.Cu" "F.Mask" "F.Paste")
			(net "SLOT2_VMONITOR_A0")
		)
		(pad "3" smd rect
			(at -0.249936 -1.550924 180)
			(size 0.3048 0.9144)
			(layers "F.Cu" "F.Mask" "F.Paste")
			(net "SMB_VMONITOR_SLOT2_ALERT_N")
		)
		(pad "4" smd rect
			(at -0.750062 -1.550924 180)
			(size 0.3048 0.9144)
			(layers "F.Cu" "F.Mask" "F.Paste")
			(net "SMB_VMONITOR_SLOT2_MUX_SDA")
		)
		(pad "5" smd rect
			(at -1.550924 -0.750062 180)
			(size 0.9144 0.3048)
			(layers "F.Cu" "F.Mask" "F.Paste")
			(net "SMB_VMONITOR_SLOT2_MUX_SCL")
		)
		(pad "6" smd rect
			(at -1.550924 -0.249936 180)
			(size 0.9144 0.3048)
			(layers "F.Cu" "F.Mask" "F.Paste")
			(net "Net_226")
		)
		(pad "7" smd rect
			(at -1.550924 0.249936 180)
			(size 0.9144 0.3048)
			(layers "F.Cu" "F.Mask" "F.Paste")
			(net "Net_227")
		)
		(pad "8" smd rect
			(at -1.550924 0.750062 180)
			(size 0.9144 0.3048)
			(layers "F.Cu" "F.Mask" "F.Paste")
			(net "Net_228")
		)
		(pad "9" smd rect
			(at -0.750062 1.550924 180)
			(size 0.3048 0.9144)
			(layers "F.Cu" "F.Mask" "F.Paste")
			(net "P3V3_STBY")
		)
		(pad "10" smd rect
			(at -0.249936 1.550924 180)
			(size 0.3048 0.9144)
			(layers "F.Cu" "F.Mask" "F.Paste")
			(net "GND")
		)
		(pad "11" smd rect
			(at 0.249936 1.550924 180)
			(size 0.3048 0.9144)
			(layers "F.Cu" "F.Mask" "F.Paste")
			(net "P12V")
		)
		(pad "12" smd rect
			(at 0.750062 1.550924 180)
			(size 0.3048 0.9144)
			(layers "F.Cu" "F.Mask" "F.Paste")
			(net "SLOT2_P12V_SENSE_VN_R")
		)
		(pad "13" smd rect
			(at 1.550924 0.750062 180)
			(size 0.9144 0.3048)
			(layers "F.Cu" "F.Mask" "F.Paste")
			(net "SLOT2_P12V_SENSE_VP_R")
		)
		(pad "14" smd rect
			(at 1.550924 0.249936 180)
			(size 0.9144 0.3048)
			(layers "F.Cu" "F.Mask" "F.Paste")
			(net "Net_223")
		)
		(pad "15" smd rect
			(at 1.550924 -0.249936 180)
			(size 0.9144 0.3048)
			(layers "F.Cu" "F.Mask" "F.Paste")
			(net "Net_224")
		)
		(pad "16" smd rect
			(at 1.550924 -0.750062 180)
			(size 0.9144 0.3048)
			(layers "F.Cu" "F.Mask" "F.Paste")
			(net "Net_225")
		)
		(pad "17" smd rect
			(at 0 0 180)
			(size 1.778 1.778)
			(layers "F.Cu" "F.Mask" "F.Paste")
			(net "GND")
		)
	)
	(footprint ""
		(layer "F.Cu")
		(at 124.8664 -15.9004 -90)
		(property "Reference" "U20"
			(at 0 0 270)
			(layer "F.SilkS")
			(hide yes)
			(effects
				(font
					(size 1.27 1.27)
				)
			)
		)
		(property "Value" "PCA9555PW-GP"
			(at 0 -12.1412 270)
			(unlocked yes)
			(layer "F.Fab")
			(hide yes)
			(effects
				(font
					(size 1.016 1.016)
					(thickness 0.1524)
				)
			)
		)
		(property "Device Type" "TSOIC24H44"
			(at 0 -13.6652 270)
			(unlocked yes)
			(layer "F.Fab")
			(hide yes)
			(effects
				(font
					(size 1.016 1.016)
					(thickness 0.1524)
				)
			)
		)
		(duplicate_pad_numbers_are_jumpers no)
		(fp_line
			(start -4.0386 1.778)
			(end -4.0386 3.556)
			(stroke
				(width 0.3556)
				(type default)
			)
			(layer "F.SilkS")
		)
		(fp_line
			(start 3.683 1.778)
			(end -4.1148 1.778)
			(stroke
				(width 0.1524)
				(type default)
			)
			(layer "F.SilkS")
		)
		(fp_line
			(start -3.8354 0)
			(end -4.1148 0.2794)
			(stroke
				(width 0.1524)
				(type default)
			)
			(layer "F.SilkS")
		)
		(fp_line
			(start -3.8354 0)
			(end -4.1148 -0.2794)
			(stroke
				(width 0.1524)
				(type default)
			)
			(layer "F.SilkS")
		)
		(fp_line
			(start -4.1148 -1.778)
			(end -4.1148 1.778)
			(stroke
				(width 0.1524)
				(type default)
			)
			(layer "F.SilkS")
		)
		(fp_line
			(start -4.1148 -1.778)
			(end 3.683 -1.778)
			(stroke
				(width 0.1524)
				(type default)
			)
			(layer "F.SilkS")
		)
		(fp_line
			(start 3.683 -1.778)
			(end 3.683 1.778)
			(stroke
				(width 0.1524)
				(type default)
			)
			(layer "F.SilkS")
		)
		(fp_poly
			(pts
				(xy -3.7592 -1.778) (xy 3.683 -1.778) (xy 3.683 1.778) (xy -3.7592 1.778)
			)
			(stroke
				(width 0)
				(type default)
			)
			(fill yes)
			(layer "F.SilkS")
		)
		(fp_poly
			(pts
				(xy -4.22656 3.81) (xy 4.22656 3.81) (xy 4.22656 -3.81) (xy -4.22656 -3.81)
			)
			(stroke
				(width 0)
				(type default)
			)
			(fill no)
			(layer "F.CrtYd")
		)
		(fp_poly
			(pts
				(xy -4.22656 -3.81) (xy 4.22656 -3.81) (xy 4.22656 3.81) (xy -4.22656 3.81)
			)
			(stroke
				(width 0)
				(type default)
			)
			(fill no)
			(layer "F.Fab")
		)
		(pad "1" smd rect
			(at -3.57632 2.8194 270)
			(size 0.3556 1.524)
			(layers "F.Cu" "F.Mask" "F.Paste")
			(net "GPIO_B_EXP_INT_N")
		)
		(pad "2" smd rect
			(at -2.92608 2.8194 270)
			(size 0.3556 1.524)
			(layers "F.Cu" "F.Mask" "F.Paste")
			(net "GPIO_B_EXP_A1")
		)
		(pad "3" smd rect
			(at -2.27584 2.8194 270)
			(size 0.3556 1.524)
			(layers "F.Cu" "F.Mask" "F.Paste")
			(net "GPIO_B_EXP_A2")
		)
		(pad "4" smd rect
			(at -1.6256 2.8194 270)
			(size 0.3556 1.524)
			(layers "F.Cu" "F.Mask" "F.Paste")
			(net "PCIE_SLOT2_PRSNT2_1_N")
		)
		(pad "5" smd rect
			(at -0.97536 2.8194 270)
			(size 0.3556 1.524)
			(layers "F.Cu" "F.Mask" "F.Paste")
			(net "PCIE_SLOT2_PRSNT2_2_N")
		)
		(pad "6" smd rect
			(at -0.32512 2.8194 270)
			(size 0.3556 1.524)
			(layers "F.Cu" "F.Mask" "F.Paste")
			(net "PCIE_SLOT2_PRSNT2_3_N")
		)
		(pad "7" smd rect
			(at 0.32512 2.8194 270)
			(size 0.3556 1.524)
			(layers "F.Cu" "F.Mask" "F.Paste")
			(net "PCIE_SLOT2_PRSNT2_4_N")
		)
		(pad "8" smd rect
			(at 0.97536 2.8194 270)
			(size 0.3556 1.524)
			(layers "F.Cu" "F.Mask" "F.Paste")
			(net "PCIE_SLOT3_PRSNT2_1_N")
		)
		(pad "9" smd rect
			(at 1.6256 2.8194 270)
			(size 0.3556 1.524)
			(layers "F.Cu" "F.Mask" "F.Paste")
			(net "PCIE_SLOT3_PRSNT2_2_N")
		)
		(pad "10" smd rect
			(at 2.27584 2.8194 270)
			(size 0.3556 1.524)
			(layers "F.Cu" "F.Mask" "F.Paste")
			(net "PCIE_SLOT3_PRSNT2_3_N")
		)
		(pad "11" smd rect
			(at 2.92608 2.8194 270)
			(size 0.3556 1.524)
			(layers "F.Cu" "F.Mask" "F.Paste")
			(net "PCIE_SLOT3_PRSNT2_4_N")
		)
		(pad "12" smd rect
			(at 3.57632 2.8194 270)
			(size 0.3556 1.524)
			(layers "F.Cu" "F.Mask" "F.Paste")
			(net "GND")
		)
		(pad "13" smd rect
			(at 3.57632 -2.8194 270)
			(size 0.3556 1.524)
			(layers "F.Cu" "F.Mask" "F.Paste")
			(net "GPIO_B_IO1_0")
		)
		(pad "14" smd rect
			(at 2.92608 -2.8194 270)
			(size 0.3556 1.524)
			(layers "F.Cu" "F.Mask" "F.Paste")
			(net "FM_SLT_CFG0")
		)
		(pad "15" smd rect
			(at 2.27584 -2.8194 270)
			(size 0.3556 1.524)
			(layers "F.Cu" "F.Mask" "F.Paste")
			(net "FM_SLT_CFG1")
		)
		(pad "16" smd rect
			(at 1.6256 -2.8194 270)
			(size 0.3556 1.524)
			(layers "F.Cu" "F.Mask" "F.Paste")
			(net "GPIO_B_IO1_3")
		)
		(pad "17" smd rect
			(at 0.97536 -2.8194 270)
			(size 0.3556 1.524)
			(layers "F.Cu" "F.Mask" "F.Paste")
			(net "GPIO_B_IO1_4")
		)
		(pad "18" smd rect
			(at 0.32512 -2.8194 270)
			(size 0.3556 1.524)
			(layers "F.Cu" "F.Mask" "F.Paste")
			(net "GPIO_B_IO1_5")
		)
		(pad "19" smd rect
			(at -0.32512 -2.8194 270)
			(size 0.3556 1.524)
			(layers "F.Cu" "F.Mask" "F.Paste")
			(net "GPIO_B_IO1_6")
		)
		(pad "20" smd rect
			(at -0.97536 -2.8194 270)
			(size 0.3556 1.524)
			(layers "F.Cu" "F.Mask" "F.Paste")
			(net "GPIO_B_IO1_7")
		)
		(pad "21" smd rect
			(at -1.6256 -2.8194 270)
			(size 0.3556 1.524)
			(layers "F.Cu" "F.Mask" "F.Paste")
			(net "GPIO_B_EXP_A0")
		)
		(pad "22" smd rect
			(at -2.27584 -2.8194 270)
			(size 0.3556 1.524)
			(layers "F.Cu" "F.Mask" "F.Paste")
			(net "SMCLK_EXP_R_BMC")
		)
		(pad "23" smd rect
			(at -2.92608 -2.8194 270)
			(size 0.3556 1.524)
			(layers "F.Cu" "F.Mask" "F.Paste")
			(net "SMDAT_BMC_DEVICE")
		)
		(pad "24" smd rect
			(at -3.57632 -2.8194 270)
			(size 0.3556 1.524)
			(layers "F.Cu" "F.Mask" "F.Paste")
			(net "P3V3_STBY")
		)
	)
	(footprint ""
		(layer "F.Cu")
		(at 87.10676 -20.897088)
		(property "Reference" "U5"
			(at 0 0 0)
			(layer "F.SilkS")
			(hide yes)
			(effects
				(font
					(size 1.27 1.27)
				)
			)
		)
		(property "Value" "TPS3809K33-2-GP"
			(at 0 -4.3942 0)
			(unlocked yes)
			(layer "F.Fab")
			(hide yes)
			(effects
				(font
					(size 1.016 1.016)
					(thickness 0.1524)
				)
			)
		)
		(property "Device Type" "SOT-23-1H58"
			(at 0 -5.7912 0)
			(unlocked yes)
			(layer "F.Fab")
			(hide yes)
			(effects
				(font
					(size 1.016 1.016)
					(thickness 0.1524)
				)
			)
		)
		(duplicate_pad_numbers_are_jumpers no)
		(fp_line
			(start -1.7018 -0.254)
			(end -1.7018 0.254)
			(stroke
				(width 0.1524)
				(type default)
			)
			(layer "F.SilkS")
		)
		(fp_line
			(start -1.7018 0.254)
			(end 1.7018 0.254)
			(stroke
				(width 0.1524)
				(type default)
			)
			(layer "F.SilkS")
		)
		(fp_line
			(start 1.7018 -0.254)
			(end -1.7018 -0.254)
			(stroke
				(width 0.1524)
				(type default)
			)
			(layer "F.SilkS")
		)
		(fp_line
			(start 1.7018 0.254)
			(end 1.7018 -0.254)
			(stroke
				(width 0.1524)
				(type default)
			)
			(layer "F.SilkS")
		)
		(fp_rect
			(start -1.778 1.9812)
			(end 1.778 -1.9812)
			(stroke
				(width 0)
				(type default)
			)
			(fill no)
			(layer "F.CrtYd")
		)
		(fp_rect
			(start -1.778 1.9812)
			(end 1.778 -1.9812)
			(stroke
				(width 0)
				(type default)
			)
			(fill no)
			(layer "F.Fab")
		)
		(pad "1" smd custom
			(at -1.016 1.1176)
			(size 0.254 0.254)
			(layers "F.Cu" "F.Mask" "F.Paste")
			(net "GND")
			(options
				(clearance outline)
				(anchor circle)
			)
			(primitives
				(gr_poly
					(pts
						(arc
							(start -0.508 -0.4064)
							(mid -0.448484 -0.550084)
							(end -0.3048 -0.6096)
						)
						(arc
							(start 0.3048 -0.6096)
							(mid 0.448484 -0.550084)
							(end 0.508 -0.4064)
						)
						(arc
							(start 0.508 0.4064)
							(mid 0.448484 0.550084)
							(end 0.3048 0.6096)
						)
						(arc
							(start -0.3048 0.6096)
							(mid -0.448484 0.550084)
							(end -0.508 0.4064)
						)
					)
					(width 0)
					(fill yes)
				)
			)
		)
		(pad "2" smd custom
			(at 1.016 1.1176)
			(size 0.254 0.254)
			(layers "F.Cu" "F.Mask" "F.Paste")
			(net "RESET_O_1")
			(options
				(clearance outline)
				(anchor circle)
			)
			(primitives
				(gr_poly
					(pts
						(arc
							(start -0.508 -0.4064)
							(mid -0.448484 -0.550084)
							(end -0.3048 -0.6096)
						)
						(arc
							(start 0.3048 -0.6096)
							(mid 0.448484 -0.550084)
							(end 0.508 -0.4064)
						)
						(arc
							(start 0.508 0.4064)
							(mid 0.448484 0.550084)
							(end 0.3048 0.6096)
						)
						(arc
							(start -0.3048 0.6096)
							(mid -0.448484 0.550084)
							(end -0.508 0.4064)
						)
					)
					(width 0)
					(fill yes)
				)
			)
		)
		(pad "3" smd custom
			(at 0 -1.1176)
			(size 0.254 0.254)
			(layers "F.Cu" "F.Mask" "F.Paste")
			(net "RESET_IN")
			(options
				(clearance outline)
				(anchor circle)
			)
			(primitives
				(gr_poly
					(pts
						(arc
							(start -0.508 -0.4064)
							(mid -0.448484 -0.550084)
							(end -0.3048 -0.6096)
						)
						(arc
							(start 0.3048 -0.6096)
							(mid 0.448484 -0.550084)
							(end 0.508 -0.4064)
						)
						(arc
							(start 0.508 0.4064)
							(mid 0.448484 0.550084)
							(end 0.3048 0.6096)
						)
						(arc
							(start -0.3048 0.6096)
							(mid -0.448484 0.550084)
							(end -0.508 0.4064)
						)
					)
					(width 0)
					(fill yes)
				)
			)
		)
	)
	(footprint ""
		(layer "F.Cu")
		(at 130.2004 -19.812)
		(property "Reference" "R41"
			(at 0 0 0)
			(layer "F.SilkS")
			(hide yes)
			(effects
				(font
					(size 1.27 1.27)
				)
			)
		)
		(property "Value" "0R2F-1-GP"
			(at 0.064008 -3.993896 0)
			(unlocked yes)
			(layer "F.Fab")
			(hide yes)
			(effects
				(font
					(size 1.016 1.016)
					(thickness 0.1524)
				)
			)
		)
		(property "Device Type" "R402H16"
			(at 0.064008 -5.517896 0)
			(unlocked yes)
			(layer "F.Fab")
			(hide yes)
			(effects
				(font
					(size 1.016 1.016)
					(thickness 0.1524)
				)
			)
		)
		(duplicate_pad_numbers_are_jumpers no)
		(fp_line
			(start -0.508 -0.9398)
			(end -0.508 0.9398)
			(stroke
				(width 0.1524)
				(type default)
			)
			(layer "F.SilkS")
		)
		(fp_line
			(start 0.508 -0.9398)
			(end -0.508 -0.9398)
			(stroke
				(width 0.1524)
				(type default)
			)
			(layer "F.SilkS")
		)
		(fp_rect
			(start -0.508 0.9398)
			(end 0.508 -0.9398)
			(stroke
				(width 0)
				(type default)
			)
			(fill no)
			(layer "F.CrtYd")
		)
		(fp_rect
			(start -0.508 0.9398)
			(end 0.508 -0.9398)
			(stroke
				(width 0)
				(type default)
			)
			(fill no)
			(layer "F.Fab")
		)
		(pad "1" smd custom
			(at 0 -0.4445)
			(size 0.1397 0.1397)
			(layers "F.Cu" "F.Mask" "F.Paste")
			(net "SMCLK_BMC_DEVICE")
			(options
				(clearance outline)
				(anchor circle)
			)
			(primitives
				(gr_poly
					(pts
						(arc
							(start -0.1778 -0.2794)
							(mid -0.249642 -0.249642)
							(end -0.2794 -0.1778)
						)
						(arc
							(start -0.2794 0.1778)
							(mid -0.249642 0.249642)
							(end -0.1778 0.2794)
						)
						(arc
							(start 0.1778 0.2794)
							(mid 0.249642 0.249642)
							(end 0.2794 0.1778)
						)
						(arc
							(start 0.2794 -0.1778)
							(mid 0.249642 -0.249642)
							(end 0.1778 -0.2794)
						)
					)
					(width 0)
					(fill yes)
				)
			)
		)
		(pad "2" smd custom
			(at 0 0.4445)
			(size 0.1397 0.1397)
			(layers "F.Cu" "F.Mask" "F.Paste")
			(net "SMCLK_EXP_R_BMC")
			(options
				(clearance outline)
				(anchor circle)
			)
			(primitives
				(gr_poly
					(pts
						(arc
							(start -0.1778 -0.2794)
							(mid -0.249642 -0.249642)
							(end -0.2794 -0.1778)
						)
						(arc
							(start -0.2794 0.1778)
							(mid -0.249642 0.249642)
							(end -0.1778 0.2794)
						)
						(arc
							(start 0.1778 0.2794)
							(mid 0.249642 0.249642)
							(end 0.2794 0.1778)
						)
						(arc
							(start 0.2794 -0.1778)
							(mid 0.249642 -0.249642)
							(end 0.1778 -0.2794)
						)
					)
					(width 0)
					(fill yes)
				)
			)
		)
	)
	(footprint ""
		(layer "F.Cu")
		(at 13.97 -32.0548 180)
		(property "Reference" "C28"
			(at 0 0 180)
			(layer "F.SilkS")
			(hide yes)
			(effects
				(font
					(size 1.27 1.27)
				)
			)
		)
		(property "Value" "SCD1U25V3KX-GP"
			(at 0 -2.8194 180)
			(unlocked yes)
			(layer "F.Fab")
			(hide yes)
			(effects
				(font
					(size 1.016 1.016)
					(thickness 0.1524)
				)
			)
		)
		(property "Device Type" "C603H36"
			(at 0 -4.3434 180)
			(unlocked yes)
			(layer "F.Fab")
			(hide yes)
			(effects
				(font
					(size 1.016 1.016)
					(thickness 0.1524)
				)
			)
		)
		(duplicate_pad_numbers_are_jumpers no)
		(fp_line
			(start 0.508 0)
			(end -0.508 0)
			(stroke
				(width 0.2032)
				(type default)
			)
			(layer "F.SilkS")
		)
		(fp_rect
			(start -0.5842 1.3335)
			(end 0.5842 -1.3335)
			(stroke
				(width 0)
				(type default)
			)
			(fill no)
			(layer "F.CrtYd")
		)
		(fp_rect
			(start -0.5842 1.3335)
			(end 0.5842 -1.3335)
			(stroke
				(width 0)
				(type default)
			)
			(fill no)
			(layer "F.Fab")
		)
		(pad "1" smd custom
			(at 0 -0.762 180)
			(size 0.2159 0.2159)
			(layers "F.Cu" "F.Mask" "F.Paste")
			(net "P12V_SLOT3")
			(options
				(clearance outline)
				(anchor circle)
			)
			(primitives
				(gr_poly
					(pts
						(arc
							(start -0.3302 -0.4318)
							(mid -0.402042 -0.402042)
							(end -0.4318 -0.3302)
						)
						(arc
							(start -0.4318 0.3302)
							(mid -0.402042 0.402042)
							(end -0.3302 0.4318)
						)
						(arc
							(start 0.3302 0.4318)
							(mid 0.402042 0.402042)
							(end 0.4318 0.3302)
						)
						(arc
							(start 0.4318 -0.3302)
							(mid 0.402042 -0.402042)
							(end 0.3302 -0.4318)
						)
					)
					(width 0)
					(fill yes)
				)
			)
		)
		(pad "2" smd custom
			(at 0 0.762 180)
			(size 0.2159 0.2159)
			(layers "F.Cu" "F.Mask" "F.Paste")
			(net "GND")
			(options
				(clearance outline)
				(anchor circle)
			)
			(primitives
				(gr_poly
					(pts
						(arc
							(start -0.3302 -0.4318)
							(mid -0.402042 -0.402042)
							(end -0.4318 -0.3302)
						)
						(arc
							(start -0.4318 0.3302)
							(mid -0.402042 0.402042)
							(end -0.3302 0.4318)
						)
						(arc
							(start 0.3302 0.4318)
							(mid 0.402042 0.402042)
							(end 0.4318 0.3302)
						)
						(arc
							(start 0.4318 -0.3302)
							(mid 0.402042 -0.402042)
							(end 0.3302 -0.4318)
						)
					)
					(width 0)
					(fill yes)
				)
			)
		)
	)
	(footprint ""
		(layer "F.Cu")
		(at 16.353536 -19.63801 135)
		(property "Reference" "R81"
			(at 0 0 135)
			(layer "F.SilkS")
			(hide yes)
			(effects
				(font
					(size 1.27 1.27)
				)
			)
		)
		(property "Value" "10R2F-L-GP"
			(at 0.064119 -3.993804 135)
			(unlocked yes)
			(layer "F.Fab")
			(hide yes)
			(effects
				(font
					(size 1.016 1.016)
					(thickness 0.1524)
				)
			)
		)
		(property "Device Type" "R402H14"
			(at 0.064119 -5.517933 135)
			(unlocked yes)
			(layer "F.Fab")
			(hide yes)
			(effects
				(font
					(size 1.016 1.016)
					(thickness 0.1524)
				)
			)
		)
		(duplicate_pad_numbers_are_jumpers no)
		(fp_line
			(start 0.508103 -0.939874)
			(end -0.507923 -0.939694)
			(stroke
				(width 0.1524)
				(type default)
			)
			(layer "F.SilkS")
		)
		(fp_line
			(start -0.507923 -0.939694)
			(end -0.507923 0.939694)
			(stroke
				(width 0.1524)
				(type default)
			)
			(layer "F.SilkS")
		)
		(fp_poly
			(pts
				(xy -0.507923 -0.939906) (xy 0.508077 -0.939905) (xy 0.508076 0.939694) (xy -0.507923 0.939694)
			)
			(stroke
				(width 0)
				(type default)
			)
			(fill no)
			(layer "F.CrtYd")
		)
		(fp_poly
			(pts
				(xy -0.507923 -0.939906) (xy 0.508077 -0.939905) (xy 0.508076 0.939694) (xy -0.507923 0.939694)
			)
			(stroke
				(width 0)
				(type default)
			)
			(fill no)
			(layer "F.Fab")
		)
		(pad "1" smd custom
			(at 0 -0.4445 135)
			(size 0.1397 0.1397)
			(layers "F.Cu" "F.Mask" "F.Paste")
			(net "P12V_SLOT2")
			(options
				(clearance outline)
				(anchor circle)
			)
			(primitives
				(gr_poly
					(pts
						(arc
							(start -0.1778 -0.2794)
							(mid -0.249642 -0.249642)
							(end -0.2794 -0.1778)
						)
						(arc
							(start -0.2794 0.1778)
							(mid -0.249642 0.249642)
							(end -0.1778 0.2794)
						)
						(arc
							(start 0.1778 0.2794)
							(mid 0.249642 0.249642)
							(end 0.2794 0.1778)
						)
						(arc
							(start 0.2794 -0.1778)
							(mid 0.249642 -0.249642)
							(end 0.1778 -0.2794)
						)
					)
					(width 0)
					(fill yes)
				)
			)
		)
		(pad "2" smd custom
			(at 0 0.4445 135)
			(size 0.1397 0.1397)
			(layers "F.Cu" "F.Mask" "F.Paste")
			(net "SLOT2_P12V_SENSE_VN_R")
			(options
				(clearance outline)
				(anchor circle)
			)
			(primitives
				(gr_poly
					(pts
						(arc
							(start -0.1778 -0.2794)
							(mid -0.249642 -0.249642)
							(end -0.2794 -0.1778)
						)
						(arc
							(start -0.2794 0.1778)
							(mid -0.249642 0.249642)
							(end -0.1778 0.2794)
						)
						(arc
							(start 0.1778 0.2794)
							(mid 0.249642 0.249642)
							(end 0.2794 0.1778)
						)
						(arc
							(start 0.2794 -0.1778)
							(mid 0.249642 -0.249642)
							(end 0.1778 -0.2794)
						)
					)
					(width 0)
					(fill yes)
				)
			)
		)
	)
	(footprint ""
		(layer "F.Cu")
		(at 119.5832 -4.953 90)
		(property "Reference" "R139"
			(at 0 0 90)
			(layer "F.SilkS")
			(hide yes)
			(effects
				(font
					(size 1.27 1.27)
				)
			)
		)
		(property "Value" "10KR2F-2-GP"
			(at 0.064008 -3.993896 90)
			(unlocked yes)
			(layer "F.Fab")
			(hide yes)
			(effects
				(font
					(size 1.016 1.016)
					(thickness 0.1524)
				)
			)
		)
		(property "Device Type" "R402H16"
			(at 0.064008 -5.517896 90)
			(unlocked yes)
			(layer "F.Fab")
			(hide yes)
			(effects
				(font
					(size 1.016 1.016)
					(thickness 0.1524)
				)
			)
		)
		(duplicate_pad_numbers_are_jumpers no)
		(fp_line
			(start 0.508 -0.9398)
			(end -0.508 -0.9398)
			(stroke
				(width 0.1524)
				(type default)
			)
			(layer "F.SilkS")
		)
		(fp_line
			(start -0.508 -0.9398)
			(end -0.508 0.9398)
			(stroke
				(width 0.1524)
				(type default)
			)
			(layer "F.SilkS")
		)
		(fp_rect
			(start -0.508 0.9398)
			(end 0.508 -0.9398)
			(stroke
				(width 0)
				(type default)
			)
			(fill no)
			(layer "F.CrtYd")
		)
		(fp_rect
			(start -0.508 0.9398)
			(end 0.508 -0.9398)
			(stroke
				(width 0)
				(type default)
			)
			(fill no)
			(layer "F.Fab")
		)
		(pad "1" smd custom
			(at 0 -0.4445 90)
			(size 0.1397 0.1397)
			(layers "F.Cu" "F.Mask" "F.Paste")
			(net "P3V3_STBY")
			(options
				(clearance outline)
				(anchor circle)
			)
			(primitives
				(gr_poly
					(pts
						(arc
							(start -0.1778 -0.2794)
							(mid -0.249642 -0.249642)
							(end -0.2794 -0.1778)
						)
						(arc
							(start -0.2794 0.1778)
							(mid -0.249642 0.249642)
							(end -0.1778 0.2794)
						)
						(arc
							(start 0.1778 0.2794)
							(mid 0.249642 0.249642)
							(end 0.2794 0.1778)
						)
						(arc
							(start 0.2794 -0.1778)
							(mid 0.249642 -0.249642)
							(end 0.1778 -0.2794)
						)
					)
					(width 0)
					(fill yes)
				)
			)
		)
		(pad "2" smd custom
			(at 0 0.4445 90)
			(size 0.1397 0.1397)
			(layers "F.Cu" "F.Mask" "F.Paste")
			(net "GPIO_P_IO1_4")
			(options
				(clearance outline)
				(anchor circle)
			)
			(primitives
				(gr_poly
					(pts
						(arc
							(start -0.1778 -0.2794)
							(mid -0.249642 -0.249642)
							(end -0.2794 -0.1778)
						)
						(arc
							(start -0.2794 0.1778)
							(mid -0.249642 0.249642)
							(end -0.1778 0.2794)
						)
						(arc
							(start 0.1778 0.2794)
							(mid 0.249642 0.249642)
							(end 0.2794 0.1778)
						)
						(arc
							(start 0.2794 -0.1778)
							(mid 0.249642 -0.249642)
							(end 0.1778 -0.2794)
						)
					)
					(width 0)
					(fill yes)
				)
			)
		)
	)
	(footprint ""
		(layer "F.Cu")
		(at 15.1638 -32.0548 180)
		(property "Reference" "C30"
			(at 0 0 180)
			(layer "F.SilkS")
			(hide yes)
			(effects
				(font
					(size 1.27 1.27)
				)
			)
		)
		(property "Value" "SCD1U25V3KX-GP"
			(at 0 -2.8194 180)
			(unlocked yes)
			(layer "F.Fab")
			(hide yes)
			(effects
				(font
					(size 1.016 1.016)
					(thickness 0.1524)
				)
			)
		)
		(property "Device Type" "C603H36"
			(at 0 -4.3434 180)
			(unlocked yes)
			(layer "F.Fab")
			(hide yes)
			(effects
				(font
					(size 1.016 1.016)
					(thickness 0.1524)
				)
			)
		)
		(duplicate_pad_numbers_are_jumpers no)
		(fp_line
			(start 0.508 0)
			(end -0.508 0)
			(stroke
				(width 0.2032)
				(type default)
			)
			(layer "F.SilkS")
		)
		(fp_rect
			(start -0.5842 1.3335)
			(end 0.5842 -1.3335)
			(stroke
				(width 0)
				(type default)
			)
			(fill no)
			(layer "F.CrtYd")
		)
		(fp_rect
			(start -0.5842 1.3335)
			(end 0.5842 -1.3335)
			(stroke
				(width 0)
				(type default)
			)
			(fill no)
			(layer "F.Fab")
		)
		(pad "1" smd custom
			(at 0 -0.762 180)
			(size 0.2159 0.2159)
			(layers "F.Cu" "F.Mask" "F.Paste")
			(net "P12V_SLOT3")
			(options
				(clearance outline)
				(anchor circle)
			)
			(primitives
				(gr_poly
					(pts
						(arc
							(start -0.3302 -0.4318)
							(mid -0.402042 -0.402042)
							(end -0.4318 -0.3302)
						)
						(arc
							(start -0.4318 0.3302)
							(mid -0.402042 0.402042)
							(end -0.3302 0.4318)
						)
						(arc
							(start 0.3302 0.4318)
							(mid 0.402042 0.402042)
							(end 0.4318 0.3302)
						)
						(arc
							(start 0.4318 -0.3302)
							(mid 0.402042 -0.402042)
							(end 0.3302 -0.4318)
						)
					)
					(width 0)
					(fill yes)
				)
			)
		)
		(pad "2" smd custom
			(at 0 0.762 180)
			(size 0.2159 0.2159)
			(layers "F.Cu" "F.Mask" "F.Paste")
			(net "GND")
			(options
				(clearance outline)
				(anchor circle)
			)
			(primitives
				(gr_poly
					(pts
						(arc
							(start -0.3302 -0.4318)
							(mid -0.402042 -0.402042)
							(end -0.4318 -0.3302)
						)
						(arc
							(start -0.4318 0.3302)
							(mid -0.402042 0.402042)
							(end -0.3302 0.4318)
						)
						(arc
							(start 0.3302 0.4318)
							(mid 0.402042 0.402042)
							(end 0.4318 0.3302)
						)
						(arc
							(start 0.4318 -0.3302)
							(mid 0.402042 -0.402042)
							(end 0.3302 -0.4318)
						)
					)
					(width 0)
					(fill yes)
				)
			)
		)
	)
	(footprint ""
		(layer "F.Cu")
		(at 21.1836 -31.9532 180)
		(property "Reference" "C92"
			(at 0 0 180)
			(layer "F.SilkS")
			(hide yes)
			(effects
				(font
					(size 1.27 1.27)
				)
			)
		)
		(property "Value" "SC22U16V5MX-4-GP"
			(at -0.0762 -6.1214 180)
			(unlocked yes)
			(layer "F.Fab")
			(hide yes)
			(effects
				(font
					(size 1.016 1.016)
					(thickness 0.1524)
				)
			)
		)
		(property "Device Type" "C805H58"
			(at -0.0762 -8.1534 180)
			(unlocked yes)
			(layer "F.Fab")
			(hide yes)
			(effects
				(font
					(size 1.016 1.016)
					(thickness 0.1524)
				)
			)
		)
		(duplicate_pad_numbers_are_jumpers no)
		(fp_line
			(start 0.635 0)
			(end -0.635 0)
			(stroke
				(width 0.508)
				(type default)
			)
			(layer "F.SilkS")
		)
		(fp_rect
			(start -0.9652 1.778)
			(end 0.9652 -1.778)
			(stroke
				(width 0)
				(type default)
			)
			(fill no)
			(layer "F.CrtYd")
		)
		(fp_poly
			(pts
				(xy -0.9652 -1.778) (xy 0.9652 -1.778) (xy 0.9652 1.778) (xy -0.9652 1.778)
			)
			(stroke
				(width 0)
				(type default)
			)
			(fill no)
			(layer "F.Fab")
		)
		(pad "1" smd rect
			(at 0 -0.9652 180)
			(size 1.397 1.143)
			(layers "F.Cu" "F.Mask" "F.Paste")
			(net "P12V_SLOT3")
		)
		(pad "2" smd rect
			(at 0 0.9652 180)
			(size 1.397 1.143)
			(layers "F.Cu" "F.Mask" "F.Paste")
			(net "GND")
		)
	)
	(footprint ""
		(layer "F.Cu")
		(at 20.467066 -15.75054)
		(property "Reference" "R64"
			(at 0 0 0)
			(layer "F.SilkS")
			(hide yes)
			(effects
				(font
					(size 1.27 1.27)
				)
			)
		)
		(property "Value" "10KR2F-2-GP"
			(at 0.064008 -3.993896 0)
			(unlocked yes)
			(layer "F.Fab")
			(hide yes)
			(effects
				(font
					(size 1.016 1.016)
					(thickness 0.1524)
				)
			)
		)
		(property "Device Type" "R402H16"
			(at 0.064008 -5.517896 0)
			(unlocked yes)
			(layer "F.Fab")
			(hide yes)
			(effects
				(font
					(size 1.016 1.016)
					(thickness 0.1524)
				)
			)
		)
		(duplicate_pad_numbers_are_jumpers no)
		(fp_line
			(start -0.508 -0.9398)
			(end -0.508 0.9398)
			(stroke
				(width 0.1524)
				(type default)
			)
			(layer "F.SilkS")
		)
		(fp_line
			(start 0.508 -0.9398)
			(end -0.508 -0.9398)
			(stroke
				(width 0.1524)
				(type default)
			)
			(layer "F.SilkS")
		)
		(fp_rect
			(start -0.508 0.9398)
			(end 0.508 -0.9398)
			(stroke
				(width 0)
				(type default)
			)
			(fill no)
			(layer "F.CrtYd")
		)
		(fp_rect
			(start -0.508 0.9398)
			(end 0.508 -0.9398)
			(stroke
				(width 0)
				(type default)
			)
			(fill no)
			(layer "F.Fab")
		)
		(pad "1" smd custom
			(at 0 -0.4445)
			(size 0.1397 0.1397)
			(layers "F.Cu" "F.Mask" "F.Paste")
			(net "SLOT2_VMONITOR_A1")
			(options
				(clearance outline)
				(anchor circle)
			)
			(primitives
				(gr_poly
					(pts
						(arc
							(start -0.1778 -0.2794)
							(mid -0.249642 -0.249642)
							(end -0.2794 -0.1778)
						)
						(arc
							(start -0.2794 0.1778)
							(mid -0.249642 0.249642)
							(end -0.1778 0.2794)
						)
						(arc
							(start 0.1778 0.2794)
							(mid 0.249642 0.249642)
							(end 0.2794 0.1778)
						)
						(arc
							(start 0.2794 -0.1778)
							(mid 0.249642 -0.249642)
							(end 0.1778 -0.2794)
						)
					)
					(width 0)
					(fill yes)
				)
			)
		)
		(pad "2" smd custom
			(at 0 0.4445)
			(size 0.1397 0.1397)
			(layers "F.Cu" "F.Mask" "F.Paste")
			(net "GND")
			(options
				(clearance outline)
				(anchor circle)
			)
			(primitives
				(gr_poly
					(pts
						(arc
							(start -0.1778 -0.2794)
							(mid -0.249642 -0.249642)
							(end -0.2794 -0.1778)
						)
						(arc
							(start -0.2794 0.1778)
							(mid -0.249642 0.249642)
							(end -0.1778 0.2794)
						)
						(arc
							(start 0.1778 0.2794)
							(mid 0.249642 0.249642)
							(end 0.2794 0.1778)
						)
						(arc
							(start 0.2794 -0.1778)
							(mid 0.249642 -0.249642)
							(end 0.1778 -0.2794)
						)
					)
					(width 0)
					(fill yes)
				)
			)
		)
	)
	(footprint ""
		(layer "F.Cu")
		(at 131.699 -20.9296 90)
		(property "Reference" "R130"
			(at 0 0 90)
			(layer "F.SilkS")
			(hide yes)
			(effects
				(font
					(size 1.27 1.27)
				)
			)
		)
		(property "Value" "10KR2F-2-GP"
			(at 0.064008 -3.993896 90)
			(unlocked yes)
			(layer "F.Fab")
			(hide yes)
			(effects
				(font
					(size 1.016 1.016)
					(thickness 0.1524)
				)
			)
		)
		(property "Device Type" "R402H16"
			(at 0.064008 -5.517896 90)
			(unlocked yes)
			(layer "F.Fab")
			(hide yes)
			(effects
				(font
					(size 1.016 1.016)
					(thickness 0.1524)
				)
			)
		)
		(duplicate_pad_numbers_are_jumpers no)
		(fp_line
			(start 0.508 -0.9398)
			(end -0.508 -0.9398)
			(stroke
				(width 0.1524)
				(type default)
			)
			(layer "F.SilkS")
		)
		(fp_line
			(start -0.508 -0.9398)
			(end -0.508 0.9398)
			(stroke
				(width 0.1524)
				(type default)
			)
			(layer "F.SilkS")
		)
		(fp_rect
			(start -0.508 0.9398)
			(end 0.508 -0.9398)
			(stroke
				(width 0)
				(type default)
			)
			(fill no)
			(layer "F.CrtYd")
		)
		(fp_rect
			(start -0.508 0.9398)
			(end 0.508 -0.9398)
			(stroke
				(width 0)
				(type default)
			)
			(fill no)
			(layer "F.Fab")
		)
		(pad "1" smd custom
			(at 0 -0.4445 90)
			(size 0.1397 0.1397)
			(layers "F.Cu" "F.Mask" "F.Paste")
			(net "GPIO_B_EXP_A0")
			(options
				(clearance outline)
				(anchor circle)
			)
			(primitives
				(gr_poly
					(pts
						(arc
							(start -0.1778 -0.2794)
							(mid -0.249642 -0.249642)
							(end -0.2794 -0.1778)
						)
						(arc
							(start -0.2794 0.1778)
							(mid -0.249642 0.249642)
							(end -0.1778 0.2794)
						)
						(arc
							(start 0.1778 0.2794)
							(mid 0.249642 0.249642)
							(end 0.2794 0.1778)
						)
						(arc
							(start 0.2794 -0.1778)
							(mid 0.249642 -0.249642)
							(end 0.1778 -0.2794)
						)
					)
					(width 0)
					(fill yes)
				)
			)
		)
		(pad "2" smd custom
			(at 0 0.4445 90)
			(size 0.1397 0.1397)
			(layers "F.Cu" "F.Mask" "F.Paste")
			(net "GND")
			(options
				(clearance outline)
				(anchor circle)
			)
			(primitives
				(gr_poly
					(pts
						(arc
							(start -0.1778 -0.2794)
							(mid -0.249642 -0.249642)
							(end -0.2794 -0.1778)
						)
						(arc
							(start -0.2794 0.1778)
							(mid -0.249642 0.249642)
							(end -0.1778 0.2794)
						)
						(arc
							(start 0.1778 0.2794)
							(mid 0.249642 0.249642)
							(end 0.2794 0.1778)
						)
						(arc
							(start 0.2794 -0.1778)
							(mid 0.249642 -0.249642)
							(end 0.1778 -0.2794)
						)
					)
					(width 0)
					(fill yes)
				)
			)
		)
	)
	(footprint ""
		(layer "F.Cu")
		(at 32.131 3.2512 90)
		(property "Reference" "R203"
			(at 0 0 90)
			(layer "F.SilkS")
			(hide yes)
			(effects
				(font
					(size 1.27 1.27)
				)
			)
		)
		(property "Value" "0R6J-3-GP"
			(at -0.0508 -4.8514 90)
			(unlocked yes)
			(layer "F.Fab")
			(hide yes)
			(effects
				(font
					(size 1.016 1.016)
					(thickness 0.1524)
				)
			)
		)
		(property "Device Type" "R1206H28"
			(at 0 -6.3754 90)
			(unlocked yes)
			(layer "F.Fab")
			(hide yes)
			(effects
				(font
					(size 1.016 1.016)
					(thickness 0.1524)
				)
			)
		)
		(duplicate_pad_numbers_are_jumpers no)
		(fp_line
			(start 1.016 -2.2352)
			(end 1.016 2.2352)
			(stroke
				(width 0.1524)
				(type default)
			)
			(layer "F.SilkS")
		)
		(fp_line
			(start -1.016 -2.2352)
			(end 1.016 -2.2352)
			(stroke
				(width 0.1524)
				(type default)
			)
			(layer "F.SilkS")
		)
		(fp_line
			(start 1.016 2.2352)
			(end -1.016 2.2352)
			(stroke
				(width 0.1524)
				(type default)
			)
			(layer "F.SilkS")
		)
		(fp_line
			(start -1.016 2.2352)
			(end -1.016 -2.2352)
			(stroke
				(width 0.1524)
				(type default)
			)
			(layer "F.SilkS")
		)
		(fp_rect
			(start -1.0922 2.3114)
			(end 1.0922 -2.3114)
			(stroke
				(width 0)
				(type default)
			)
			(fill no)
			(layer "F.CrtYd")
		)
		(fp_poly
			(pts
				(xy -1.0922 -2.3114) (xy 1.0922 -2.3114) (xy 1.0922 2.3114) (xy -1.0922 2.3114)
			)
			(stroke
				(width 0)
				(type default)
			)
			(fill no)
			(layer "F.Fab")
		)
		(pad "1" smd rect
			(at 0 -1.397 90)
			(size 1.651 1.27)
			(layers "F.Cu" "F.Mask" "F.Paste")
			(net "P3V3_MB")
		)
		(pad "2" smd rect
			(at 0 1.397 90)
			(size 1.651 1.27)
			(layers "F.Cu" "F.Mask" "F.Paste")
			(net "P3V3")
		)
	)
	(footprint ""
		(layer "F.Cu")
		(at 131.6736 -19.8882 90)
		(property "Reference" "R133"
			(at 0 0 90)
			(layer "F.SilkS")
			(hide yes)
			(effects
				(font
					(size 1.27 1.27)
				)
			)
		)
		(property "Value" "10KR2F-2-GP"
			(at 0.064008 -3.993896 90)
			(unlocked yes)
			(layer "F.Fab")
			(hide yes)
			(effects
				(font
					(size 1.016 1.016)
					(thickness 0.1524)
				)
			)
		)
		(property "Device Type" "R402H16"
			(at 0.064008 -5.517896 90)
			(unlocked yes)
			(layer "F.Fab")
			(hide yes)
			(effects
				(font
					(size 1.016 1.016)
					(thickness 0.1524)
				)
			)
		)
		(duplicate_pad_numbers_are_jumpers no)
		(fp_line
			(start 0.508 -0.9398)
			(end -0.508 -0.9398)
			(stroke
				(width 0.1524)
				(type default)
			)
			(layer "F.SilkS")
		)
		(fp_line
			(start -0.508 -0.9398)
			(end -0.508 0.9398)
			(stroke
				(width 0.1524)
				(type default)
			)
			(layer "F.SilkS")
		)
		(fp_rect
			(start -0.508 0.9398)
			(end 0.508 -0.9398)
			(stroke
				(width 0)
				(type default)
			)
			(fill no)
			(layer "F.CrtYd")
		)
		(fp_rect
			(start -0.508 0.9398)
			(end 0.508 -0.9398)
			(stroke
				(width 0)
				(type default)
			)
			(fill no)
			(layer "F.Fab")
		)
		(pad "1" smd custom
			(at 0 -0.4445 90)
			(size 0.1397 0.1397)
			(layers "F.Cu" "F.Mask" "F.Paste")
			(net "GPIO_B_IO1_7")
			(options
				(clearance outline)
				(anchor circle)
			)
			(primitives
				(gr_poly
					(pts
						(arc
							(start -0.1778 -0.2794)
							(mid -0.249642 -0.249642)
							(end -0.2794 -0.1778)
						)
						(arc
							(start -0.2794 0.1778)
							(mid -0.249642 0.249642)
							(end -0.1778 0.2794)
						)
						(arc
							(start 0.1778 0.2794)
							(mid 0.249642 0.249642)
							(end 0.2794 0.1778)
						)
						(arc
							(start 0.2794 -0.1778)
							(mid 0.249642 -0.249642)
							(end 0.1778 -0.2794)
						)
					)
					(width 0)
					(fill yes)
				)
			)
		)
		(pad "2" smd custom
			(at 0 0.4445 90)
			(size 0.1397 0.1397)
			(layers "F.Cu" "F.Mask" "F.Paste")
			(net "GND")
			(options
				(clearance outline)
				(anchor circle)
			)
			(primitives
				(gr_poly
					(pts
						(arc
							(start -0.1778 -0.2794)
							(mid -0.249642 -0.249642)
							(end -0.2794 -0.1778)
						)
						(arc
							(start -0.2794 0.1778)
							(mid -0.249642 0.249642)
							(end -0.1778 0.2794)
						)
						(arc
							(start 0.1778 0.2794)
							(mid 0.249642 0.249642)
							(end 0.2794 0.1778)
						)
						(arc
							(start 0.2794 -0.1778)
							(mid 0.249642 -0.249642)
							(end 0.1778 -0.2794)
						)
					)
					(width 0)
					(fill yes)
				)
			)
		)
	)
	(footprint ""
		(layer "F.Cu")
		(at 25.273 -20.9296 90)
		(property "Reference" "R40"
			(at 0 0 90)
			(layer "F.SilkS")
			(hide yes)
			(effects
				(font
					(size 1.27 1.27)
				)
			)
		)
		(property "Value" "0R2F-1-GP"
			(at 0.064008 -3.993896 90)
			(unlocked yes)
			(layer "F.Fab")
			(hide yes)
			(effects
				(font
					(size 1.016 1.016)
					(thickness 0.1524)
				)
			)
		)
		(property "Device Type" "R402H16"
			(at 0.064008 -5.517896 90)
			(unlocked yes)
			(layer "F.Fab")
			(hide yes)
			(effects
				(font
					(size 1.016 1.016)
					(thickness 0.1524)
				)
			)
		)
		(duplicate_pad_numbers_are_jumpers no)
		(fp_line
			(start 0.508 -0.9398)
			(end -0.508 -0.9398)
			(stroke
				(width 0.1524)
				(type default)
			)
			(layer "F.SilkS")
		)
		(fp_line
			(start -0.508 -0.9398)
			(end -0.508 0.9398)
			(stroke
				(width 0.1524)
				(type default)
			)
			(layer "F.SilkS")
		)
		(fp_rect
			(start -0.508 0.9398)
			(end 0.508 -0.9398)
			(stroke
				(width 0)
				(type default)
			)
			(fill no)
			(layer "F.CrtYd")
		)
		(fp_rect
			(start -0.508 0.9398)
			(end 0.508 -0.9398)
			(stroke
				(width 0)
				(type default)
			)
			(fill no)
			(layer "F.Fab")
		)
		(pad "1" smd custom
			(at 0 -0.4445 90)
			(size 0.1397 0.1397)
			(layers "F.Cu" "F.Mask" "F.Paste")
			(net "SMB_VMONITOR_SLOT2_MUX_SCL")
			(options
				(clearance outline)
				(anchor circle)
			)
			(primitives
				(gr_poly
					(pts
						(arc
							(start -0.1778 -0.2794)
							(mid -0.249642 -0.249642)
							(end -0.2794 -0.1778)
						)
						(arc
							(start -0.2794 0.1778)
							(mid -0.249642 0.249642)
							(end -0.1778 0.2794)
						)
						(arc
							(start 0.1778 0.2794)
							(mid 0.249642 0.249642)
							(end 0.2794 0.1778)
						)
						(arc
							(start 0.2794 -0.1778)
							(mid 0.249642 -0.249642)
							(end 0.1778 -0.2794)
						)
					)
					(width 0)
					(fill yes)
				)
			)
		)
		(pad "2" smd custom
			(at 0 0.4445 90)
			(size 0.1397 0.1397)
			(layers "F.Cu" "F.Mask" "F.Paste")
			(net "SMCLK_BMC_DEVICE")
			(options
				(clearance outline)
				(anchor circle)
			)
			(primitives
				(gr_poly
					(pts
						(arc
							(start -0.1778 -0.2794)
							(mid -0.249642 -0.249642)
							(end -0.2794 -0.1778)
						)
						(arc
							(start -0.2794 0.1778)
							(mid -0.249642 0.249642)
							(end -0.1778 0.2794)
						)
						(arc
							(start 0.1778 0.2794)
							(mid 0.249642 0.249642)
							(end 0.2794 0.1778)
						)
						(arc
							(start 0.2794 -0.1778)
							(mid 0.249642 -0.249642)
							(end 0.1778 -0.2794)
						)
					)
					(width 0)
					(fill yes)
				)
			)
		)
	)
	(footprint ""
		(layer "F.Cu")
		(at 119.5832 -7.0358 -90)
		(property "Reference" "R137"
			(at 0 0 270)
			(layer "F.SilkS")
			(hide yes)
			(effects
				(font
					(size 1.27 1.27)
				)
			)
		)
		(property "Value" "10KR2F-2-GP"
			(at 0.064008 -3.993896 270)
			(unlocked yes)
			(layer "F.Fab")
			(hide yes)
			(effects
				(font
					(size 1.016 1.016)
					(thickness 0.1524)
				)
			)
		)
		(property "Device Type" "R402H16"
			(at 0.064008 -5.517896 270)
			(unlocked yes)
			(layer "F.Fab")
			(hide yes)
			(effects
				(font
					(size 1.016 1.016)
					(thickness 0.1524)
				)
			)
		)
		(duplicate_pad_numbers_are_jumpers no)
		(fp_line
			(start -0.508 -0.9398)
			(end -0.508 0.9398)
			(stroke
				(width 0.1524)
				(type default)
			)
			(layer "F.SilkS")
		)
		(fp_line
			(start 0.508 -0.9398)
			(end -0.508 -0.9398)
			(stroke
				(width 0.1524)
				(type default)
			)
			(layer "F.SilkS")
		)
		(fp_rect
			(start -0.508 0.9398)
			(end 0.508 -0.9398)
			(stroke
				(width 0)
				(type default)
			)
			(fill no)
			(layer "F.CrtYd")
		)
		(fp_rect
			(start -0.508 0.9398)
			(end 0.508 -0.9398)
			(stroke
				(width 0)
				(type default)
			)
			(fill no)
			(layer "F.Fab")
		)
		(pad "1" smd custom
			(at 0 -0.4445 270)
			(size 0.1397 0.1397)
			(layers "F.Cu" "F.Mask" "F.Paste")
			(net "GPIO_P_IO1_3")
			(options
				(clearance outline)
				(anchor circle)
			)
			(primitives
				(gr_poly
					(pts
						(arc
							(start -0.1778 -0.2794)
							(mid -0.249642 -0.249642)
							(end -0.2794 -0.1778)
						)
						(arc
							(start -0.2794 0.1778)
							(mid -0.249642 0.249642)
							(end -0.1778 0.2794)
						)
						(arc
							(start 0.1778 0.2794)
							(mid 0.249642 0.249642)
							(end 0.2794 0.1778)
						)
						(arc
							(start 0.2794 -0.1778)
							(mid 0.249642 -0.249642)
							(end 0.1778 -0.2794)
						)
					)
					(width 0)
					(fill yes)
				)
			)
		)
		(pad "2" smd custom
			(at 0 0.4445 270)
			(size 0.1397 0.1397)
			(layers "F.Cu" "F.Mask" "F.Paste")
			(net "GND")
			(options
				(clearance outline)
				(anchor circle)
			)
			(primitives
				(gr_poly
					(pts
						(arc
							(start -0.1778 -0.2794)
							(mid -0.249642 -0.249642)
							(end -0.2794 -0.1778)
						)
						(arc
							(start -0.2794 0.1778)
							(mid -0.249642 0.249642)
							(end -0.1778 0.2794)
						)
						(arc
							(start 0.1778 0.2794)
							(mid 0.249642 0.249642)
							(end 0.2794 0.1778)
						)
						(arc
							(start 0.2794 -0.1778)
							(mid 0.249642 -0.249642)
							(end 0.1778 -0.2794)
						)
					)
					(width 0)
					(fill yes)
				)
			)
		)
	)
	(footprint ""
		(layer "F.Cu")
		(at 109.1946 0.2794)
		(property "Reference" "R12"
			(at 0 0 0)
			(layer "F.SilkS")
			(hide yes)
			(effects
				(font
					(size 1.27 1.27)
				)
			)
		)
		(property "Value" "10KR2F-2-GP"
			(at 0.064008 -3.993896 0)
			(unlocked yes)
			(layer "F.Fab")
			(hide yes)
			(effects
				(font
					(size 1.016 1.016)
					(thickness 0.1524)
				)
			)
		)
		(property "Device Type" "R402H16"
			(at 0.064008 -5.517896 0)
			(unlocked yes)
			(layer "F.Fab")
			(hide yes)
			(effects
				(font
					(size 1.016 1.016)
					(thickness 0.1524)
				)
			)
		)
		(duplicate_pad_numbers_are_jumpers no)
		(fp_line
			(start -0.508 -0.9398)
			(end -0.508 0.9398)
			(stroke
				(width 0.1524)
				(type default)
			)
			(layer "F.SilkS")
		)
		(fp_line
			(start 0.508 -0.9398)
			(end -0.508 -0.9398)
			(stroke
				(width 0.1524)
				(type default)
			)
			(layer "F.SilkS")
		)
		(fp_rect
			(start -0.508 0.9398)
			(end 0.508 -0.9398)
			(stroke
				(width 0)
				(type default)
			)
			(fill no)
			(layer "F.CrtYd")
		)
		(fp_rect
			(start -0.508 0.9398)
			(end 0.508 -0.9398)
			(stroke
				(width 0)
				(type default)
			)
			(fill no)
			(layer "F.Fab")
		)
		(pad "1" smd custom
			(at 0 -0.4445)
			(size 0.1397 0.1397)
			(layers "F.Cu" "F.Mask" "F.Paste")
			(net "P3V3_STBY")
			(options
				(clearance outline)
				(anchor circle)
			)
			(primitives
				(gr_poly
					(pts
						(arc
							(start -0.1778 -0.2794)
							(mid -0.249642 -0.249642)
							(end -0.2794 -0.1778)
						)
						(arc
							(start -0.2794 0.1778)
							(mid -0.249642 0.249642)
							(end -0.1778 0.2794)
						)
						(arc
							(start 0.1778 0.2794)
							(mid 0.249642 0.249642)
							(end 0.2794 0.1778)
						)
						(arc
							(start 0.2794 -0.1778)
							(mid 0.249642 -0.249642)
							(end 0.1778 -0.2794)
						)
					)
					(width 0)
					(fill yes)
				)
			)
		)
		(pad "2" smd custom
			(at 0 0.4445)
			(size 0.1397 0.1397)
			(layers "F.Cu" "F.Mask" "F.Paste")
			(net "SMB_B_HUB_A0")
			(options
				(clearance outline)
				(anchor circle)
			)
			(primitives
				(gr_poly
					(pts
						(arc
							(start -0.1778 -0.2794)
							(mid -0.249642 -0.249642)
							(end -0.2794 -0.1778)
						)
						(arc
							(start -0.2794 0.1778)
							(mid -0.249642 0.249642)
							(end -0.1778 0.2794)
						)
						(arc
							(start 0.1778 0.2794)
							(mid 0.249642 0.249642)
							(end 0.2794 0.1778)
						)
						(arc
							(start 0.2794 -0.1778)
							(mid 0.249642 -0.249642)
							(end 0.1778 -0.2794)
						)
					)
					(width 0)
					(fill yes)
				)
			)
		)
	)
	(footprint ""
		(layer "F.Cu")
		(at 25.8064 -17.0434 90)
		(property "Reference" "R164"
			(at 0 0 90)
			(layer "F.SilkS")
			(hide yes)
			(effects
				(font
					(size 1.27 1.27)
				)
			)
		)
		(property "Value" "0R2F-1-GP"
			(at 0.064008 -3.993896 90)
			(unlocked yes)
			(layer "F.Fab")
			(hide yes)
			(effects
				(font
					(size 1.016 1.016)
					(thickness 0.1524)
				)
			)
		)
		(property "Device Type" "R402H16"
			(at 0.064008 -5.517896 90)
			(unlocked yes)
			(layer "F.Fab")
			(hide yes)
			(effects
				(font
					(size 1.016 1.016)
					(thickness 0.1524)
				)
			)
		)
		(duplicate_pad_numbers_are_jumpers no)
		(fp_line
			(start 0.508 -0.9398)
			(end -0.508 -0.9398)
			(stroke
				(width 0.1524)
				(type default)
			)
			(layer "F.SilkS")
		)
		(fp_line
			(start -0.508 -0.9398)
			(end -0.508 0.9398)
			(stroke
				(width 0.1524)
				(type default)
			)
			(layer "F.SilkS")
		)
		(fp_rect
			(start -0.508 0.9398)
			(end 0.508 -0.9398)
			(stroke
				(width 0)
				(type default)
			)
			(fill no)
			(layer "F.CrtYd")
		)
		(fp_rect
			(start -0.508 0.9398)
			(end 0.508 -0.9398)
			(stroke
				(width 0)
				(type default)
			)
			(fill no)
			(layer "F.Fab")
		)
		(pad "1" smd custom
			(at 0 -0.4445 90)
			(size 0.1397 0.1397)
			(layers "F.Cu" "F.Mask" "F.Paste")
			(net "SMB_VMONITOR_SLOT2_ALERT_N")
			(options
				(clearance outline)
				(anchor circle)
			)
			(primitives
				(gr_poly
					(pts
						(arc
							(start -0.1778 -0.2794)
							(mid -0.249642 -0.249642)
							(end -0.2794 -0.1778)
						)
						(arc
							(start -0.2794 0.1778)
							(mid -0.249642 0.249642)
							(end -0.1778 0.2794)
						)
						(arc
							(start 0.1778 0.2794)
							(mid 0.249642 0.249642)
							(end 0.2794 0.1778)
						)
						(arc
							(start 0.2794 -0.1778)
							(mid 0.249642 -0.249642)
							(end 0.1778 -0.2794)
						)
					)
					(width 0)
					(fill yes)
				)
			)
		)
		(pad "2" smd custom
			(at 0 0.4445 90)
			(size 0.1397 0.1397)
			(layers "F.Cu" "F.Mask" "F.Paste")
			(net "SMB_BMC_DEVICE_ALERT_N")
			(options
				(clearance outline)
				(anchor circle)
			)
			(primitives
				(gr_poly
					(pts
						(arc
							(start -0.1778 -0.2794)
							(mid -0.249642 -0.249642)
							(end -0.2794 -0.1778)
						)
						(arc
							(start -0.2794 0.1778)
							(mid -0.249642 0.249642)
							(end -0.1778 0.2794)
						)
						(arc
							(start 0.1778 0.2794)
							(mid 0.249642 0.249642)
							(end 0.2794 0.1778)
						)
						(arc
							(start 0.2794 -0.1778)
							(mid 0.249642 -0.249642)
							(end 0.1778 -0.2794)
						)
					)
					(width 0)
					(fill yes)
				)
			)
		)
	)
	(footprint ""
		(layer "F.Cu")
		(at 88.646 -18.3388 90)
		(property "Reference" "R76"
			(at 0 0 90)
			(layer "F.SilkS")
			(hide yes)
			(effects
				(font
					(size 1.27 1.27)
				)
			)
		)
		(property "Value" "0R2F-1-GP"
			(at 0.064008 -3.993896 90)
			(unlocked yes)
			(layer "F.Fab")
			(hide yes)
			(effects
				(font
					(size 1.016 1.016)
					(thickness 0.1524)
				)
			)
		)
		(property "Device Type" "R402H16"
			(at 0.064008 -5.517896 90)
			(unlocked yes)
			(layer "F.Fab")
			(hide yes)
			(effects
				(font
					(size 1.016 1.016)
					(thickness 0.1524)
				)
			)
		)
		(duplicate_pad_numbers_are_jumpers no)
		(fp_line
			(start 0.508 -0.9398)
			(end -0.508 -0.9398)
			(stroke
				(width 0.1524)
				(type default)
			)
			(layer "F.SilkS")
		)
		(fp_line
			(start -0.508 -0.9398)
			(end -0.508 0.9398)
			(stroke
				(width 0.1524)
				(type default)
			)
			(layer "F.SilkS")
		)
		(fp_rect
			(start -0.508 0.9398)
			(end 0.508 -0.9398)
			(stroke
				(width 0)
				(type default)
			)
			(fill no)
			(layer "F.CrtYd")
		)
		(fp_rect
			(start -0.508 0.9398)
			(end 0.508 -0.9398)
			(stroke
				(width 0)
				(type default)
			)
			(fill no)
			(layer "F.Fab")
		)
		(pad "1" smd custom
			(at 0 -0.4445 90)
			(size 0.1397 0.1397)
			(layers "F.Cu" "F.Mask" "F.Paste")
			(net "RESET_O_1")
			(options
				(clearance outline)
				(anchor circle)
			)
			(primitives
				(gr_poly
					(pts
						(arc
							(start -0.1778 -0.2794)
							(mid -0.249642 -0.249642)
							(end -0.2794 -0.1778)
						)
						(arc
							(start -0.2794 0.1778)
							(mid -0.249642 0.249642)
							(end -0.1778 0.2794)
						)
						(arc
							(start 0.1778 0.2794)
							(mid 0.249642 0.249642)
							(end 0.2794 0.1778)
						)
						(arc
							(start 0.2794 -0.1778)
							(mid 0.249642 -0.249642)
							(end 0.1778 -0.2794)
						)
					)
					(width 0)
					(fill yes)
				)
			)
		)
		(pad "2" smd custom
			(at 0 0.4445 90)
			(size 0.1397 0.1397)
			(layers "F.Cu" "F.Mask" "F.Paste")
			(net "PERST_N_1_R")
			(options
				(clearance outline)
				(anchor circle)
			)
			(primitives
				(gr_poly
					(pts
						(arc
							(start -0.1778 -0.2794)
							(mid -0.249642 -0.249642)
							(end -0.2794 -0.1778)
						)
						(arc
							(start -0.2794 0.1778)
							(mid -0.249642 0.249642)
							(end -0.1778 0.2794)
						)
						(arc
							(start 0.1778 0.2794)
							(mid 0.249642 0.249642)
							(end 0.2794 0.1778)
						)
						(arc
							(start 0.2794 -0.1778)
							(mid 0.249642 -0.249642)
							(end 0.1778 -0.2794)
						)
					)
					(width 0)
					(fill yes)
				)
			)
		)
	)
	(footprint ""
		(layer "F.Cu")
		(at 131.699 -15.6972 90)
		(property "Reference" "R127"
			(at 0 0 90)
			(layer "F.SilkS")
			(hide yes)
			(effects
				(font
					(size 1.27 1.27)
				)
			)
		)
		(property "Value" "10KR2F-2-GP"
			(at 0.064008 -3.993896 90)
			(unlocked yes)
			(layer "F.Fab")
			(hide yes)
			(effects
				(font
					(size 1.016 1.016)
					(thickness 0.1524)
				)
			)
		)
		(property "Device Type" "R402H16"
			(at 0.064008 -5.517896 90)
			(unlocked yes)
			(layer "F.Fab")
			(hide yes)
			(effects
				(font
					(size 1.016 1.016)
					(thickness 0.1524)
				)
			)
		)
		(duplicate_pad_numbers_are_jumpers no)
		(fp_line
			(start 0.508 -0.9398)
			(end -0.508 -0.9398)
			(stroke
				(width 0.1524)
				(type default)
			)
			(layer "F.SilkS")
		)
		(fp_line
			(start -0.508 -0.9398)
			(end -0.508 0.9398)
			(stroke
				(width 0.1524)
				(type default)
			)
			(layer "F.SilkS")
		)
		(fp_rect
			(start -0.508 0.9398)
			(end 0.508 -0.9398)
			(stroke
				(width 0)
				(type default)
			)
			(fill no)
			(layer "F.CrtYd")
		)
		(fp_rect
			(start -0.508 0.9398)
			(end 0.508 -0.9398)
			(stroke
				(width 0)
				(type default)
			)
			(fill no)
			(layer "F.Fab")
		)
		(pad "1" smd custom
			(at 0 -0.4445 90)
			(size 0.1397 0.1397)
			(layers "F.Cu" "F.Mask" "F.Paste")
			(net "GPIO_B_IO1_5")
			(options
				(clearance outline)
				(anchor circle)
			)
			(primitives
				(gr_poly
					(pts
						(arc
							(start -0.1778 -0.2794)
							(mid -0.249642 -0.249642)
							(end -0.2794 -0.1778)
						)
						(arc
							(start -0.2794 0.1778)
							(mid -0.249642 0.249642)
							(end -0.1778 0.2794)
						)
						(arc
							(start 0.1778 0.2794)
							(mid 0.249642 0.249642)
							(end 0.2794 0.1778)
						)
						(arc
							(start 0.2794 -0.1778)
							(mid 0.249642 -0.249642)
							(end 0.1778 -0.2794)
						)
					)
					(width 0)
					(fill yes)
				)
			)
		)
		(pad "2" smd custom
			(at 0 0.4445 90)
			(size 0.1397 0.1397)
			(layers "F.Cu" "F.Mask" "F.Paste")
			(net "GND")
			(options
				(clearance outline)
				(anchor circle)
			)
			(primitives
				(gr_poly
					(pts
						(arc
							(start -0.1778 -0.2794)
							(mid -0.249642 -0.249642)
							(end -0.2794 -0.1778)
						)
						(arc
							(start -0.2794 0.1778)
							(mid -0.249642 0.249642)
							(end -0.1778 0.2794)
						)
						(arc
							(start 0.1778 0.2794)
							(mid 0.249642 0.249642)
							(end 0.2794 0.1778)
						)
						(arc
							(start 0.2794 -0.1778)
							(mid 0.249642 -0.249642)
							(end 0.1778 -0.2794)
						)
					)
					(width 0)
					(fill yes)
				)
			)
		)
	)
	(footprint ""
		(layer "F.Cu")
		(at 131.699 -14.6558 -90)
		(property "Reference" "R126"
			(at 0 0 270)
			(layer "F.SilkS")
			(hide yes)
			(effects
				(font
					(size 1.27 1.27)
				)
			)
		)
		(property "Value" "10KR2F-2-GP"
			(at 0.064008 -3.993896 270)
			(unlocked yes)
			(layer "F.Fab")
			(hide yes)
			(effects
				(font
					(size 1.016 1.016)
					(thickness 0.1524)
				)
			)
		)
		(property "Device Type" "R402H16"
			(at 0.064008 -5.517896 270)
			(unlocked yes)
			(layer "F.Fab")
			(hide yes)
			(effects
				(font
					(size 1.016 1.016)
					(thickness 0.1524)
				)
			)
		)
		(duplicate_pad_numbers_are_jumpers no)
		(fp_line
			(start -0.508 -0.9398)
			(end -0.508 0.9398)
			(stroke
				(width 0.1524)
				(type default)
			)
			(layer "F.SilkS")
		)
		(fp_line
			(start 0.508 -0.9398)
			(end -0.508 -0.9398)
			(stroke
				(width 0.1524)
				(type default)
			)
			(layer "F.SilkS")
		)
		(fp_rect
			(start -0.508 0.9398)
			(end 0.508 -0.9398)
			(stroke
				(width 0)
				(type default)
			)
			(fill no)
			(layer "F.CrtYd")
		)
		(fp_rect
			(start -0.508 0.9398)
			(end 0.508 -0.9398)
			(stroke
				(width 0)
				(type default)
			)
			(fill no)
			(layer "F.Fab")
		)
		(pad "1" smd custom
			(at 0 -0.4445 270)
			(size 0.1397 0.1397)
			(layers "F.Cu" "F.Mask" "F.Paste")
			(net "P3V3_STBY")
			(options
				(clearance outline)
				(anchor circle)
			)
			(primitives
				(gr_poly
					(pts
						(arc
							(start -0.1778 -0.2794)
							(mid -0.249642 -0.249642)
							(end -0.2794 -0.1778)
						)
						(arc
							(start -0.2794 0.1778)
							(mid -0.249642 0.249642)
							(end -0.1778 0.2794)
						)
						(arc
							(start 0.1778 0.2794)
							(mid 0.249642 0.249642)
							(end 0.2794 0.1778)
						)
						(arc
							(start 0.2794 -0.1778)
							(mid 0.249642 -0.249642)
							(end 0.1778 -0.2794)
						)
					)
					(width 0)
					(fill yes)
				)
			)
		)
		(pad "2" smd custom
			(at 0 0.4445 270)
			(size 0.1397 0.1397)
			(layers "F.Cu" "F.Mask" "F.Paste")
			(net "GPIO_B_IO1_5")
			(options
				(clearance outline)
				(anchor circle)
			)
			(primitives
				(gr_poly
					(pts
						(arc
							(start -0.1778 -0.2794)
							(mid -0.249642 -0.249642)
							(end -0.2794 -0.1778)
						)
						(arc
							(start -0.2794 0.1778)
							(mid -0.249642 0.249642)
							(end -0.1778 0.2794)
						)
						(arc
							(start 0.1778 0.2794)
							(mid 0.249642 0.249642)
							(end 0.2794 0.1778)
						)
						(arc
							(start 0.2794 -0.1778)
							(mid 0.249642 -0.249642)
							(end 0.1778 -0.2794)
						)
					)
					(width 0)
					(fill yes)
				)
			)
		)
	)
	(footprint ""
		(layer "F.Cu")
		(at 113.9444 -24.0792)
		(property "Reference" "TP17"
			(at 0 0 0)
			(layer "F.SilkS")
			(hide yes)
			(effects
				(font
					(size 1.27 1.27)
				)
			)
		)
		(property "Value" "TPAD24"
			(at 0 -1.6129 0)
			(unlocked yes)
			(layer "F.Fab")
			(hide yes)
			(effects
				(font
					(size 1.016 1.016)
					(thickness 0.1524)
				)
			)
		)
		(property "Device Type" "TPAD24"
			(at 0 -3.1369 0)
			(unlocked yes)
			(layer "F.Fab")
			(hide yes)
			(effects
				(font
					(size 1.016 1.016)
					(thickness 0.1524)
				)
			)
		)
		(duplicate_pad_numbers_are_jumpers no)
		(fp_poly
			(pts
				(arc
					(start 0.3048 0)
					(mid -0.3048 0)
					(end 0.3048 0)
				)
			)
			(stroke
				(width 0)
				(type default)
			)
			(fill no)
			(layer "F.CrtYd")
		)
		(fp_poly
			(pts
				(arc
					(start 0.6096 0)
					(mid -0.6096 0)
					(end 0.6096 0)
				)
			)
			(stroke
				(width 0)
				(type default)
			)
			(fill no)
			(layer "F.Fab")
		)
		(pad "1" smd circle
			(at 0 0)
			(size 0.6096 0.6096)
			(layers "F.Cu" "F.Mask" "F.Paste")
			(net "TP_RSVD_SLOT3_PIN82")
		)
	)
	(footprint ""
		(layer "F.Cu")
		(at 119.6086 -10.2108 90)
		(property "Reference" "R134"
			(at 0 0 90)
			(layer "F.SilkS")
			(hide yes)
			(effects
				(font
					(size 1.27 1.27)
				)
			)
		)
		(property "Value" "10KR2F-2-GP"
			(at 0.064008 -3.993896 90)
			(unlocked yes)
			(layer "F.Fab")
			(hide yes)
			(effects
				(font
					(size 1.016 1.016)
					(thickness 0.1524)
				)
			)
		)
		(property "Device Type" "R402H16"
			(at 0.064008 -5.517896 90)
			(unlocked yes)
			(layer "F.Fab")
			(hide yes)
			(effects
				(font
					(size 1.016 1.016)
					(thickness 0.1524)
				)
			)
		)
		(duplicate_pad_numbers_are_jumpers no)
		(fp_line
			(start 0.508 -0.9398)
			(end -0.508 -0.9398)
			(stroke
				(width 0.1524)
				(type default)
			)
			(layer "F.SilkS")
		)
		(fp_line
			(start -0.508 -0.9398)
			(end -0.508 0.9398)
			(stroke
				(width 0.1524)
				(type default)
			)
			(layer "F.SilkS")
		)
		(fp_rect
			(start -0.508 0.9398)
			(end 0.508 -0.9398)
			(stroke
				(width 0)
				(type default)
			)
			(fill no)
			(layer "F.CrtYd")
		)
		(fp_rect
			(start -0.508 0.9398)
			(end 0.508 -0.9398)
			(stroke
				(width 0)
				(type default)
			)
			(fill no)
			(layer "F.Fab")
		)
		(pad "1" smd custom
			(at 0 -0.4445 90)
			(size 0.1397 0.1397)
			(layers "F.Cu" "F.Mask" "F.Paste")
			(net "P3V3_STBY")
			(options
				(clearance outline)
				(anchor circle)
			)
			(primitives
				(gr_poly
					(pts
						(arc
							(start -0.1778 -0.2794)
							(mid -0.249642 -0.249642)
							(end -0.2794 -0.1778)
						)
						(arc
							(start -0.2794 0.1778)
							(mid -0.249642 0.249642)
							(end -0.1778 0.2794)
						)
						(arc
							(start 0.1778 0.2794)
							(mid 0.249642 0.249642)
							(end 0.2794 0.1778)
						)
						(arc
							(start 0.2794 -0.1778)
							(mid 0.249642 -0.249642)
							(end 0.1778 -0.2794)
						)
					)
					(width 0)
					(fill yes)
				)
			)
		)
		(pad "2" smd custom
			(at 0 0.4445 90)
			(size 0.1397 0.1397)
			(layers "F.Cu" "F.Mask" "F.Paste")
			(net "GPIO_P_IO1_0")
			(options
				(clearance outline)
				(anchor circle)
			)
			(primitives
				(gr_poly
					(pts
						(arc
							(start -0.1778 -0.2794)
							(mid -0.249642 -0.249642)
							(end -0.2794 -0.1778)
						)
						(arc
							(start -0.2794 0.1778)
							(mid -0.249642 0.249642)
							(end -0.1778 0.2794)
						)
						(arc
							(start 0.1778 0.2794)
							(mid 0.249642 0.249642)
							(end 0.2794 0.1778)
						)
						(arc
							(start 0.2794 -0.1778)
							(mid 0.249642 -0.249642)
							(end 0.1778 -0.2794)
						)
					)
					(width 0)
					(fill yes)
				)
			)
		)
	)
	(footprint ""
		(layer "F.Cu")
		(at 38.6969 0.8382 90)
		(property "Reference" "C19"
			(at 0 0 90)
			(layer "F.SilkS")
			(hide yes)
			(effects
				(font
					(size 1.27 1.27)
				)
			)
		)
		(property "Value" "SCD1U16V2KX-3GP"
			(at 1.1811 -2.7051 90)
			(unlocked yes)
			(layer "F.Fab")
			(hide yes)
			(effects
				(font
					(size 1.016 1.016)
					(thickness 0.1524)
				)
			)
		)
		(property "Device Type" "C402H22"
			(at 1.1811 -4.2291 90)
			(unlocked yes)
			(layer "F.Fab")
			(hide yes)
			(effects
				(font
					(size 1.016 1.016)
					(thickness 0.1524)
				)
			)
		)
		(duplicate_pad_numbers_are_jumpers no)
		(fp_rect
			(start -0.4318 0.9525)
			(end 0.4318 -0.9525)
			(stroke
				(width 0)
				(type default)
			)
			(fill no)
			(layer "F.CrtYd")
		)
		(fp_rect
			(start -0.4318 0.9525)
			(end 0.4318 -0.9525)
			(stroke
				(width 0)
				(type default)
			)
			(fill no)
			(layer "F.Fab")
		)
		(pad "1" smd custom
			(at 0 -0.4445 90)
			(size 0.1524 0.1524)
			(layers "F.Cu" "F.Mask" "F.Paste")
			(net "P3V3")
			(options
				(clearance outline)
				(anchor circle)
			)
			(primitives
				(gr_poly
					(pts
						(arc
							(start 0.3048 -0.2032)
							(mid 0.275042 -0.275042)
							(end 0.2032 -0.3048)
						)
						(arc
							(start -0.2032 -0.3048)
							(mid -0.275042 -0.275042)
							(end -0.3048 -0.2032)
						)
						(arc
							(start -0.3048 0.2032)
							(mid -0.275042 0.275042)
							(end -0.2032 0.3048)
						)
						(arc
							(start 0.2032 0.3048)
							(mid 0.275042 0.275042)
							(end 0.3048 0.2032)
						)
					)
					(width 0)
					(fill yes)
				)
			)
		)
		(pad "2" smd custom
			(at 0 0.4445 90)
			(size 0.1524 0.1524)
			(layers "F.Cu" "F.Mask" "F.Paste")
			(net "GND")
			(options
				(clearance outline)
				(anchor circle)
			)
			(primitives
				(gr_poly
					(pts
						(arc
							(start 0.3048 -0.2032)
							(mid 0.275042 -0.275042)
							(end 0.2032 -0.3048)
						)
						(arc
							(start -0.2032 -0.3048)
							(mid -0.275042 -0.275042)
							(end -0.3048 -0.2032)
						)
						(arc
							(start -0.3048 0.2032)
							(mid -0.275042 0.275042)
							(end -0.2032 0.3048)
						)
						(arc
							(start 0.2032 0.3048)
							(mid 0.275042 0.275042)
							(end 0.3048 0.2032)
						)
					)
					(width 0)
					(fill yes)
				)
			)
		)
	)
	(footprint ""
		(layer "F.Cu")
		(at 119.5832 -9.144 -90)
		(property "Reference" "R135"
			(at 0 0 270)
			(layer "F.SilkS")
			(hide yes)
			(effects
				(font
					(size 1.27 1.27)
				)
			)
		)
		(property "Value" "10KR2F-2-GP"
			(at 0.064008 -3.993896 270)
			(unlocked yes)
			(layer "F.Fab")
			(hide yes)
			(effects
				(font
					(size 1.016 1.016)
					(thickness 0.1524)
				)
			)
		)
		(property "Device Type" "R402H16"
			(at 0.064008 -5.517896 270)
			(unlocked yes)
			(layer "F.Fab")
			(hide yes)
			(effects
				(font
					(size 1.016 1.016)
					(thickness 0.1524)
				)
			)
		)
		(duplicate_pad_numbers_are_jumpers no)
		(fp_line
			(start -0.508 -0.9398)
			(end -0.508 0.9398)
			(stroke
				(width 0.1524)
				(type default)
			)
			(layer "F.SilkS")
		)
		(fp_line
			(start 0.508 -0.9398)
			(end -0.508 -0.9398)
			(stroke
				(width 0.1524)
				(type default)
			)
			(layer "F.SilkS")
		)
		(fp_rect
			(start -0.508 0.9398)
			(end 0.508 -0.9398)
			(stroke
				(width 0)
				(type default)
			)
			(fill no)
			(layer "F.CrtYd")
		)
		(fp_rect
			(start -0.508 0.9398)
			(end 0.508 -0.9398)
			(stroke
				(width 0)
				(type default)
			)
			(fill no)
			(layer "F.Fab")
		)
		(pad "1" smd custom
			(at 0 -0.4445 270)
			(size 0.1397 0.1397)
			(layers "F.Cu" "F.Mask" "F.Paste")
			(net "GPIO_P_IO1_0")
			(options
				(clearance outline)
				(anchor circle)
			)
			(primitives
				(gr_poly
					(pts
						(arc
							(start -0.1778 -0.2794)
							(mid -0.249642 -0.249642)
							(end -0.2794 -0.1778)
						)
						(arc
							(start -0.2794 0.1778)
							(mid -0.249642 0.249642)
							(end -0.1778 0.2794)
						)
						(arc
							(start 0.1778 0.2794)
							(mid 0.249642 0.249642)
							(end 0.2794 0.1778)
						)
						(arc
							(start 0.2794 -0.1778)
							(mid 0.249642 -0.249642)
							(end 0.1778 -0.2794)
						)
					)
					(width 0)
					(fill yes)
				)
			)
		)
		(pad "2" smd custom
			(at 0 0.4445 270)
			(size 0.1397 0.1397)
			(layers "F.Cu" "F.Mask" "F.Paste")
			(net "GND")
			(options
				(clearance outline)
				(anchor circle)
			)
			(primitives
				(gr_poly
					(pts
						(arc
							(start -0.1778 -0.2794)
							(mid -0.249642 -0.249642)
							(end -0.2794 -0.1778)
						)
						(arc
							(start -0.2794 0.1778)
							(mid -0.249642 0.249642)
							(end -0.1778 0.2794)
						)
						(arc
							(start 0.1778 0.2794)
							(mid 0.249642 0.249642)
							(end 0.2794 0.1778)
						)
						(arc
							(start 0.2794 -0.1778)
							(mid 0.249642 -0.249642)
							(end 0.1778 -0.2794)
						)
					)
					(width 0)
					(fill yes)
				)
			)
		)
	)
	(footprint ""
		(layer "F.Cu")
		(at 42.3799 13.530072)
		(property "Reference" "GF2"
			(at 0 0 0)
			(layer "F.SilkS")
			(hide yes)
			(effects
				(font
					(size 1.27 1.27)
				)
			)
		)
		(property "Value" "GF-200P-11-GP"
			(at 58.674 -9.3472 0)
			(unlocked yes)
			(layer "F.Fab")
			(hide yes)
			(effects
				(font
					(size 1.016 1.016)
					(thickness 0.1524)
				)
			)
		)
		(property "Device Type" "GF-200P-11"
			(at 58.674 -10.8712 0)
			(unlocked yes)
			(layer "F.Fab")
			(hide yes)
			(effects
				(font
					(size 1.016 1.016)
					(thickness 0.1524)
				)
			)
		)
		(duplicate_pad_numbers_are_jumpers no)
		(fp_rect
			(start -29.1084 2.032)
			(end 57.912 -4.826)
			(stroke
				(width 0)
				(type default)
			)
			(fill no)
			(layer "B.CrtYd")
		)
		(fp_rect
			(start -29.1084 2.032)
			(end 57.912 -4.826)
			(stroke
				(width 0)
				(type default)
			)
			(fill no)
			(layer "F.CrtYd")
		)
		(fp_rect
			(start -29.1084 2.032)
			(end 57.912 -4.826)
			(stroke
				(width 0)
				(type default)
			)
			(fill no)
			(layer "B.Fab")
		)
		(fp_rect
			(start -29.1084 2.032)
			(end 57.912 -4.826)
			(stroke
				(width 0)
				(type default)
			)
			(fill no)
			(layer "F.Fab")
		)
		(fp_text user "02 Do not mirror"
			(at -9.144 3.0988 0)
			(unlocked yes)
			(layer "F.Fab")
			(effects
				(font
					(size 1.016 1.016)
					(thickness 0.1524)
				)
				(justify left)
			)
		)
		(pad "1" smd rect
			(at -26.800048 -1.397)
			(size 0.5588 2.794)
			(layers "F.Cu" "F.Mask" "F.Paste")
			(net "P12V")
		)
		(pad "2" smd rect
			(at -26.800048 -1.016)
			(size 0.5588 2.794)
			(drill
				(offset 0 -0.381)
			)
			(layers "F.Cu" "F.Mask" "F.Paste")
			(net "P12V")
		)
		(pad "3" smd rect
			(at -25.999948 -1.397)
			(size 0.5588 2.794)
			(layers "F.Cu" "F.Mask" "F.Paste")
			(net "P12V")
		)
		(pad "4" smd rect
			(at -25.999948 -1.016)
			(size 0.5588 2.794)
			(drill
				(offset 0 -0.381)
			)
			(layers "F.Cu" "F.Mask" "F.Paste")
			(net "P12V")
		)
		(pad "5" smd rect
			(at -25.200102 -1.397)
			(size 0.5588 2.794)
			(layers "F.Cu" "F.Mask" "F.Paste")
			(net "P12V")
		)
		(pad "6" smd rect
			(at -25.200102 -1.016)
			(size 0.5588 2.794)
			(drill
				(offset 0 -0.381)
			)
			(layers "F.Cu" "F.Mask" "F.Paste")
			(net "P12V")
		)
		(pad "7" smd rect
			(at -24.400002 -1.397)
			(size 0.5588 2.794)
			(layers "F.Cu" "F.Mask" "F.Paste")
			(net "P12V")
		)
		(pad "8" smd rect
			(at -24.400002 -1.016)
			(size 0.5588 2.794)
			(drill
				(offset 0 -0.381)
			)
			(layers "F.Cu" "F.Mask" "F.Paste")
			(net "P12V")
		)
		(pad "9" smd rect
			(at -23.599902 -1.397)
			(size 0.5588 2.794)
			(layers "F.Cu" "F.Mask" "F.Paste")
			(net "P12V")
		)
		(pad "10" smd rect
			(at -23.599902 -1.016)
			(size 0.5588 2.794)
			(drill
				(offset 0 -0.381)
			)
			(layers "F.Cu" "F.Mask" "F.Paste")
			(net "P12V")
		)
		(pad "11" smd rect
			(at -22.800056 -1.397)
			(size 0.5588 2.794)
			(layers "F.Cu" "F.Mask" "F.Paste")
			(net "P12V")
		)
		(pad "12" smd rect
			(at -22.800056 -1.016)
			(size 0.5588 2.794)
			(drill
				(offset 0 -0.381)
			)
			(layers "F.Cu" "F.Mask" "F.Paste")
			(net "P12V")
		)
		(pad "13" smd rect
			(at -21.999956 -1.397)
			(size 0.5588 2.794)
			(layers "F.Cu" "F.Mask" "F.Paste")
			(net "GND")
		)
		(pad "14" smd rect
			(at -21.999956 -1.016)
			(size 0.5588 2.794)
			(drill
				(offset 0 -0.381)
			)
			(layers "F.Cu" "F.Mask" "F.Paste")
			(net "GND")
		)
		(pad "15" smd rect
			(at -21.20011 -1.397)
			(size 0.5588 2.794)
			(layers "F.Cu" "F.Mask" "F.Paste")
			(net "SMB_SLOTX24_STBY_LVC3_SDA_R2")
		)
		(pad "16" smd rect
			(at -21.20011 -1.016)
			(size 0.5588 2.794)
			(drill
				(offset 0 -0.381)
			)
			(layers "F.Cu" "F.Mask" "F.Paste")
			(net "IRQ_OOB_MGMT_RISER_ALERT_N")
		)
		(pad "17" smd rect
			(at -20.40001 -1.397)
			(size 0.5588 2.794)
			(layers "F.Cu" "F.Mask" "F.Paste")
			(net "SMB_SLOTX24_STBY_LVC3_SCL_R2")
		)
		(pad "18" smd rect
			(at -20.40001 -1.016)
			(size 0.5588 2.794)
			(drill
				(offset 0 -0.381)
			)
			(layers "F.Cu" "F.Mask" "F.Paste")
			(net "FM_SLT_CFG1")
		)
		(pad "19" smd rect
			(at -19.59991 -1.397)
			(size 0.5588 2.794)
			(layers "F.Cu" "F.Mask" "F.Paste")
			(net "FM_SLT_CFG0")
		)
		(pad "20" smd rect
			(at -19.59991 -1.016)
			(size 0.5588 2.794)
			(drill
				(offset 0 -0.381)
			)
			(layers "F.Cu" "F.Mask" "F.Paste")
			(net "FM_PWRBRK_SLOT_N")
		)
		(pad "21" smd rect
			(at -18.800064 -1.397)
			(size 0.5588 2.794)
			(layers "F.Cu" "F.Mask" "F.Paste")
			(net "P3V3_MB")
		)
		(pad "22" smd rect
			(at -18.800064 -1.016)
			(size 0.5588 2.794)
			(drill
				(offset 0 -0.381)
			)
			(layers "F.Cu" "F.Mask" "F.Paste")
			(net "P3V3_MB")
		)
		(pad "23" smd rect
			(at -17.999964 -1.397)
			(size 0.5588 2.794)
			(layers "F.Cu" "F.Mask" "F.Paste")
			(net "P3V3_MB")
		)
		(pad "24" smd rect
			(at -17.999964 -1.016)
			(size 0.5588 2.794)
			(drill
				(offset 0 -0.381)
			)
			(layers "F.Cu" "F.Mask" "F.Paste")
			(net "P3V3_MB")
		)
		(pad "25" smd rect
			(at -17.200118 -1.397)
			(size 0.5588 2.794)
			(layers "F.Cu" "F.Mask" "F.Paste")
			(net "P3V3_STBY")
		)
		(pad "26" smd rect
			(at -17.200118 -1.016)
			(size 0.5588 2.794)
			(drill
				(offset 0 -0.381)
			)
			(layers "F.Cu" "F.Mask" "F.Paste")
			(net "GND")
		)
		(pad "27" smd rect
			(at -16.400018 -1.397)
			(size 0.5588 2.794)
			(layers "F.Cu" "F.Mask" "F.Paste")
			(net "SMB_PCH_ALERT_R_N")
		)
		(pad "28" smd rect
			(at -16.400018 -1.016)
			(size 0.5588 2.794)
			(drill
				(offset 0 -0.381)
			)
			(layers "F.Cu" "F.Mask" "F.Paste")
			(net "FM_PE_SLOTX24_WAKE_N")
		)
		(pad "29" smd rect
			(at -15.599918 -1.397)
			(size 0.5588 2.794)
			(layers "F.Cu" "F.Mask" "F.Paste")
			(net "PERST_N")
		)
		(pad "30" smd rect
			(at -15.599918 -1.016)
			(size 0.5588 2.794)
			(drill
				(offset 0 -0.381)
			)
			(layers "F.Cu" "F.Mask" "F.Paste")
			(net "SMB_HOST_STBY_LVC3_SDA_R5")
		)
		(pad "31" smd rect
			(at -14.800072 -1.397)
			(size 0.5588 2.794)
			(layers "F.Cu" "F.Mask" "F.Paste")
			(net "GND")
		)
		(pad "32" smd rect
			(at -14.800072 -1.016)
			(size 0.5588 2.794)
			(drill
				(offset 0 -0.381)
			)
			(layers "F.Cu" "F.Mask" "F.Paste")
			(net "SMB_HOST_STBY_LVC3_SCL_R5")
		)
		(pad "33" smd rect
			(at -13.999972 -1.397)
			(size 0.5588 2.794)
			(layers "F.Cu" "F.Mask" "F.Paste")
			(net "CLK_100M_PCH_SLOTX24_S5_DP")
		)
		(pad "34" smd rect
			(at -13.999972 -1.016)
			(size 0.5588 2.794)
			(drill
				(offset 0 -0.381)
			)
			(layers "F.Cu" "F.Mask" "F.Paste")
			(net "GND")
		)
		(pad "35" smd rect
			(at -13.200126 -1.397)
			(size 0.5588 2.794)
			(layers "F.Cu" "F.Mask" "F.Paste")
			(net "CLK_100M_PCH_SLOTX24_S5_DN")
		)
		(pad "36" smd rect
			(at -13.200126 -1.016)
			(size 0.5588 2.794)
			(drill
				(offset 0 -0.381)
			)
			(layers "F.Cu" "F.Mask" "F.Paste")
			(net "CLK_100M_PCH_SLOTX24_S4_DP")
		)
		(pad "37" smd rect
			(at -12.400026 -1.397)
			(size 0.5588 2.794)
			(layers "F.Cu" "F.Mask" "F.Paste")
			(net "GND")
		)
		(pad "38" smd rect
			(at -12.400026 -1.016)
			(size 0.5588 2.794)
			(drill
				(offset 0 -0.381)
			)
			(layers "F.Cu" "F.Mask" "F.Paste")
			(net "CLK_100M_PCH_SLOTX24_S4_DN")
		)
		(pad "39" smd rect
			(at -11.599926 -1.397)
			(size 0.5588 2.794)
			(layers "F.Cu" "F.Mask" "F.Paste")
			(net "Net_107")
		)
		(pad "40" smd rect
			(at -11.599926 -1.016)
			(size 0.5588 2.794)
			(drill
				(offset 0 -0.381)
			)
			(layers "F.Cu" "F.Mask" "F.Paste")
			(net "GND")
		)
		(pad "41" smd rect
			(at -10.80008 -1.397)
			(size 0.5588 2.794)
			(layers "F.Cu" "F.Mask" "F.Paste")
			(net "Net_106")
		)
		(pad "42" smd rect
			(at -10.80008 -1.016)
			(size 0.5588 2.794)
			(drill
				(offset 0 -0.381)
			)
			(layers "F.Cu" "F.Mask" "F.Paste")
			(net "Net_109")
		)
		(pad "43" smd rect
			(at -9.99998 -1.397)
			(size 0.5588 2.794)
			(layers "F.Cu" "F.Mask" "F.Paste")
			(net "GND")
		)
		(pad "44" smd rect
			(at -9.99998 -1.016)
			(size 0.5588 2.794)
			(drill
				(offset 0 -0.381)
			)
			(layers "F.Cu" "F.Mask" "F.Paste")
			(net "Net_108")
		)
		(pad "45" smd rect
			(at -9.19988 -1.397)
			(size 0.5588 2.794)
			(layers "F.Cu" "F.Mask" "F.Paste")
			(net "Net_113")
		)
		(pad "46" smd rect
			(at -9.19988 -1.016)
			(size 0.5588 2.794)
			(drill
				(offset 0 -0.381)
			)
			(layers "F.Cu" "F.Mask" "F.Paste")
			(net "GND")
		)
		(pad "47" smd rect
			(at -8.400034 -1.397)
			(size 0.5588 2.794)
			(layers "F.Cu" "F.Mask" "F.Paste")
			(net "Net_112")
		)
		(pad "48" smd rect
			(at -8.400034 -1.016)
			(size 0.5588 2.794)
			(drill
				(offset 0 -0.381)
			)
			(layers "F.Cu" "F.Mask" "F.Paste")
			(net "Net_111")
		)
		(pad "49" smd rect
			(at -7.599934 -1.397)
			(size 0.5588 2.794)
			(layers "F.Cu" "F.Mask" "F.Paste")
			(net "GND")
		)
		(pad "50" smd rect
			(at -7.599934 -1.016)
			(size 0.5588 2.794)
			(drill
				(offset 0 -0.381)
			)
			(layers "F.Cu" "F.Mask" "F.Paste")
			(net "Net_110")
		)
		(pad "51" smd rect
			(at -6.800088 -1.397)
			(size 0.5588 2.794)
			(layers "F.Cu" "F.Mask" "F.Paste")
			(net "P3E_CPU0_PE1_PCH_CON_TXP<15>")
		)
		(pad "52" smd rect
			(at -6.800088 -1.016)
			(size 0.5588 2.794)
			(drill
				(offset 0 -0.381)
			)
			(layers "F.Cu" "F.Mask" "F.Paste")
			(net "GND")
		)
		(pad "53" smd rect
			(at -5.999988 -1.397)
			(size 0.5588 2.794)
			(layers "F.Cu" "F.Mask" "F.Paste")
			(net "P3E_CPU0_PE1_PCH_CON_TXN<15>")
		)
		(pad "54" smd rect
			(at -5.999988 -1.016)
			(size 0.5588 2.794)
			(drill
				(offset 0 -0.381)
			)
			(layers "F.Cu" "F.Mask" "F.Paste")
			(net "P3E_CPU0_PE1_PCH_CON_RXP<15>")
		)
		(pad "55" smd rect
			(at -5.199888 -1.397)
			(size 0.5588 2.794)
			(layers "F.Cu" "F.Mask" "F.Paste")
			(net "GND")
		)
		(pad "56" smd rect
			(at -5.199888 -1.016)
			(size 0.5588 2.794)
			(drill
				(offset 0 -0.381)
			)
			(layers "F.Cu" "F.Mask" "F.Paste")
			(net "P3E_CPU0_PE1_PCH_CON_RXN<15>")
		)
		(pad "57" smd rect
			(at -4.400042 -1.397)
			(size 0.5588 2.794)
			(layers "F.Cu" "F.Mask" "F.Paste")
			(net "P3E_CPU0_PE1_PCH_CON_TXP<14>")
		)
		(pad "58" smd rect
			(at -4.400042 -1.016)
			(size 0.5588 2.794)
			(drill
				(offset 0 -0.381)
			)
			(layers "F.Cu" "F.Mask" "F.Paste")
			(net "GND")
		)
		(pad "59" smd rect
			(at -3.599942 -1.397)
			(size 0.5588 2.794)
			(layers "F.Cu" "F.Mask" "F.Paste")
			(net "P3E_CPU0_PE1_PCH_CON_TXN<14>")
		)
		(pad "60" smd rect
			(at -3.599942 -1.016)
			(size 0.5588 2.794)
			(drill
				(offset 0 -0.381)
			)
			(layers "F.Cu" "F.Mask" "F.Paste")
			(net "P3E_CPU0_PE1_PCH_CON_RXP<14>")
		)
		(pad "61" smd rect
			(at -2.800096 -1.397)
			(size 0.5588 2.794)
			(layers "F.Cu" "F.Mask" "F.Paste")
			(net "GND")
		)
		(pad "62" smd rect
			(at -2.800096 -1.016)
			(size 0.5588 2.794)
			(drill
				(offset 0 -0.381)
			)
			(layers "F.Cu" "F.Mask" "F.Paste")
			(net "P3E_CPU0_PE1_PCH_CON_RXN<14>")
		)
		(pad "63" smd rect
			(at -1.999996 -1.397)
			(size 0.5588 2.794)
			(layers "F.Cu" "F.Mask" "F.Paste")
			(net "Net_116")
		)
		(pad "64" smd rect
			(at -1.999996 -1.016)
			(size 0.5588 2.794)
			(drill
				(offset 0 -0.381)
			)
			(layers "F.Cu" "F.Mask" "F.Paste")
			(net "GND")
		)
		(pad "65" smd rect
			(at 1.999996 -1.397)
			(size 0.5588 2.794)
			(layers "F.Cu" "F.Mask" "F.Paste")
			(net "GND")
		)
		(pad "66" smd rect
			(at 1.999996 -1.016)
			(size 0.5588 2.794)
			(drill
				(offset 0 -0.381)
			)
			(layers "F.Cu" "F.Mask" "F.Paste")
			(net "Net_117")
		)
		(pad "67" smd rect
			(at 2.800096 -1.397)
			(size 0.5588 2.794)
			(layers "F.Cu" "F.Mask" "F.Paste")
			(net "P3E_CPU0_PE1_PCH_CON_TXP<13>")
		)
		(pad "68" smd rect
			(at 2.800096 -1.016)
			(size 0.5588 2.794)
			(drill
				(offset 0 -0.381)
			)
			(layers "F.Cu" "F.Mask" "F.Paste")
			(net "GND")
		)
		(pad "69" smd rect
			(at 3.599942 -1.397)
			(size 0.5588 2.794)
			(layers "F.Cu" "F.Mask" "F.Paste")
			(net "P3E_CPU0_PE1_PCH_CON_TXN<13>")
		)
		(pad "70" smd rect
			(at 3.599942 -1.016)
			(size 0.5588 2.794)
			(drill
				(offset 0 -0.381)
			)
			(layers "F.Cu" "F.Mask" "F.Paste")
			(net "P3E_CPU0_PE1_PCH_CON_RXP<13>")
		)
		(pad "71" smd rect
			(at 4.400042 -1.397)
			(size 0.5588 2.794)
			(layers "F.Cu" "F.Mask" "F.Paste")
			(net "GND")
		)
		(pad "72" smd rect
			(at 4.400042 -1.016)
			(size 0.5588 2.794)
			(drill
				(offset 0 -0.381)
			)
			(layers "F.Cu" "F.Mask" "F.Paste")
			(net "P3E_CPU0_PE1_PCH_CON_RXN<13>")
		)
		(pad "73" smd rect
			(at 5.199888 -1.397)
			(size 0.5588 2.794)
			(layers "F.Cu" "F.Mask" "F.Paste")
			(net "P3E_CPU0_PE1_PCH_CON_TXP<12>")
		)
		(pad "74" smd rect
			(at 5.199888 -1.016)
			(size 0.5588 2.794)
			(drill
				(offset 0 -0.381)
			)
			(layers "F.Cu" "F.Mask" "F.Paste")
			(net "GND")
		)
		(pad "75" smd rect
			(at 5.999988 -1.397)
			(size 0.5588 2.794)
			(layers "F.Cu" "F.Mask" "F.Paste")
			(net "P3E_CPU0_PE1_PCH_CON_TXN<12>")
		)
		(pad "76" smd rect
			(at 5.999988 -1.016)
			(size 0.5588 2.794)
			(drill
				(offset 0 -0.381)
			)
			(layers "F.Cu" "F.Mask" "F.Paste")
			(net "P3E_CPU0_PE1_PCH_CON_RXP<12>")
		)
		(pad "77" smd rect
			(at 6.800088 -1.397)
			(size 0.5588 2.794)
			(layers "F.Cu" "F.Mask" "F.Paste")
			(net "GND")
		)
		(pad "78" smd rect
			(at 6.800088 -1.016)
			(size 0.5588 2.794)
			(drill
				(offset 0 -0.381)
			)
			(layers "F.Cu" "F.Mask" "F.Paste")
			(net "P3E_CPU0_PE1_PCH_CON_RXN<12>")
		)
		(pad "79" smd rect
			(at 7.599934 -1.397)
			(size 0.5588 2.794)
			(layers "F.Cu" "F.Mask" "F.Paste")
			(net "P3E_CPU0_PE1_PCH_CON_TXP<11>")
		)
		(pad "80" smd rect
			(at 7.599934 -1.016)
			(size 0.5588 2.794)
			(drill
				(offset 0 -0.381)
			)
			(layers "F.Cu" "F.Mask" "F.Paste")
			(net "GND")
		)
		(pad "81" smd rect
			(at 8.400034 -1.397)
			(size 0.5588 2.794)
			(layers "F.Cu" "F.Mask" "F.Paste")
			(net "P3E_CPU0_PE1_PCH_CON_TXN<11>")
		)
		(pad "82" smd rect
			(at 8.400034 -1.016)
			(size 0.5588 2.794)
			(drill
				(offset 0 -0.381)
			)
			(layers "F.Cu" "F.Mask" "F.Paste")
			(net "P3E_CPU0_PE1_PCH_CON_RXP<11>")
		)
		(pad "83" smd rect
			(at 9.19988 -1.397)
			(size 0.5588 2.794)
			(layers "F.Cu" "F.Mask" "F.Paste")
			(net "GND")
		)
		(pad "84" smd rect
			(at 9.19988 -1.016)
			(size 0.5588 2.794)
			(drill
				(offset 0 -0.381)
			)
			(layers "F.Cu" "F.Mask" "F.Paste")
			(net "P3E_CPU0_PE1_PCH_CON_RXN<11>")
		)
		(pad "85" smd rect
			(at 9.99998 -1.397)
			(size 0.5588 2.794)
			(layers "F.Cu" "F.Mask" "F.Paste")
			(net "P3E_CPU0_PE1_PCH_CON_TXP<10>")
		)
		(pad "86" smd rect
			(at 9.99998 -1.016)
			(size 0.5588 2.794)
			(drill
				(offset 0 -0.381)
			)
			(layers "F.Cu" "F.Mask" "F.Paste")
			(net "GND")
		)
		(pad "87" smd rect
			(at 10.80008 -1.397)
			(size 0.5588 2.794)
			(layers "F.Cu" "F.Mask" "F.Paste")
			(net "P3E_CPU0_PE1_PCH_CON_TXN<10>")
		)
		(pad "88" smd rect
			(at 10.80008 -1.016)
			(size 0.5588 2.794)
			(drill
				(offset 0 -0.381)
			)
			(layers "F.Cu" "F.Mask" "F.Paste")
			(net "P3E_CPU0_PE1_PCH_CON_RXP<10>")
		)
		(pad "89" smd rect
			(at 11.599926 -1.397)
			(size 0.5588 2.794)
			(layers "F.Cu" "F.Mask" "F.Paste")
			(net "GND")
		)
		(pad "90" smd rect
			(at 11.599926 -1.016)
			(size 0.5588 2.794)
			(drill
				(offset 0 -0.381)
			)
			(layers "F.Cu" "F.Mask" "F.Paste")
			(net "P3E_CPU0_PE1_PCH_CON_RXN<10>")
		)
		(pad "91" smd rect
			(at 12.400026 -1.397)
			(size 0.5588 2.794)
			(layers "F.Cu" "F.Mask" "F.Paste")
			(net "P3E_CPU0_PE1_PCH_CON_TXP<9>")
		)
		(pad "92" smd rect
			(at 12.400026 -1.016)
			(size 0.5588 2.794)
			(drill
				(offset 0 -0.381)
			)
			(layers "F.Cu" "F.Mask" "F.Paste")
			(net "GND")
		)
		(pad "93" smd rect
			(at 13.200126 -1.397)
			(size 0.5588 2.794)
			(layers "F.Cu" "F.Mask" "F.Paste")
			(net "P3E_CPU0_PE1_PCH_CON_TXN<9>")
		)
		(pad "94" smd rect
			(at 13.200126 -1.016)
			(size 0.5588 2.794)
			(drill
				(offset 0 -0.381)
			)
			(layers "F.Cu" "F.Mask" "F.Paste")
			(net "P3E_CPU0_PE1_PCH_CON_RXP<9>")
		)
		(pad "95" smd rect
			(at 13.999972 -1.397)
			(size 0.5588 2.794)
			(layers "F.Cu" "F.Mask" "F.Paste")
			(net "GND")
		)
		(pad "96" smd rect
			(at 13.999972 -1.016)
			(size 0.5588 2.794)
			(drill
				(offset 0 -0.381)
			)
			(layers "F.Cu" "F.Mask" "F.Paste")
			(net "P3E_CPU0_PE1_PCH_CON_RXN<9>")
		)
		(pad "97" smd rect
			(at 14.800072 -1.397)
			(size 0.5588 2.794)
			(layers "F.Cu" "F.Mask" "F.Paste")
			(net "P3E_CPU0_PE1_PCH_CON_TXP<8>")
		)
		(pad "98" smd rect
			(at 14.800072 -1.016)
			(size 0.5588 2.794)
			(drill
				(offset 0 -0.381)
			)
			(layers "F.Cu" "F.Mask" "F.Paste")
			(net "GND")
		)
		(pad "99" smd rect
			(at 15.599918 -1.397)
			(size 0.5588 2.794)
			(layers "F.Cu" "F.Mask" "F.Paste")
			(net "P3E_CPU0_PE1_PCH_CON_TXN<8>")
		)
		(pad "100" smd rect
			(at 15.599918 -1.016)
			(size 0.5588 2.794)
			(drill
				(offset 0 -0.381)
			)
			(layers "F.Cu" "F.Mask" "F.Paste")
			(net "P3E_CPU0_PE1_PCH_CON_RXP<8>")
		)
		(pad "101" smd rect
			(at 16.400018 -1.397)
			(size 0.5588 2.794)
			(layers "F.Cu" "F.Mask" "F.Paste")
			(net "GND")
		)
		(pad "102" smd rect
			(at 16.400018 -1.016)
			(size 0.5588 2.794)
			(drill
				(offset 0 -0.381)
			)
			(layers "F.Cu" "F.Mask" "F.Paste")
			(net "P3E_CPU0_PE1_PCH_CON_RXN<8>")
		)
		(pad "103" smd rect
			(at 17.200118 -1.397)
			(size 0.5588 2.794)
			(layers "F.Cu" "F.Mask" "F.Paste")
			(net "P3E_CPU0_PE1_SS_C_TXP<7>")
		)
		(pad "104" smd rect
			(at 17.200118 -1.016)
			(size 0.5588 2.794)
			(drill
				(offset 0 -0.381)
			)
			(layers "F.Cu" "F.Mask" "F.Paste")
			(net "GND")
		)
		(pad "105" smd rect
			(at 17.999964 -1.397)
			(size 0.5588 2.794)
			(layers "F.Cu" "F.Mask" "F.Paste")
			(net "P3E_CPU0_PE1_SS_C_TXN<7>")
		)
		(pad "106" smd rect
			(at 17.999964 -1.016)
			(size 0.5588 2.794)
			(drill
				(offset 0 -0.381)
			)
			(layers "F.Cu" "F.Mask" "F.Paste")
			(net "P3E_CPU0_PE1_SS_C_RXP<7>")
		)
		(pad "107" smd rect
			(at 18.800064 -1.397)
			(size 0.5588 2.794)
			(layers "F.Cu" "F.Mask" "F.Paste")
			(net "GND")
		)
		(pad "108" smd rect
			(at 18.800064 -1.016)
			(size 0.5588 2.794)
			(drill
				(offset 0 -0.381)
			)
			(layers "F.Cu" "F.Mask" "F.Paste")
			(net "P3E_CPU0_PE1_SS_C_RXN<7>")
		)
		(pad "109" smd rect
			(at 19.59991 -1.397)
			(size 0.5588 2.794)
			(layers "F.Cu" "F.Mask" "F.Paste")
			(net "P3E_CPU0_PE1_SS_C_TXP<6>")
		)
		(pad "110" smd rect
			(at 19.59991 -1.016)
			(size 0.5588 2.794)
			(drill
				(offset 0 -0.381)
			)
			(layers "F.Cu" "F.Mask" "F.Paste")
			(net "GND")
		)
		(pad "111" smd rect
			(at 20.40001 -1.397)
			(size 0.5588 2.794)
			(layers "F.Cu" "F.Mask" "F.Paste")
			(net "P3E_CPU0_PE1_SS_C_TXN<6>")
		)
		(pad "112" smd rect
			(at 20.40001 -1.016)
			(size 0.5588 2.794)
			(drill
				(offset 0 -0.381)
			)
			(layers "F.Cu" "F.Mask" "F.Paste")
			(net "P3E_CPU0_PE1_SS_C_RXP<6>")
		)
		(pad "113" smd rect
			(at 21.20011 -1.397)
			(size 0.5588 2.794)
			(layers "F.Cu" "F.Mask" "F.Paste")
			(net "GND")
		)
		(pad "114" smd rect
			(at 21.20011 -1.016)
			(size 0.5588 2.794)
			(drill
				(offset 0 -0.381)
			)
			(layers "F.Cu" "F.Mask" "F.Paste")
			(net "P3E_CPU0_PE1_SS_C_RXN<6>")
		)
		(pad "115" smd rect
			(at 21.999956 -1.397)
			(size 0.5588 2.794)
			(layers "F.Cu" "F.Mask" "F.Paste")
			(net "P3E_CPU0_PE1_SS_C_TXP<5>")
		)
		(pad "116" smd rect
			(at 21.999956 -1.016)
			(size 0.5588 2.794)
			(drill
				(offset 0 -0.381)
			)
			(layers "F.Cu" "F.Mask" "F.Paste")
			(net "GND")
		)
		(pad "117" smd rect
			(at 22.800056 -1.397)
			(size 0.5588 2.794)
			(layers "F.Cu" "F.Mask" "F.Paste")
			(net "P3E_CPU0_PE1_SS_C_TXN<5>")
		)
		(pad "118" smd rect
			(at 22.800056 -1.016)
			(size 0.5588 2.794)
			(drill
				(offset 0 -0.381)
			)
			(layers "F.Cu" "F.Mask" "F.Paste")
			(net "P3E_CPU0_PE1_SS_C_RXP<5>")
		)
		(pad "119" smd rect
			(at 23.599902 -1.397)
			(size 0.5588 2.794)
			(layers "F.Cu" "F.Mask" "F.Paste")
			(net "GND")
		)
		(pad "120" smd rect
			(at 23.599902 -1.016)
			(size 0.5588 2.794)
			(drill
				(offset 0 -0.381)
			)
			(layers "F.Cu" "F.Mask" "F.Paste")
			(net "P3E_CPU0_PE1_SS_C_RXN<5>")
		)
		(pad "121" smd rect
			(at 24.400002 -1.397)
			(size 0.5588 2.794)
			(layers "F.Cu" "F.Mask" "F.Paste")
			(net "P3E_CPU0_PE1_SS_C_TXP<4>")
		)
		(pad "122" smd rect
			(at 24.400002 -1.016)
			(size 0.5588 2.794)
			(drill
				(offset 0 -0.381)
			)
			(layers "F.Cu" "F.Mask" "F.Paste")
			(net "GND")
		)
		(pad "123" smd rect
			(at 25.200102 -1.397)
			(size 0.5588 2.794)
			(layers "F.Cu" "F.Mask" "F.Paste")
			(net "P3E_CPU0_PE1_SS_C_TXN<4>")
		)
		(pad "124" smd rect
			(at 25.200102 -1.016)
			(size 0.5588 2.794)
			(drill
				(offset 0 -0.381)
			)
			(layers "F.Cu" "F.Mask" "F.Paste")
			(net "P3E_CPU0_PE1_SS_C_RXP<4>")
		)
		(pad "125" smd rect
			(at 25.999948 -1.397)
			(size 0.5588 2.794)
			(layers "F.Cu" "F.Mask" "F.Paste")
			(net "GND")
		)
		(pad "126" smd rect
			(at 25.999948 -1.016)
			(size 0.5588 2.794)
			(drill
				(offset 0 -0.381)
			)
			(layers "F.Cu" "F.Mask" "F.Paste")
			(net "P3E_CPU0_PE1_SS_C_RXN<4>")
		)
		(pad "127" smd rect
			(at 26.800048 -1.397)
			(size 0.5588 2.794)
			(layers "F.Cu" "F.Mask" "F.Paste")
			(net "P3E_CPU0_PE1_SS_C_TXP<3>")
		)
		(pad "128" smd rect
			(at 26.800048 -1.016)
			(size 0.5588 2.794)
			(drill
				(offset 0 -0.381)
			)
			(layers "F.Cu" "F.Mask" "F.Paste")
			(net "GND")
		)
		(pad "129" smd rect
			(at 27.599894 -1.397)
			(size 0.5588 2.794)
			(layers "F.Cu" "F.Mask" "F.Paste")
			(net "P3E_CPU0_PE1_SS_C_TXN<3>")
		)
		(pad "130" smd rect
			(at 27.599894 -1.016)
			(size 0.5588 2.794)
			(drill
				(offset 0 -0.381)
			)
			(layers "F.Cu" "F.Mask" "F.Paste")
			(net "P3E_CPU0_PE1_SS_C_RXP<3>")
		)
		(pad "131" smd rect
			(at 28.399994 -1.397)
			(size 0.5588 2.794)
			(layers "F.Cu" "F.Mask" "F.Paste")
			(net "GND")
		)
		(pad "132" smd rect
			(at 28.399994 -1.016)
			(size 0.5588 2.794)
			(drill
				(offset 0 -0.381)
			)
			(layers "F.Cu" "F.Mask" "F.Paste")
			(net "P3E_CPU0_PE1_SS_C_RXN<3>")
		)
		(pad "133" smd rect
			(at 29.200094 -1.397)
			(size 0.5588 2.794)
			(layers "F.Cu" "F.Mask" "F.Paste")
			(net "P3E_CPU0_PE1_SS_C_TXP<2>")
		)
		(pad "134" smd rect
			(at 29.200094 -1.016)
			(size 0.5588 2.794)
			(drill
				(offset 0 -0.381)
			)
			(layers "F.Cu" "F.Mask" "F.Paste")
			(net "GND")
		)
		(pad "135" smd rect
			(at 29.99994 -1.397)
			(size 0.5588 2.794)
			(layers "F.Cu" "F.Mask" "F.Paste")
			(net "P3E_CPU0_PE1_SS_C_TXN<2>")
		)
		(pad "136" smd rect
			(at 29.99994 -1.016)
			(size 0.5588 2.794)
			(drill
				(offset 0 -0.381)
			)
			(layers "F.Cu" "F.Mask" "F.Paste")
			(net "P3E_CPU0_PE1_SS_C_RXP<2>")
		)
		(pad "137" smd rect
			(at 30.80004 -1.397)
			(size 0.5588 2.794)
			(layers "F.Cu" "F.Mask" "F.Paste")
			(net "GND")
		)
		(pad "138" smd rect
			(at 30.80004 -1.016)
			(size 0.5588 2.794)
			(drill
				(offset 0 -0.381)
			)
			(layers "F.Cu" "F.Mask" "F.Paste")
			(net "P3E_CPU0_PE1_SS_C_RXN<2>")
		)
		(pad "139" smd rect
			(at 31.599886 -1.397)
			(size 0.5588 2.794)
			(layers "F.Cu" "F.Mask" "F.Paste")
			(net "P3E_CPU0_PE1_SS_C_TXP<1>")
		)
		(pad "140" smd rect
			(at 31.599886 -1.016)
			(size 0.5588 2.794)
			(drill
				(offset 0 -0.381)
			)
			(layers "F.Cu" "F.Mask" "F.Paste")
			(net "GND")
		)
		(pad "141" smd rect
			(at 32.399986 -1.397)
			(size 0.5588 2.794)
			(layers "F.Cu" "F.Mask" "F.Paste")
			(net "P3E_CPU0_PE1_SS_C_TXN<1>")
		)
		(pad "142" smd rect
			(at 32.399986 -1.016)
			(size 0.5588 2.794)
			(drill
				(offset 0 -0.381)
			)
			(layers "F.Cu" "F.Mask" "F.Paste")
			(net "P3E_CPU0_PE1_SS_C_RXP<1>")
		)
		(pad "143" smd rect
			(at 33.200086 -1.397)
			(size 0.5588 2.794)
			(layers "F.Cu" "F.Mask" "F.Paste")
			(net "GND")
		)
		(pad "144" smd rect
			(at 33.200086 -1.016)
			(size 0.5588 2.794)
			(drill
				(offset 0 -0.381)
			)
			(layers "F.Cu" "F.Mask" "F.Paste")
			(net "P3E_CPU0_PE1_SS_C_RXN<1>")
		)
		(pad "145" smd rect
			(at 33.999932 -1.397)
			(size 0.5588 2.794)
			(layers "F.Cu" "F.Mask" "F.Paste")
			(net "P3E_CPU0_PE1_SS_C_TXP<0>")
		)
		(pad "146" smd rect
			(at 33.999932 -1.016)
			(size 0.5588 2.794)
			(drill
				(offset 0 -0.381)
			)
			(layers "F.Cu" "F.Mask" "F.Paste")
			(net "GND")
		)
		(pad "147" smd rect
			(at 34.800032 -1.397)
			(size 0.5588 2.794)
			(layers "F.Cu" "F.Mask" "F.Paste")
			(net "P3E_CPU0_PE1_SS_C_TXN<0>")
		)
		(pad "148" smd rect
			(at 34.800032 -1.016)
			(size 0.5588 2.794)
			(drill
				(offset 0 -0.381)
			)
			(layers "F.Cu" "F.Mask" "F.Paste")
			(net "P3E_CPU0_PE1_SS_C_RXP<0>")
		)
		(pad "149" smd rect
			(at 35.599878 -1.397)
			(size 0.5588 2.794)
			(layers "F.Cu" "F.Mask" "F.Paste")
			(net "GND")
		)
		(pad "150" smd rect
			(at 35.599878 -1.016)
			(size 0.5588 2.794)
			(drill
				(offset 0 -0.381)
			)
			(layers "F.Cu" "F.Mask" "F.Paste")
			(net "P3E_CPU0_PE1_SS_C_RXN<0>")
		)
		(pad "151" smd rect
			(at 36.399978 -1.397)
			(size 0.5588 2.794)
			(layers "F.Cu" "F.Mask" "F.Paste")
			(net "P3E_CPU0_PE2_SS_C_TXP<0>")
		)
		(pad "152" smd rect
			(at 36.399978 -1.016)
			(size 0.5588 2.794)
			(drill
				(offset 0 -0.381)
			)
			(layers "F.Cu" "F.Mask" "F.Paste")
			(net "GND")
		)
		(pad "153" smd rect
			(at 37.200078 -1.397)
			(size 0.5588 2.794)
			(layers "F.Cu" "F.Mask" "F.Paste")
			(net "P3E_CPU0_PE2_SS_C_TXN<0>")
		)
		(pad "154" smd rect
			(at 37.200078 -1.016)
			(size 0.5588 2.794)
			(drill
				(offset 0 -0.381)
			)
			(layers "F.Cu" "F.Mask" "F.Paste")
			(net "P3E_CPU0_PE2_SS_RXP<0>")
		)
		(pad "155" smd rect
			(at 37.999924 -1.397)
			(size 0.5588 2.794)
			(layers "F.Cu" "F.Mask" "F.Paste")
			(net "GND")
		)
		(pad "156" smd rect
			(at 37.999924 -1.016)
			(size 0.5588 2.794)
			(drill
				(offset 0 -0.381)
			)
			(layers "F.Cu" "F.Mask" "F.Paste")
			(net "P3E_CPU0_PE2_SS_RXN<0>")
		)
		(pad "157" smd rect
			(at 38.800024 -1.397)
			(size 0.5588 2.794)
			(layers "F.Cu" "F.Mask" "F.Paste")
			(net "P3E_CPU0_PE2_SS_C_TXP<1>")
		)
		(pad "158" smd rect
			(at 38.800024 -1.016)
			(size 0.5588 2.794)
			(drill
				(offset 0 -0.381)
			)
			(layers "F.Cu" "F.Mask" "F.Paste")
			(net "GND")
		)
		(pad "159" smd rect
			(at 39.600124 -1.397)
			(size 0.5588 2.794)
			(layers "F.Cu" "F.Mask" "F.Paste")
			(net "P3E_CPU0_PE2_SS_C_TXN<1>")
		)
		(pad "160" smd rect
			(at 39.600124 -1.016)
			(size 0.5588 2.794)
			(drill
				(offset 0 -0.381)
			)
			(layers "F.Cu" "F.Mask" "F.Paste")
			(net "P3E_CPU0_PE2_SS_RXP<1>")
		)
		(pad "161" smd rect
			(at 40.39997 -1.397)
			(size 0.5588 2.794)
			(layers "F.Cu" "F.Mask" "F.Paste")
			(net "GND")
		)
		(pad "162" smd rect
			(at 40.39997 -1.016)
			(size 0.5588 2.794)
			(drill
				(offset 0 -0.381)
			)
			(layers "F.Cu" "F.Mask" "F.Paste")
			(net "P3E_CPU0_PE2_SS_RXN<1>")
		)
		(pad "163" smd rect
			(at 41.20007 -1.397)
			(size 0.5588 2.794)
			(layers "F.Cu" "F.Mask" "F.Paste")
			(net "P3E_CPU0_PE2_SS_C_TXP<2>")
		)
		(pad "164" smd rect
			(at 41.20007 -1.016)
			(size 0.5588 2.794)
			(drill
				(offset 0 -0.381)
			)
			(layers "F.Cu" "F.Mask" "F.Paste")
			(net "GND")
		)
		(pad "165" smd rect
			(at 41.999916 -1.397)
			(size 0.5588 2.794)
			(layers "F.Cu" "F.Mask" "F.Paste")
			(net "P3E_CPU0_PE2_SS_C_TXN<2>")
		)
		(pad "166" smd rect
			(at 41.999916 -1.016)
			(size 0.5588 2.794)
			(drill
				(offset 0 -0.381)
			)
			(layers "F.Cu" "F.Mask" "F.Paste")
			(net "P3E_CPU0_PE2_SS_RXP<2>")
		)
		(pad "167" smd rect
			(at 42.800016 -1.397)
			(size 0.5588 2.794)
			(layers "F.Cu" "F.Mask" "F.Paste")
			(net "GND")
		)
		(pad "168" smd rect
			(at 42.800016 -1.016)
			(size 0.5588 2.794)
			(drill
				(offset 0 -0.381)
			)
			(layers "F.Cu" "F.Mask" "F.Paste")
			(net "P3E_CPU0_PE2_SS_RXN<2>")
		)
		(pad "169" smd rect
			(at 43.600116 -1.397)
			(size 0.5588 2.794)
			(layers "F.Cu" "F.Mask" "F.Paste")
			(net "P3E_CPU0_PE2_SS_C_TXP<3>")
		)
		(pad "170" smd rect
			(at 43.600116 -1.016)
			(size 0.5588 2.794)
			(drill
				(offset 0 -0.381)
			)
			(layers "F.Cu" "F.Mask" "F.Paste")
			(net "GND")
		)
		(pad "171" smd rect
			(at 44.399962 -1.397)
			(size 0.5588 2.794)
			(layers "F.Cu" "F.Mask" "F.Paste")
			(net "P3E_CPU0_PE2_SS_C_TXN<3>")
		)
		(pad "172" smd rect
			(at 44.399962 -1.016)
			(size 0.5588 2.794)
			(drill
				(offset 0 -0.381)
			)
			(layers "F.Cu" "F.Mask" "F.Paste")
			(net "P3E_CPU0_PE2_SS_RXP<3>")
		)
		(pad "173" smd rect
			(at 45.200062 -1.397)
			(size 0.5588 2.794)
			(layers "F.Cu" "F.Mask" "F.Paste")
			(net "GND")
		)
		(pad "174" smd rect
			(at 45.200062 -1.016)
			(size 0.5588 2.794)
			(drill
				(offset 0 -0.381)
			)
			(layers "F.Cu" "F.Mask" "F.Paste")
			(net "P3E_CPU0_PE2_SS_RXN<3>")
		)
		(pad "175" smd rect
			(at 45.999908 -1.397)
			(size 0.5588 2.794)
			(layers "F.Cu" "F.Mask" "F.Paste")
			(net "P3E_CPU0_PE2_SS_C_TXP<4>")
		)
		(pad "176" smd rect
			(at 45.999908 -1.016)
			(size 0.5588 2.794)
			(drill
				(offset 0 -0.381)
			)
			(layers "F.Cu" "F.Mask" "F.Paste")
			(net "GND")
		)
		(pad "177" smd rect
			(at 46.800008 -1.397)
			(size 0.5588 2.794)
			(layers "F.Cu" "F.Mask" "F.Paste")
			(net "P3E_CPU0_PE2_SS_C_TXN<4>")
		)
		(pad "178" smd rect
			(at 46.800008 -1.016)
			(size 0.5588 2.794)
			(drill
				(offset 0 -0.381)
			)
			(layers "F.Cu" "F.Mask" "F.Paste")
			(net "P3E_CPU0_PE2_SS_RXP<4>")
		)
		(pad "179" smd rect
			(at 47.600108 -1.397)
			(size 0.5588 2.794)
			(layers "F.Cu" "F.Mask" "F.Paste")
			(net "GND")
		)
		(pad "180" smd rect
			(at 47.600108 -1.016)
			(size 0.5588 2.794)
			(drill
				(offset 0 -0.381)
			)
			(layers "F.Cu" "F.Mask" "F.Paste")
			(net "P3E_CPU0_PE2_SS_RXN<4>")
		)
		(pad "181" smd rect
			(at 48.399954 -1.397)
			(size 0.5588 2.794)
			(layers "F.Cu" "F.Mask" "F.Paste")
			(net "P3E_CPU0_PE2_SS_C_TXP<5>")
		)
		(pad "182" smd rect
			(at 48.399954 -1.016)
			(size 0.5588 2.794)
			(drill
				(offset 0 -0.381)
			)
			(layers "F.Cu" "F.Mask" "F.Paste")
			(net "GND")
		)
		(pad "183" smd rect
			(at 49.200054 -1.397)
			(size 0.5588 2.794)
			(layers "F.Cu" "F.Mask" "F.Paste")
			(net "P3E_CPU0_PE2_SS_C_TXN<5>")
		)
		(pad "184" smd rect
			(at 49.200054 -1.016)
			(size 0.5588 2.794)
			(drill
				(offset 0 -0.381)
			)
			(layers "F.Cu" "F.Mask" "F.Paste")
			(net "P3E_CPU0_PE2_SS_RXP<5>")
		)
		(pad "185" smd rect
			(at 49.9999 -1.397)
			(size 0.5588 2.794)
			(layers "F.Cu" "F.Mask" "F.Paste")
			(net "GND")
		)
		(pad "186" smd rect
			(at 49.9999 -1.016)
			(size 0.5588 2.794)
			(drill
				(offset 0 -0.381)
			)
			(layers "F.Cu" "F.Mask" "F.Paste")
			(net "P3E_CPU0_PE2_SS_RXN<5>")
		)
		(pad "187" smd rect
			(at 50.8 -1.397)
			(size 0.5588 2.794)
			(layers "F.Cu" "F.Mask" "F.Paste")
			(net "P3E_CPU0_PE2_SS_C_TXP<6>")
		)
		(pad "188" smd rect
			(at 50.8 -1.016)
			(size 0.5588 2.794)
			(drill
				(offset 0 -0.381)
			)
			(layers "F.Cu" "F.Mask" "F.Paste")
			(net "GND")
		)
		(pad "189" smd rect
			(at 51.6001 -1.397)
			(size 0.5588 2.794)
			(layers "F.Cu" "F.Mask" "F.Paste")
			(net "P3E_CPU0_PE2_SS_C_TXN<6>")
		)
		(pad "190" smd rect
			(at 51.6001 -1.016)
			(size 0.5588 2.794)
			(drill
				(offset 0 -0.381)
			)
			(layers "F.Cu" "F.Mask" "F.Paste")
			(net "P3E_CPU0_PE2_SS_RXP<6>")
		)
		(pad "191" smd rect
			(at 52.399946 -1.397)
			(size 0.5588 2.794)
			(layers "F.Cu" "F.Mask" "F.Paste")
			(net "GND")
		)
		(pad "192" smd rect
			(at 52.399946 -1.016)
			(size 0.5588 2.794)
			(drill
				(offset 0 -0.381)
			)
			(layers "F.Cu" "F.Mask" "F.Paste")
			(net "P3E_CPU0_PE2_SS_RXN<6>")
		)
		(pad "193" smd rect
			(at 53.200046 -1.397)
			(size 0.5588 2.794)
			(layers "F.Cu" "F.Mask" "F.Paste")
			(net "P3E_CPU0_PE2_SS_C_TXP<7>")
		)
		(pad "194" smd rect
			(at 53.200046 -1.016)
			(size 0.5588 2.794)
			(drill
				(offset 0 -0.381)
			)
			(layers "F.Cu" "F.Mask" "F.Paste")
			(net "GND")
		)
		(pad "195" smd rect
			(at 53.999892 -1.397)
			(size 0.5588 2.794)
			(layers "F.Cu" "F.Mask" "F.Paste")
			(net "P3E_CPU0_PE2_SS_C_TXN<7>")
		)
		(pad "196" smd rect
			(at 53.999892 -1.016)
			(size 0.5588 2.794)
			(drill
				(offset 0 -0.381)
			)
			(layers "F.Cu" "F.Mask" "F.Paste")
			(net "P3E_CPU0_PE2_SS_RXP<7>")
		)
		(pad "197" smd rect
			(at 54.799992 -1.397)
			(size 0.5588 2.794)
			(layers "F.Cu" "F.Mask" "F.Paste")
			(net "GND")
		)
		(pad "198" smd rect
			(at 54.799992 -1.016)
			(size 0.5588 2.794)
			(drill
				(offset 0 -0.381)
			)
			(layers "F.Cu" "F.Mask" "F.Paste")
			(net "P3E_CPU0_PE2_SS_RXN<7>")
		)
		(pad "199" smd rect
			(at 55.600092 -1.397)
			(size 0.5588 2.794)
			(layers "F.Cu" "F.Mask" "F.Paste")
			(net "FM_PRSNT_2_6_N")
		)
		(pad "200" smd rect
			(at 55.600092 -1.016)
			(size 0.5588 2.794)
			(drill
				(offset 0 -0.381)
			)
			(layers "F.Cu" "F.Mask" "F.Paste")
			(net "GND")
		)
		(zone
			(layer "F.Cu")
			(hatch none 0.5)
			(connect_pads
				(clearance 0)
			)
			(min_thickness 0.25)
			(keepout
				(tracks allowed)
				(vias not_allowed)
				(pads allowed)
				(copperpour not_allowed)
				(footprints allowed)
			)
			(placement
				(enabled no)
				(sheetname "")
			)
			(fill
				(thermal_gap 0.5)
				(thermal_bridge_width 0.5)
				(island_removal_mode 0)
			)
			(polygon
				(pts
					(xy 14.2875 14.546072) (xy 99.2759 14.546072) (xy 99.2759 9.720072) (xy 14.2875 9.720072)
				)
			)
		)
		(zone
			(layer "F.Cu")
			(hatch none 0.5)
			(connect_pads
				(clearance 0)
			)
			(min_thickness 0.25)
			(keepout
				(tracks not_allowed)
				(vias allowed)
				(pads allowed)
				(copperpour not_allowed)
				(footprints allowed)
			)
			(placement
				(enabled no)
				(sheetname "")
			)
			(fill
				(thermal_gap 0.5)
				(thermal_bridge_width 0.5)
				(island_removal_mode 0)
			)
			(polygon
				(pts
					(xy 14.2875 14.546072) (xy 99.2759 14.546072) (xy 99.2759 13.530072) (xy 14.2875 13.530072)
				)
			)
		)
		(zone
			(layer "B.Cu")
			(hatch none 0.5)
			(connect_pads
				(clearance 0)
			)
			(min_thickness 0.25)
			(keepout
				(tracks allowed)
				(vias not_allowed)
				(pads allowed)
				(copperpour not_allowed)
				(footprints allowed)
			)
			(placement
				(enabled no)
				(sheetname "")
			)
			(fill
				(thermal_gap 0.5)
				(thermal_bridge_width 0.5)
				(island_removal_mode 0)
			)
			(polygon
				(pts
					(xy 14.2875 14.546072) (xy 99.2759 14.546072) (xy 99.2759 9.720072) (xy 14.2875 9.720072)
				)
			)
		)
		(zone
			(layer "B.Cu")
			(hatch none 0.5)
			(connect_pads
				(clearance 0)
			)
			(min_thickness 0.25)
			(keepout
				(tracks not_allowed)
				(vias allowed)
				(pads allowed)
				(copperpour not_allowed)
				(footprints allowed)
			)
			(placement
				(enabled no)
				(sheetname "")
			)
			(fill
				(thermal_gap 0.5)
				(thermal_bridge_width 0.5)
				(island_removal_mode 0)
			)
			(polygon
				(pts
					(xy 14.2875 14.546072) (xy 99.2759 14.546072) (xy 99.2759 13.530072) (xy 14.2875 13.530072)
				)
			)
		)
	)
	(footprint ""
		(layer "F.Cu")
		(at 26.5176 -26.6446 90)
		(property "Reference" "R93"
			(at 0 0 90)
			(layer "F.SilkS")
			(hide yes)
			(effects
				(font
					(size 1.27 1.27)
				)
			)
		)
		(property "Value" "10KR2F-2-GP"
			(at 0.064008 -3.993896 90)
			(unlocked yes)
			(layer "F.Fab")
			(hide yes)
			(effects
				(font
					(size 1.016 1.016)
					(thickness 0.1524)
				)
			)
		)
		(property "Device Type" "R402H16"
			(at 0.064008 -5.517896 90)
			(unlocked yes)
			(layer "F.Fab")
			(hide yes)
			(effects
				(font
					(size 1.016 1.016)
					(thickness 0.1524)
				)
			)
		)
		(duplicate_pad_numbers_are_jumpers no)
		(fp_line
			(start 0.508 -0.9398)
			(end -0.508 -0.9398)
			(stroke
				(width 0.1524)
				(type default)
			)
			(layer "F.SilkS")
		)
		(fp_line
			(start -0.508 -0.9398)
			(end -0.508 0.9398)
			(stroke
				(width 0.1524)
				(type default)
			)
			(layer "F.SilkS")
		)
		(fp_rect
			(start -0.508 0.9398)
			(end 0.508 -0.9398)
			(stroke
				(width 0)
				(type default)
			)
			(fill no)
			(layer "F.CrtYd")
		)
		(fp_rect
			(start -0.508 0.9398)
			(end 0.508 -0.9398)
			(stroke
				(width 0)
				(type default)
			)
			(fill no)
			(layer "F.Fab")
		)
		(pad "1" smd custom
			(at 0 -0.4445 90)
			(size 0.1397 0.1397)
			(layers "F.Cu" "F.Mask" "F.Paste")
			(net "SLOT3_VMONITOR_A0")
			(options
				(clearance outline)
				(anchor circle)
			)
			(primitives
				(gr_poly
					(pts
						(arc
							(start -0.1778 -0.2794)
							(mid -0.249642 -0.249642)
							(end -0.2794 -0.1778)
						)
						(arc
							(start -0.2794 0.1778)
							(mid -0.249642 0.249642)
							(end -0.1778 0.2794)
						)
						(arc
							(start 0.1778 0.2794)
							(mid 0.249642 0.249642)
							(end 0.2794 0.1778)
						)
						(arc
							(start 0.2794 -0.1778)
							(mid 0.249642 -0.249642)
							(end 0.1778 -0.2794)
						)
					)
					(width 0)
					(fill yes)
				)
			)
		)
		(pad "2" smd custom
			(at 0 0.4445 90)
			(size 0.1397 0.1397)
			(layers "F.Cu" "F.Mask" "F.Paste")
			(net "GND")
			(options
				(clearance outline)
				(anchor circle)
			)
			(primitives
				(gr_poly
					(pts
						(arc
							(start -0.1778 -0.2794)
							(mid -0.249642 -0.249642)
							(end -0.2794 -0.1778)
						)
						(arc
							(start -0.2794 0.1778)
							(mid -0.249642 0.249642)
							(end -0.1778 0.2794)
						)
						(arc
							(start 0.1778 0.2794)
							(mid 0.249642 0.249642)
							(end 0.2794 0.1778)
						)
						(arc
							(start 0.2794 -0.1778)
							(mid 0.249642 -0.249642)
							(end 0.1778 -0.2794)
						)
					)
					(width 0)
					(fill yes)
				)
			)
		)
	)
	(footprint ""
		(layer "F.Cu")
		(at 26.5176 -25.6032 90)
		(property "Reference" "R92"
			(at 0 0 90)
			(layer "F.SilkS")
			(hide yes)
			(effects
				(font
					(size 1.27 1.27)
				)
			)
		)
		(property "Value" "10KR2F-2-GP"
			(at 0.064008 -3.993896 90)
			(unlocked yes)
			(layer "F.Fab")
			(hide yes)
			(effects
				(font
					(size 1.016 1.016)
					(thickness 0.1524)
				)
			)
		)
		(property "Device Type" "R402H16"
			(at 0.064008 -5.517896 90)
			(unlocked yes)
			(layer "F.Fab")
			(hide yes)
			(effects
				(font
					(size 1.016 1.016)
					(thickness 0.1524)
				)
			)
		)
		(duplicate_pad_numbers_are_jumpers no)
		(fp_line
			(start 0.508 -0.9398)
			(end -0.508 -0.9398)
			(stroke
				(width 0.1524)
				(type default)
			)
			(layer "F.SilkS")
		)
		(fp_line
			(start -0.508 -0.9398)
			(end -0.508 0.9398)
			(stroke
				(width 0.1524)
				(type default)
			)
			(layer "F.SilkS")
		)
		(fp_rect
			(start -0.508 0.9398)
			(end 0.508 -0.9398)
			(stroke
				(width 0)
				(type default)
			)
			(fill no)
			(layer "F.CrtYd")
		)
		(fp_rect
			(start -0.508 0.9398)
			(end 0.508 -0.9398)
			(stroke
				(width 0)
				(type default)
			)
			(fill no)
			(layer "F.Fab")
		)
		(pad "1" smd custom
			(at 0 -0.4445 90)
			(size 0.1397 0.1397)
			(layers "F.Cu" "F.Mask" "F.Paste")
			(net "SLOT3_VMONITOR_A1")
			(options
				(clearance outline)
				(anchor circle)
			)
			(primitives
				(gr_poly
					(pts
						(arc
							(start -0.1778 -0.2794)
							(mid -0.249642 -0.249642)
							(end -0.2794 -0.1778)
						)
						(arc
							(start -0.2794 0.1778)
							(mid -0.249642 0.249642)
							(end -0.1778 0.2794)
						)
						(arc
							(start 0.1778 0.2794)
							(mid 0.249642 0.249642)
							(end 0.2794 0.1778)
						)
						(arc
							(start 0.2794 -0.1778)
							(mid 0.249642 -0.249642)
							(end 0.1778 -0.2794)
						)
					)
					(width 0)
					(fill yes)
				)
			)
		)
		(pad "2" smd custom
			(at 0 0.4445 90)
			(size 0.1397 0.1397)
			(layers "F.Cu" "F.Mask" "F.Paste")
			(net "GND")
			(options
				(clearance outline)
				(anchor circle)
			)
			(primitives
				(gr_poly
					(pts
						(arc
							(start -0.1778 -0.2794)
							(mid -0.249642 -0.249642)
							(end -0.2794 -0.1778)
						)
						(arc
							(start -0.2794 0.1778)
							(mid -0.249642 0.249642)
							(end -0.1778 0.2794)
						)
						(arc
							(start 0.1778 0.2794)
							(mid 0.249642 0.249642)
							(end 0.2794 0.1778)
						)
						(arc
							(start 0.2794 -0.1778)
							(mid 0.249642 -0.249642)
							(end 0.1778 -0.2794)
						)
					)
					(width 0)
					(fill yes)
				)
			)
		)
	)
	(footprint ""
		(layer "F.Cu")
		(at 6.999986 -25.584912 -90)
		(property "Reference" "H1"
			(at 0 0 270)
			(layer "F.SilkS")
			(hide yes)
			(effects
				(font
					(size 1.27 1.27)
				)
			)
		)
		(property "Value" "STFT363B238R224H453-GP"
			(at 7.0612 1.4605 270)
			(unlocked yes)
			(layer "F.Fab")
			(hide yes)
			(effects
				(font
					(size 1.016 1.016)
					(thickness 0.1524)
				)
			)
		)
		(property "Device Type" "STFT363B238R224H453"
			(at 7.0612 -0.0635 270)
			(unlocked yes)
			(layer "F.Fab")
			(hide yes)
			(effects
				(font
					(size 1.016 1.016)
					(thickness 0.1524)
				)
			)
		)
		(duplicate_pad_numbers_are_jumpers no)
		(fp_circle
			(center 0 0)
			(end 0 -5.3594)
			(stroke
				(width 0.3048)
				(type default)
			)
			(fill no)
			(layer "F.SilkS")
		)
		(fp_poly
			(pts
				(arc
					(start 0 -3.5306)
					(mid 0 3.5306)
					(end 0 -3.5306)
				)
			)
			(stroke
				(width 0)
				(type default)
			)
			(fill no)
			(layer "B.CrtYd")
		)
		(fp_poly
			(pts
				(arc
					(start 0 -5.0038)
					(mid 0 5.0038)
					(end 0 -5.0038)
				)
			)
			(stroke
				(width 0)
				(type default)
			)
			(fill no)
			(layer "F.CrtYd")
		)
		(fp_poly
			(pts
				(arc
					(start 5.5118 0.00635)
					(mid -5.511804 0)
					(end 5.5118 -0.00635)
				)
				(arc
					(start 5.0038 -0.00635)
					(mid -5.003804 0)
					(end 5.0038 0.00635)
				)
			)
			(stroke
				(width 0)
				(type default)
			)
			(fill no)
			(layer "F.CrtYd")
		)
		(fp_poly
			(pts
				(arc
					(start 0 -3.5306)
					(mid 0 3.5306)
					(end 0 -3.5306)
				)
			)
			(stroke
				(width 0)
				(type default)
			)
			(fill no)
			(layer "B.Fab")
		)
		(fp_poly
			(pts
				(arc
					(start 0 -5.5118)
					(mid 0 5.5118)
					(end 0 -5.5118)
				)
			)
			(stroke
				(width 0)
				(type default)
			)
			(fill no)
			(layer "F.Fab")
		)
		(pad "1" thru_hole circle
			(at 0 0 270)
			(size 9.2202 9.2202)
			(drill 5.6896)
			(layers "*.Cu" "*.Mask")
			(remove_unused_layers no)
			(net "GND")
			(clearance -1.2573)
			(thermal_gap 0.3302)
			(padstack
				(mode front_inner_back)
				(layer "Inner"
					(shape circle)
					(size 6.0452 6.0452)
					(clearance 0.3302)
				)
				(layer "B.Cu"
					(shape circle)
					(size 6.0452 6.0452)
					(clearance 0.3302)
				)
			)
		)
	)
	(footprint ""
		(layer "F.Cu")
		(at 17.1958 -24.003 90)
		(property "Reference" "R87"
			(at 0 0 90)
			(layer "F.SilkS")
			(hide yes)
			(effects
				(font
					(size 1.27 1.27)
				)
			)
		)
		(property "Value" "10R2F-L-GP"
			(at 0.064008 -3.993896 90)
			(unlocked yes)
			(layer "F.Fab")
			(hide yes)
			(effects
				(font
					(size 1.016 1.016)
					(thickness 0.1524)
				)
			)
		)
		(property "Device Type" "R402H14"
			(at 0.064008 -5.517896 90)
			(unlocked yes)
			(layer "F.Fab")
			(hide yes)
			(effects
				(font
					(size 1.016 1.016)
					(thickness 0.1524)
				)
			)
		)
		(duplicate_pad_numbers_are_jumpers no)
		(fp_line
			(start 0.508 -0.9398)
			(end -0.508 -0.9398)
			(stroke
				(width 0.1524)
				(type default)
			)
			(layer "F.SilkS")
		)
		(fp_line
			(start -0.508 -0.9398)
			(end -0.508 0.9398)
			(stroke
				(width 0.1524)
				(type default)
			)
			(layer "F.SilkS")
		)
		(fp_rect
			(start -0.508 0.9398)
			(end 0.508 -0.9398)
			(stroke
				(width 0)
				(type default)
			)
			(fill no)
			(layer "F.CrtYd")
		)
		(fp_rect
			(start -0.508 0.9398)
			(end 0.508 -0.9398)
			(stroke
				(width 0)
				(type default)
			)
			(fill no)
			(layer "F.Fab")
		)
		(pad "1" smd custom
			(at 0 -0.4445 90)
			(size 0.1397 0.1397)
			(layers "F.Cu" "F.Mask" "F.Paste")
			(net "P12V_SLOT3")
			(options
				(clearance outline)
				(anchor circle)
			)
			(primitives
				(gr_poly
					(pts
						(arc
							(start -0.1778 -0.2794)
							(mid -0.249642 -0.249642)
							(end -0.2794 -0.1778)
						)
						(arc
							(start -0.2794 0.1778)
							(mid -0.249642 0.249642)
							(end -0.1778 0.2794)
						)
						(arc
							(start 0.1778 0.2794)
							(mid 0.249642 0.249642)
							(end 0.2794 0.1778)
						)
						(arc
							(start 0.2794 -0.1778)
							(mid 0.249642 -0.249642)
							(end 0.1778 -0.2794)
						)
					)
					(width 0)
					(fill yes)
				)
			)
		)
		(pad "2" smd custom
			(at 0 0.4445 90)
			(size 0.1397 0.1397)
			(layers "F.Cu" "F.Mask" "F.Paste")
			(net "SLOT3_P12V_SENSE_VN_R")
			(options
				(clearance outline)
				(anchor circle)
			)
			(primitives
				(gr_poly
					(pts
						(arc
							(start -0.1778 -0.2794)
							(mid -0.249642 -0.249642)
							(end -0.2794 -0.1778)
						)
						(arc
							(start -0.2794 0.1778)
							(mid -0.249642 0.249642)
							(end -0.1778 0.2794)
						)
						(arc
							(start 0.1778 0.2794)
							(mid 0.249642 0.249642)
							(end 0.2794 0.1778)
						)
						(arc
							(start 0.2794 -0.1778)
							(mid 0.249642 -0.249642)
							(end 0.1778 -0.2794)
						)
					)
					(width 0)
					(fill yes)
				)
			)
		)
	)
	(footprint ""
		(layer "F.Cu")
		(at 22.2504 -27.0002 -90)
		(property "Reference" "U15"
			(at 0 0 270)
			(layer "F.SilkS")
			(hide yes)
			(effects
				(font
					(size 1.27 1.27)
				)
			)
		)
		(property "Value" "INA230AIRGTR-GP"
			(at -5.6388 -6.1468 270)
			(unlocked yes)
			(layer "F.Fab")
			(hide yes)
			(effects
				(font
					(size 1.016 1.016)
					(thickness 0.1524)
				)
			)
		)
		(property "Device Type" "QFN16-G1D8-UH40"
			(at -5.6388 -7.6708 270)
			(unlocked yes)
			(layer "F.Fab")
			(hide yes)
			(effects
				(font
					(size 1.016 1.016)
					(thickness 0.1524)
				)
			)
		)
		(duplicate_pad_numbers_are_jumpers no)
		(fp_line
			(start -2.5146 2.5146)
			(end -1.2446 2.5146)
			(stroke
				(width 0.1524)
				(type default)
			)
			(layer "F.SilkS")
		)
		(fp_line
			(start 1.2446 2.5146)
			(end 2.5146 2.5146)
			(stroke
				(width 0.1524)
				(type default)
			)
			(layer "F.SilkS")
		)
		(fp_line
			(start 2.5146 2.5146)
			(end 2.5146 1.2446)
			(stroke
				(width 0.1524)
				(type default)
			)
			(layer "F.SilkS")
		)
		(fp_line
			(start -0.248666 2.287524)
			(end -0.248666 3.049524)
			(stroke
				(width 0.1524)
				(type default)
			)
			(layer "F.SilkS")
		)
		(fp_line
			(start -2.5146 1.2446)
			(end -2.5146 2.5146)
			(stroke
				(width 0.1524)
				(type default)
			)
			(layer "F.SilkS")
		)
		(fp_line
			(start 2.287524 -0.260604)
			(end 2.795524 -0.260604)
			(stroke
				(width 0.1524)
				(type default)
			)
			(layer "F.SilkS")
		)
		(fp_line
			(start -2.287524 -0.753364)
			(end -2.795524 -0.753364)
			(stroke
				(width 0.1524)
				(type default)
			)
			(layer "F.SilkS")
		)
		(fp_line
			(start -2.5146 -2.5146)
			(end -2.5146 -1.2446)
			(stroke
				(width 0.1524)
				(type default)
			)
			(layer "F.SilkS")
		)
		(fp_line
			(start -1.2446 -2.5146)
			(end -2.5146 -2.5146)
			(stroke
				(width 0.1524)
				(type default)
			)
			(layer "F.SilkS")
		)
		(fp_poly
			(pts
				(xy 1.2446 -2.5146) (xy 2.5146 -2.5146) (xy 2.5146 -1.2446)
			)
			(stroke
				(width 0)
				(type default)
			)
			(fill yes)
			(layer "F.SilkS")
		)
		(fp_rect
			(start -1.4986 1.4986)
			(end 1.4986 -1.4986)
			(stroke
				(width 0)
				(type default)
			)
			(fill no)
			(layer "F.CrtYd")
		)
		(fp_poly
			(pts
				(xy -1.4986 -1.4986) (xy -2.5146 -1.4986) (xy -2.5146 -2.5146) (xy 2.5146 -2.5146) (xy 2.5146 2.5146)
				(xy -2.5146 2.5146) (xy -2.5146 -1.4859) (xy -1.4986 -1.4859) (xy -1.4986 1.4986) (xy 1.4986 1.4986)
				(xy 1.4986 -1.4986)
			)
			(stroke
				(width 0)
				(type default)
			)
			(fill no)
			(layer "F.CrtYd")
		)
		(fp_rect
			(start -2.5146 2.5146)
			(end 2.5146 -2.5146)
			(stroke
				(width 0)
				(type default)
			)
			(fill no)
			(layer "F.Fab")
		)
		(pad "1" smd rect
			(at 0.750062 -1.550924 270)
			(size 0.3048 0.9144)
			(layers "F.Cu" "F.Mask" "F.Paste")
			(net "SLOT3_VMONITOR_A1")
		)
		(pad "2" smd rect
			(at 0.249936 -1.550924 270)
			(size 0.3048 0.9144)
			(layers "F.Cu" "F.Mask" "F.Paste")
			(net "SLOT3_VMONITOR_A0")
		)
		(pad "3" smd rect
			(at -0.249936 -1.550924 270)
			(size 0.3048 0.9144)
			(layers "F.Cu" "F.Mask" "F.Paste")
			(net "SMB_VMONITOR_SLOT3_ALERT_N")
		)
		(pad "4" smd rect
			(at -0.750062 -1.550924 270)
			(size 0.3048 0.9144)
			(layers "F.Cu" "F.Mask" "F.Paste")
			(net "SMB_VMONITOR_SLOT3_MUX_SDA")
		)
		(pad "5" smd rect
			(at -1.550924 -0.750062 270)
			(size 0.9144 0.3048)
			(layers "F.Cu" "F.Mask" "F.Paste")
			(net "SMB_VMONITOR_SLOT3_MUX_SCL")
		)
		(pad "6" smd rect
			(at -1.550924 -0.249936 270)
			(size 0.9144 0.3048)
			(layers "F.Cu" "F.Mask" "F.Paste")
			(net "Net_220")
		)
		(pad "7" smd rect
			(at -1.550924 0.249936 270)
			(size 0.9144 0.3048)
			(layers "F.Cu" "F.Mask" "F.Paste")
			(net "Net_221")
		)
		(pad "8" smd rect
			(at -1.550924 0.750062 270)
			(size 0.9144 0.3048)
			(layers "F.Cu" "F.Mask" "F.Paste")
			(net "Net_222")
		)
		(pad "9" smd rect
			(at -0.750062 1.550924 270)
			(size 0.3048 0.9144)
			(layers "F.Cu" "F.Mask" "F.Paste")
			(net "P3V3_STBY")
		)
		(pad "10" smd rect
			(at -0.249936 1.550924 270)
			(size 0.3048 0.9144)
			(layers "F.Cu" "F.Mask" "F.Paste")
			(net "GND")
		)
		(pad "11" smd rect
			(at 0.249936 1.550924 270)
			(size 0.3048 0.9144)
			(layers "F.Cu" "F.Mask" "F.Paste")
			(net "P12V")
		)
		(pad "12" smd rect
			(at 0.750062 1.550924 270)
			(size 0.3048 0.9144)
			(layers "F.Cu" "F.Mask" "F.Paste")
			(net "SLOT3_P12V_SENSE_VN_R")
		)
		(pad "13" smd rect
			(at 1.550924 0.750062 270)
			(size 0.9144 0.3048)
			(layers "F.Cu" "F.Mask" "F.Paste")
			(net "SLOT3_P12V_SENSE_VP_R")
		)
		(pad "14" smd rect
			(at 1.550924 0.249936 270)
			(size 0.9144 0.3048)
			(layers "F.Cu" "F.Mask" "F.Paste")
			(net "Net_217")
		)
		(pad "15" smd rect
			(at 1.550924 -0.249936 270)
			(size 0.9144 0.3048)
			(layers "F.Cu" "F.Mask" "F.Paste")
			(net "Net_218")
		)
		(pad "16" smd rect
			(at 1.550924 -0.750062 270)
			(size 0.9144 0.3048)
			(layers "F.Cu" "F.Mask" "F.Paste")
			(net "Net_219")
		)
		(pad "17" smd rect
			(at 0 0 270)
			(size 1.778 1.778)
			(layers "F.Cu" "F.Mask" "F.Paste")
			(net "GND")
		)
	)
	(footprint ""
		(layer "F.Cu")
		(at 123.9266 -0.0508 180)
		(property "Reference" "R140"
			(at 0 0 180)
			(layer "F.SilkS")
			(hide yes)
			(effects
				(font
					(size 1.27 1.27)
				)
			)
		)
		(property "Value" "10KR2F-2-GP"
			(at 0.064008 -3.993896 180)
			(unlocked yes)
			(layer "F.Fab")
			(hide yes)
			(effects
				(font
					(size 1.016 1.016)
					(thickness 0.1524)
				)
			)
		)
		(property "Device Type" "R402H16"
			(at 0.064008 -5.517896 180)
			(unlocked yes)
			(layer "F.Fab")
			(hide yes)
			(effects
				(font
					(size 1.016 1.016)
					(thickness 0.1524)
				)
			)
		)
		(duplicate_pad_numbers_are_jumpers no)
		(fp_line
			(start 0.508 -0.9398)
			(end -0.508 -0.9398)
			(stroke
				(width 0.1524)
				(type default)
			)
			(layer "F.SilkS")
		)
		(fp_line
			(start -0.508 -0.9398)
			(end -0.508 0.9398)
			(stroke
				(width 0.1524)
				(type default)
			)
			(layer "F.SilkS")
		)
		(fp_rect
			(start -0.508 0.9398)
			(end 0.508 -0.9398)
			(stroke
				(width 0)
				(type default)
			)
			(fill no)
			(layer "F.CrtYd")
		)
		(fp_rect
			(start -0.508 0.9398)
			(end 0.508 -0.9398)
			(stroke
				(width 0)
				(type default)
			)
			(fill no)
			(layer "F.Fab")
		)
		(pad "1" smd custom
			(at 0 -0.4445 180)
			(size 0.1397 0.1397)
			(layers "F.Cu" "F.Mask" "F.Paste")
			(net "P3V3_STBY")
			(options
				(clearance outline)
				(anchor circle)
			)
			(primitives
				(gr_poly
					(pts
						(arc
							(start -0.1778 -0.2794)
							(mid -0.249642 -0.249642)
							(end -0.2794 -0.1778)
						)
						(arc
							(start -0.2794 0.1778)
							(mid -0.249642 0.249642)
							(end -0.1778 0.2794)
						)
						(arc
							(start 0.1778 0.2794)
							(mid 0.249642 0.249642)
							(end 0.2794 0.1778)
						)
						(arc
							(start 0.2794 -0.1778)
							(mid 0.249642 -0.249642)
							(end 0.1778 -0.2794)
						)
					)
					(width 0)
					(fill yes)
				)
			)
		)
		(pad "2" smd custom
			(at 0 0.4445 180)
			(size 0.1397 0.1397)
			(layers "F.Cu" "F.Mask" "F.Paste")
			(net "GPIO_P_IO1_5")
			(options
				(clearance outline)
				(anchor circle)
			)
			(primitives
				(gr_poly
					(pts
						(arc
							(start -0.1778 -0.2794)
							(mid -0.249642 -0.249642)
							(end -0.2794 -0.1778)
						)
						(arc
							(start -0.2794 0.1778)
							(mid -0.249642 0.249642)
							(end -0.1778 0.2794)
						)
						(arc
							(start 0.1778 0.2794)
							(mid 0.249642 0.249642)
							(end 0.2794 0.1778)
						)
						(arc
							(start 0.2794 -0.1778)
							(mid 0.249642 -0.249642)
							(end 0.1778 -0.2794)
						)
					)
					(width 0)
					(fill yes)
				)
			)
		)
	)
	(footprint ""
		(layer "F.Cu")
		(at 38.6588 -1.8288 90)
		(property "Reference" "C797"
			(at 0 0 90)
			(layer "F.SilkS")
			(hide yes)
			(effects
				(font
					(size 1.27 1.27)
				)
			)
		)
		(property "Value" "SC22U6D3V5MX-5-GP"
			(at -0.0762 -6.1214 90)
			(unlocked yes)
			(layer "F.Fab")
			(hide yes)
			(effects
				(font
					(size 1.016 1.016)
					(thickness 0.1524)
				)
			)
		)
		(property "Device Type" "C805H56"
			(at -0.0762 -8.1534 90)
			(unlocked yes)
			(layer "F.Fab")
			(hide yes)
			(effects
				(font
					(size 1.016 1.016)
					(thickness 0.1524)
				)
			)
		)
		(duplicate_pad_numbers_are_jumpers no)
		(fp_line
			(start 0.635 0)
			(end -0.635 0)
			(stroke
				(width 0.508)
				(type default)
			)
			(layer "F.SilkS")
		)
		(fp_rect
			(start -0.9652 1.778)
			(end 0.9652 -1.778)
			(stroke
				(width 0)
				(type default)
			)
			(fill no)
			(layer "F.CrtYd")
		)
		(fp_poly
			(pts
				(xy -0.9652 -1.778) (xy 0.9652 -1.778) (xy 0.9652 1.778) (xy -0.9652 1.778)
			)
			(stroke
				(width 0)
				(type default)
			)
			(fill no)
			(layer "F.Fab")
		)
		(pad "1" smd rect
			(at 0 -0.9652 90)
			(size 1.397 1.143)
			(layers "F.Cu" "F.Mask" "F.Paste")
			(net "P3V3")
		)
		(pad "2" smd rect
			(at 0 0.9652 90)
			(size 1.397 1.143)
			(layers "F.Cu" "F.Mask" "F.Paste")
			(net "GND")
		)
	)
	(footprint ""
		(layer "F.Cu")
		(at 118.8212 -31.2674 90)
		(property "Reference" "RU27"
			(at 0 0 90)
			(layer "F.SilkS")
			(hide yes)
			(effects
				(font
					(size 1.27 1.27)
				)
			)
		)
		(property "Value" "10KR2F-2-GP"
			(at 0.064008 -3.993896 90)
			(unlocked yes)
			(layer "F.Fab")
			(hide yes)
			(effects
				(font
					(size 1.016 1.016)
					(thickness 0.1524)
				)
			)
		)
		(property "Device Type" "R402H16"
			(at 0.064008 -5.517896 90)
			(unlocked yes)
			(layer "F.Fab")
			(hide yes)
			(effects
				(font
					(size 1.016 1.016)
					(thickness 0.1524)
				)
			)
		)
		(duplicate_pad_numbers_are_jumpers no)
		(fp_line
			(start 0.508 -0.9398)
			(end -0.508 -0.9398)
			(stroke
				(width 0.1524)
				(type default)
			)
			(layer "F.SilkS")
		)
		(fp_line
			(start -0.508 -0.9398)
			(end -0.508 0.9398)
			(stroke
				(width 0.1524)
				(type default)
			)
			(layer "F.SilkS")
		)
		(fp_rect
			(start -0.508 0.9398)
			(end 0.508 -0.9398)
			(stroke
				(width 0)
				(type default)
			)
			(fill no)
			(layer "F.CrtYd")
		)
		(fp_rect
			(start -0.508 0.9398)
			(end 0.508 -0.9398)
			(stroke
				(width 0)
				(type default)
			)
			(fill no)
			(layer "F.Fab")
		)
		(pad "1" smd custom
			(at 0 -0.4445 90)
			(size 0.1397 0.1397)
			(layers "F.Cu" "F.Mask" "F.Paste")
			(net "P3V3_USB_HUB")
			(options
				(clearance outline)
				(anchor circle)
			)
			(primitives
				(gr_poly
					(pts
						(arc
							(start -0.1778 -0.2794)
							(mid -0.249642 -0.249642)
							(end -0.2794 -0.1778)
						)
						(arc
							(start -0.2794 0.1778)
							(mid -0.249642 0.249642)
							(end -0.1778 0.2794)
						)
						(arc
							(start 0.1778 0.2794)
							(mid 0.249642 0.249642)
							(end 0.2794 0.1778)
						)
						(arc
							(start 0.2794 -0.1778)
							(mid 0.249642 -0.249642)
							(end 0.1778 -0.2794)
						)
					)
					(width 0)
					(fill yes)
				)
			)
		)
		(pad "2" smd custom
			(at 0 0.4445 90)
			(size 0.1397 0.1397)
			(layers "F.Cu" "F.Mask" "F.Paste")
			(net "TP_USB_DN3")
			(options
				(clearance outline)
				(anchor circle)
			)
			(primitives
				(gr_poly
					(pts
						(arc
							(start -0.1778 -0.2794)
							(mid -0.249642 -0.249642)
							(end -0.2794 -0.1778)
						)
						(arc
							(start -0.2794 0.1778)
							(mid -0.249642 0.249642)
							(end -0.1778 0.2794)
						)
						(arc
							(start 0.1778 0.2794)
							(mid 0.249642 0.249642)
							(end 0.2794 0.1778)
						)
						(arc
							(start 0.2794 -0.1778)
							(mid 0.249642 -0.249642)
							(end 0.1778 -0.2794)
						)
					)
					(width 0)
					(fill yes)
				)
			)
		)
	)
	(footprint ""
		(layer "F.Cu")
		(at 130.2512 -10.7696)
		(property "Reference" "R121"
			(at 0 0 0)
			(layer "F.SilkS")
			(hide yes)
			(effects
				(font
					(size 1.27 1.27)
				)
			)
		)
		(property "Value" "10KR2F-2-GP"
			(at 0.064008 -3.993896 0)
			(unlocked yes)
			(layer "F.Fab")
			(hide yes)
			(effects
				(font
					(size 1.016 1.016)
					(thickness 0.1524)
				)
			)
		)
		(property "Device Type" "R402H16"
			(at 0.064008 -5.517896 0)
			(unlocked yes)
			(layer "F.Fab")
			(hide yes)
			(effects
				(font
					(size 1.016 1.016)
					(thickness 0.1524)
				)
			)
		)
		(duplicate_pad_numbers_are_jumpers no)
		(fp_line
			(start -0.508 -0.9398)
			(end -0.508 0.9398)
			(stroke
				(width 0.1524)
				(type default)
			)
			(layer "F.SilkS")
		)
		(fp_line
			(start 0.508 -0.9398)
			(end -0.508 -0.9398)
			(stroke
				(width 0.1524)
				(type default)
			)
			(layer "F.SilkS")
		)
		(fp_rect
			(start -0.508 0.9398)
			(end 0.508 -0.9398)
			(stroke
				(width 0)
				(type default)
			)
			(fill no)
			(layer "F.CrtYd")
		)
		(fp_rect
			(start -0.508 0.9398)
			(end 0.508 -0.9398)
			(stroke
				(width 0)
				(type default)
			)
			(fill no)
			(layer "F.Fab")
		)
		(pad "1" smd custom
			(at 0 -0.4445)
			(size 0.1397 0.1397)
			(layers "F.Cu" "F.Mask" "F.Paste")
			(net "GPIO_B_IO1_0")
			(options
				(clearance outline)
				(anchor circle)
			)
			(primitives
				(gr_poly
					(pts
						(arc
							(start -0.1778 -0.2794)
							(mid -0.249642 -0.249642)
							(end -0.2794 -0.1778)
						)
						(arc
							(start -0.2794 0.1778)
							(mid -0.249642 0.249642)
							(end -0.1778 0.2794)
						)
						(arc
							(start 0.1778 0.2794)
							(mid 0.249642 0.249642)
							(end 0.2794 0.1778)
						)
						(arc
							(start 0.2794 -0.1778)
							(mid 0.249642 -0.249642)
							(end 0.1778 -0.2794)
						)
					)
					(width 0)
					(fill yes)
				)
			)
		)
		(pad "2" smd custom
			(at 0 0.4445)
			(size 0.1397 0.1397)
			(layers "F.Cu" "F.Mask" "F.Paste")
			(net "GND")
			(options
				(clearance outline)
				(anchor circle)
			)
			(primitives
				(gr_poly
					(pts
						(arc
							(start -0.1778 -0.2794)
							(mid -0.249642 -0.249642)
							(end -0.2794 -0.1778)
						)
						(arc
							(start -0.2794 0.1778)
							(mid -0.249642 0.249642)
							(end -0.1778 0.2794)
						)
						(arc
							(start 0.1778 0.2794)
							(mid 0.249642 0.249642)
							(end 0.2794 0.1778)
						)
						(arc
							(start 0.2794 -0.1778)
							(mid 0.249642 -0.249642)
							(end 0.1778 -0.2794)
						)
					)
					(width 0)
					(fill yes)
				)
			)
		)
	)
	(footprint ""
		(layer "F.Cu")
		(at 126.4412 0.1524 90)
		(property "Reference" "R154"
			(at 0 0 90)
			(layer "F.SilkS")
			(hide yes)
			(effects
				(font
					(size 1.27 1.27)
				)
			)
		)
		(property "Value" "10KR2F-2-GP"
			(at 0.064008 -3.993896 90)
			(unlocked yes)
			(layer "F.Fab")
			(hide yes)
			(effects
				(font
					(size 1.016 1.016)
					(thickness 0.1524)
				)
			)
		)
		(property "Device Type" "R402H16"
			(at 0.064008 -5.517896 90)
			(unlocked yes)
			(layer "F.Fab")
			(hide yes)
			(effects
				(font
					(size 1.016 1.016)
					(thickness 0.1524)
				)
			)
		)
		(duplicate_pad_numbers_are_jumpers no)
		(fp_line
			(start 0.508 -0.9398)
			(end -0.508 -0.9398)
			(stroke
				(width 0.1524)
				(type default)
			)
			(layer "F.SilkS")
		)
		(fp_line
			(start -0.508 -0.9398)
			(end -0.508 0.9398)
			(stroke
				(width 0.1524)
				(type default)
			)
			(layer "F.SilkS")
		)
		(fp_rect
			(start -0.508 0.9398)
			(end 0.508 -0.9398)
			(stroke
				(width 0)
				(type default)
			)
			(fill no)
			(layer "F.CrtYd")
		)
		(fp_rect
			(start -0.508 0.9398)
			(end 0.508 -0.9398)
			(stroke
				(width 0)
				(type default)
			)
			(fill no)
			(layer "F.Fab")
		)
		(pad "1" smd custom
			(at 0 -0.4445 90)
			(size 0.1397 0.1397)
			(layers "F.Cu" "F.Mask" "F.Paste")
			(net "GPIO_P_IO1_7")
			(options
				(clearance outline)
				(anchor circle)
			)
			(primitives
				(gr_poly
					(pts
						(arc
							(start -0.1778 -0.2794)
							(mid -0.249642 -0.249642)
							(end -0.2794 -0.1778)
						)
						(arc
							(start -0.2794 0.1778)
							(mid -0.249642 0.249642)
							(end -0.1778 0.2794)
						)
						(arc
							(start 0.1778 0.2794)
							(mid 0.249642 0.249642)
							(end 0.2794 0.1778)
						)
						(arc
							(start 0.2794 -0.1778)
							(mid 0.249642 -0.249642)
							(end 0.1778 -0.2794)
						)
					)
					(width 0)
					(fill yes)
				)
			)
		)
		(pad "2" smd custom
			(at 0 0.4445 90)
			(size 0.1397 0.1397)
			(layers "F.Cu" "F.Mask" "F.Paste")
			(net "GND")
			(options
				(clearance outline)
				(anchor circle)
			)
			(primitives
				(gr_poly
					(pts
						(arc
							(start -0.1778 -0.2794)
							(mid -0.249642 -0.249642)
							(end -0.2794 -0.1778)
						)
						(arc
							(start -0.2794 0.1778)
							(mid -0.249642 0.249642)
							(end -0.1778 0.2794)
						)
						(arc
							(start 0.1778 0.2794)
							(mid 0.249642 0.249642)
							(end 0.2794 0.1778)
						)
						(arc
							(start 0.2794 -0.1778)
							(mid 0.249642 -0.249642)
							(end 0.1778 -0.2794)
						)
					)
					(width 0)
					(fill yes)
				)
			)
		)
	)
	(footprint ""
		(layer "F.Cu")
		(at 98.5012 -18.8214 180)
		(property "Reference" "R98"
			(at 0 0 180)
			(layer "F.SilkS")
			(hide yes)
			(effects
				(font
					(size 1.27 1.27)
				)
			)
		)
		(property "Value" "0R2F-1-GP"
			(at 0.064008 -3.993896 180)
			(unlocked yes)
			(layer "F.Fab")
			(hide yes)
			(effects
				(font
					(size 1.016 1.016)
					(thickness 0.1524)
				)
			)
		)
		(property "Device Type" "R402H16"
			(at 0.064008 -5.517896 180)
			(unlocked yes)
			(layer "F.Fab")
			(hide yes)
			(effects
				(font
					(size 1.016 1.016)
					(thickness 0.1524)
				)
			)
		)
		(duplicate_pad_numbers_are_jumpers no)
		(fp_line
			(start 0.508 -0.9398)
			(end -0.508 -0.9398)
			(stroke
				(width 0.1524)
				(type default)
			)
			(layer "F.SilkS")
		)
		(fp_line
			(start -0.508 -0.9398)
			(end -0.508 0.9398)
			(stroke
				(width 0.1524)
				(type default)
			)
			(layer "F.SilkS")
		)
		(fp_rect
			(start -0.508 0.9398)
			(end 0.508 -0.9398)
			(stroke
				(width 0)
				(type default)
			)
			(fill no)
			(layer "F.CrtYd")
		)
		(fp_rect
			(start -0.508 0.9398)
			(end 0.508 -0.9398)
			(stroke
				(width 0)
				(type default)
			)
			(fill no)
			(layer "F.Fab")
		)
		(pad "1" smd custom
			(at 0 -0.4445 180)
			(size 0.1397 0.1397)
			(layers "F.Cu" "F.Mask" "F.Paste")
			(net "P3V3_PG")
			(options
				(clearance outline)
				(anchor circle)
			)
			(primitives
				(gr_poly
					(pts
						(arc
							(start -0.1778 -0.2794)
							(mid -0.249642 -0.249642)
							(end -0.2794 -0.1778)
						)
						(arc
							(start -0.2794 0.1778)
							(mid -0.249642 0.249642)
							(end -0.1778 0.2794)
						)
						(arc
							(start 0.1778 0.2794)
							(mid 0.249642 0.249642)
							(end 0.2794 0.1778)
						)
						(arc
							(start 0.2794 -0.1778)
							(mid 0.249642 -0.249642)
							(end 0.1778 -0.2794)
						)
					)
					(width 0)
					(fill yes)
				)
			)
		)
		(pad "2" smd custom
			(at 0 0.4445 180)
			(size 0.1397 0.1397)
			(layers "F.Cu" "F.Mask" "F.Paste")
			(net "RESET_O_2_R")
			(options
				(clearance outline)
				(anchor circle)
			)
			(primitives
				(gr_poly
					(pts
						(arc
							(start -0.1778 -0.2794)
							(mid -0.249642 -0.249642)
							(end -0.2794 -0.1778)
						)
						(arc
							(start -0.2794 0.1778)
							(mid -0.249642 0.249642)
							(end -0.1778 0.2794)
						)
						(arc
							(start 0.1778 0.2794)
							(mid 0.249642 0.249642)
							(end 0.2794 0.1778)
						)
						(arc
							(start 0.2794 -0.1778)
							(mid 0.249642 -0.249642)
							(end 0.1778 -0.2794)
						)
					)
					(width 0)
					(fill yes)
				)
			)
		)
	)
	(footprint ""
		(layer "F.Cu")
		(at 99.3902 5.0038 90)
		(property "Reference" "R119"
			(at 0 0 90)
			(layer "F.SilkS")
			(hide yes)
			(effects
				(font
					(size 1.27 1.27)
				)
			)
		)
		(property "Value" "100R2F-L1-GP-U"
			(at 0.064008 -3.993896 90)
			(unlocked yes)
			(layer "F.Fab")
			(hide yes)
			(effects
				(font
					(size 1.016 1.016)
					(thickness 0.1524)
				)
			)
		)
		(property "Device Type" "R402H14"
			(at 0.064008 -5.517896 90)
			(unlocked yes)
			(layer "F.Fab")
			(hide yes)
			(effects
				(font
					(size 1.016 1.016)
					(thickness 0.1524)
				)
			)
		)
		(duplicate_pad_numbers_are_jumpers no)
		(fp_line
			(start 0.508 -0.9398)
			(end -0.508 -0.9398)
			(stroke
				(width 0.1524)
				(type default)
			)
			(layer "F.SilkS")
		)
		(fp_line
			(start -0.508 -0.9398)
			(end -0.508 0.9398)
			(stroke
				(width 0.1524)
				(type default)
			)
			(layer "F.SilkS")
		)
		(fp_rect
			(start -0.508 0.9398)
			(end 0.508 -0.9398)
			(stroke
				(width 0)
				(type default)
			)
			(fill no)
			(layer "F.CrtYd")
		)
		(fp_rect
			(start -0.508 0.9398)
			(end 0.508 -0.9398)
			(stroke
				(width 0)
				(type default)
			)
			(fill no)
			(layer "F.Fab")
		)
		(pad "1" smd custom
			(at 0 -0.4445 90)
			(size 0.1397 0.1397)
			(layers "F.Cu" "F.Mask" "F.Paste")
			(net "FM_PRSNT_2_6_N")
			(options
				(clearance outline)
				(anchor circle)
			)
			(primitives
				(gr_poly
					(pts
						(arc
							(start -0.1778 -0.2794)
							(mid -0.249642 -0.249642)
							(end -0.2794 -0.1778)
						)
						(arc
							(start -0.2794 0.1778)
							(mid -0.249642 0.249642)
							(end -0.1778 0.2794)
						)
						(arc
							(start 0.1778 0.2794)
							(mid 0.249642 0.249642)
							(end 0.2794 0.1778)
						)
						(arc
							(start 0.2794 -0.1778)
							(mid 0.249642 -0.249642)
							(end 0.1778 -0.2794)
						)
					)
					(width 0)
					(fill yes)
				)
			)
		)
		(pad "2" smd custom
			(at 0 0.4445 90)
			(size 0.1397 0.1397)
			(layers "F.Cu" "F.Mask" "F.Paste")
			(net "GND")
			(options
				(clearance outline)
				(anchor circle)
			)
			(primitives
				(gr_poly
					(pts
						(arc
							(start -0.1778 -0.2794)
							(mid -0.249642 -0.249642)
							(end -0.2794 -0.1778)
						)
						(arc
							(start -0.2794 0.1778)
							(mid -0.249642 0.249642)
							(end -0.1778 0.2794)
						)
						(arc
							(start 0.1778 0.2794)
							(mid 0.249642 0.249642)
							(end 0.2794 0.1778)
						)
						(arc
							(start 0.2794 -0.1778)
							(mid 0.249642 -0.249642)
							(end 0.1778 -0.2794)
						)
					)
					(width 0)
					(fill yes)
				)
			)
		)
	)
	(footprint ""
		(layer "F.Cu")
		(at 119.1514 -19.1516 -90)
		(property "Reference" "R117"
			(at 0 0 270)
			(layer "F.SilkS")
			(hide yes)
			(effects
				(font
					(size 1.27 1.27)
				)
			)
		)
		(property "Value" "10KR2F-2-GP"
			(at 0.064008 -3.993896 270)
			(unlocked yes)
			(layer "F.Fab")
			(hide yes)
			(effects
				(font
					(size 1.016 1.016)
					(thickness 0.1524)
				)
			)
		)
		(property "Device Type" "R402H16"
			(at 0.064008 -5.517896 270)
			(unlocked yes)
			(layer "F.Fab")
			(hide yes)
			(effects
				(font
					(size 1.016 1.016)
					(thickness 0.1524)
				)
			)
		)
		(duplicate_pad_numbers_are_jumpers no)
		(fp_line
			(start -0.508 -0.9398)
			(end -0.508 0.9398)
			(stroke
				(width 0.1524)
				(type default)
			)
			(layer "F.SilkS")
		)
		(fp_line
			(start 0.508 -0.9398)
			(end -0.508 -0.9398)
			(stroke
				(width 0.1524)
				(type default)
			)
			(layer "F.SilkS")
		)
		(fp_rect
			(start -0.508 0.9398)
			(end 0.508 -0.9398)
			(stroke
				(width 0)
				(type default)
			)
			(fill no)
			(layer "F.CrtYd")
		)
		(fp_rect
			(start -0.508 0.9398)
			(end 0.508 -0.9398)
			(stroke
				(width 0)
				(type default)
			)
			(fill no)
			(layer "F.Fab")
		)
		(pad "1" smd custom
			(at 0 -0.4445 270)
			(size 0.1397 0.1397)
			(layers "F.Cu" "F.Mask" "F.Paste")
			(net "GPIO_B_EXP_A1")
			(options
				(clearance outline)
				(anchor circle)
			)
			(primitives
				(gr_poly
					(pts
						(arc
							(start -0.1778 -0.2794)
							(mid -0.249642 -0.249642)
							(end -0.2794 -0.1778)
						)
						(arc
							(start -0.2794 0.1778)
							(mid -0.249642 0.249642)
							(end -0.1778 0.2794)
						)
						(arc
							(start 0.1778 0.2794)
							(mid 0.249642 0.249642)
							(end 0.2794 0.1778)
						)
						(arc
							(start 0.2794 -0.1778)
							(mid 0.249642 -0.249642)
							(end 0.1778 -0.2794)
						)
					)
					(width 0)
					(fill yes)
				)
			)
		)
		(pad "2" smd custom
			(at 0 0.4445 270)
			(size 0.1397 0.1397)
			(layers "F.Cu" "F.Mask" "F.Paste")
			(net "GND")
			(options
				(clearance outline)
				(anchor circle)
			)
			(primitives
				(gr_poly
					(pts
						(arc
							(start -0.1778 -0.2794)
							(mid -0.249642 -0.249642)
							(end -0.2794 -0.1778)
						)
						(arc
							(start -0.2794 0.1778)
							(mid -0.249642 0.249642)
							(end -0.1778 0.2794)
						)
						(arc
							(start 0.1778 0.2794)
							(mid 0.249642 0.249642)
							(end 0.2794 0.1778)
						)
						(arc
							(start 0.2794 -0.1778)
							(mid 0.249642 -0.249642)
							(end 0.1778 -0.2794)
						)
					)
					(width 0)
					(fill yes)
				)
			)
		)
	)
	(footprint ""
		(layer "F.Cu")
		(at 119.5832 -5.9944 -90)
		(property "Reference" "R138"
			(at 0 0 270)
			(layer "F.SilkS")
			(hide yes)
			(effects
				(font
					(size 1.27 1.27)
				)
			)
		)
		(property "Value" "10KR2F-2-GP"
			(at 0.064008 -3.993896 270)
			(unlocked yes)
			(layer "F.Fab")
			(hide yes)
			(effects
				(font
					(size 1.016 1.016)
					(thickness 0.1524)
				)
			)
		)
		(property "Device Type" "R402H16"
			(at 0.064008 -5.517896 270)
			(unlocked yes)
			(layer "F.Fab")
			(hide yes)
			(effects
				(font
					(size 1.016 1.016)
					(thickness 0.1524)
				)
			)
		)
		(duplicate_pad_numbers_are_jumpers no)
		(fp_line
			(start -0.508 -0.9398)
			(end -0.508 0.9398)
			(stroke
				(width 0.1524)
				(type default)
			)
			(layer "F.SilkS")
		)
		(fp_line
			(start 0.508 -0.9398)
			(end -0.508 -0.9398)
			(stroke
				(width 0.1524)
				(type default)
			)
			(layer "F.SilkS")
		)
		(fp_rect
			(start -0.508 0.9398)
			(end 0.508 -0.9398)
			(stroke
				(width 0)
				(type default)
			)
			(fill no)
			(layer "F.CrtYd")
		)
		(fp_rect
			(start -0.508 0.9398)
			(end 0.508 -0.9398)
			(stroke
				(width 0)
				(type default)
			)
			(fill no)
			(layer "F.Fab")
		)
		(pad "1" smd custom
			(at 0 -0.4445 270)
			(size 0.1397 0.1397)
			(layers "F.Cu" "F.Mask" "F.Paste")
			(net "GPIO_P_IO1_4")
			(options
				(clearance outline)
				(anchor circle)
			)
			(primitives
				(gr_poly
					(pts
						(arc
							(start -0.1778 -0.2794)
							(mid -0.249642 -0.249642)
							(end -0.2794 -0.1778)
						)
						(arc
							(start -0.2794 0.1778)
							(mid -0.249642 0.249642)
							(end -0.1778 0.2794)
						)
						(arc
							(start 0.1778 0.2794)
							(mid 0.249642 0.249642)
							(end 0.2794 0.1778)
						)
						(arc
							(start 0.2794 -0.1778)
							(mid 0.249642 -0.249642)
							(end 0.1778 -0.2794)
						)
					)
					(width 0)
					(fill yes)
				)
			)
		)
		(pad "2" smd custom
			(at 0 0.4445 270)
			(size 0.1397 0.1397)
			(layers "F.Cu" "F.Mask" "F.Paste")
			(net "GND")
			(options
				(clearance outline)
				(anchor circle)
			)
			(primitives
				(gr_poly
					(pts
						(arc
							(start -0.1778 -0.2794)
							(mid -0.249642 -0.249642)
							(end -0.2794 -0.1778)
						)
						(arc
							(start -0.2794 0.1778)
							(mid -0.249642 0.249642)
							(end -0.1778 0.2794)
						)
						(arc
							(start 0.1778 0.2794)
							(mid 0.249642 0.249642)
							(end 0.2794 0.1778)
						)
						(arc
							(start 0.2794 -0.1778)
							(mid 0.249642 -0.249642)
							(end 0.1778 -0.2794)
						)
					)
					(width 0)
					(fill yes)
				)
			)
		)
	)
	(footprint ""
		(layer "F.Cu")
		(at 65.6082 -24.0792 180)
		(property "Reference" "R44"
			(at 0 0 180)
			(layer "F.SilkS")
			(hide yes)
			(effects
				(font
					(size 1.27 1.27)
				)
			)
		)
		(property "Value" "4K7R2F-GP"
			(at 0.064008 -3.993896 180)
			(unlocked yes)
			(layer "F.Fab")
			(hide yes)
			(effects
				(font
					(size 1.016 1.016)
					(thickness 0.1524)
				)
			)
		)
		(property "Device Type" "R402H16"
			(at 0.064008 -5.517896 180)
			(unlocked yes)
			(layer "F.Fab")
			(hide yes)
			(effects
				(font
					(size 1.016 1.016)
					(thickness 0.1524)
				)
			)
		)
		(duplicate_pad_numbers_are_jumpers no)
		(fp_line
			(start 0.508 -0.9398)
			(end -0.508 -0.9398)
			(stroke
				(width 0.1524)
				(type default)
			)
			(layer "F.SilkS")
		)
		(fp_line
			(start -0.508 -0.9398)
			(end -0.508 0.9398)
			(stroke
				(width 0.1524)
				(type default)
			)
			(layer "F.SilkS")
		)
		(fp_rect
			(start -0.508 0.9398)
			(end 0.508 -0.9398)
			(stroke
				(width 0)
				(type default)
			)
			(fill no)
			(layer "F.CrtYd")
		)
		(fp_rect
			(start -0.508 0.9398)
			(end 0.508 -0.9398)
			(stroke
				(width 0)
				(type default)
			)
			(fill no)
			(layer "F.Fab")
		)
		(pad "1" smd custom
			(at 0 -0.4445 180)
			(size 0.1397 0.1397)
			(layers "F.Cu" "F.Mask" "F.Paste")
			(net "P3V3_STBY")
			(options
				(clearance outline)
				(anchor circle)
			)
			(primitives
				(gr_poly
					(pts
						(arc
							(start -0.1778 -0.2794)
							(mid -0.249642 -0.249642)
							(end -0.2794 -0.1778)
						)
						(arc
							(start -0.2794 0.1778)
							(mid -0.249642 0.249642)
							(end -0.1778 0.2794)
						)
						(arc
							(start 0.1778 0.2794)
							(mid 0.249642 0.249642)
							(end 0.2794 0.1778)
						)
						(arc
							(start 0.2794 -0.1778)
							(mid 0.249642 -0.249642)
							(end 0.1778 -0.2794)
						)
					)
					(width 0)
					(fill yes)
				)
			)
		)
		(pad "2" smd custom
			(at 0 0.4445 180)
			(size 0.1397 0.1397)
			(layers "F.Cu" "F.Mask" "F.Paste")
			(net "PCIE_SLOT3_PRSNT2_2_N")
			(options
				(clearance outline)
				(anchor circle)
			)
			(primitives
				(gr_poly
					(pts
						(arc
							(start -0.1778 -0.2794)
							(mid -0.249642 -0.249642)
							(end -0.2794 -0.1778)
						)
						(arc
							(start -0.2794 0.1778)
							(mid -0.249642 0.249642)
							(end -0.1778 0.2794)
						)
						(arc
							(start 0.1778 0.2794)
							(mid 0.249642 0.249642)
							(end 0.2794 0.1778)
						)
						(arc
							(start 0.2794 -0.1778)
							(mid 0.249642 -0.249642)
							(end 0.1778 -0.2794)
						)
					)
					(width 0)
					(fill yes)
				)
			)
		)
	)
	(footprint ""
		(layer "F.Cu")
		(at 128.6256 1.9558 90)
		(property "Reference" "R26"
			(at 0 0 90)
			(layer "F.SilkS")
			(hide yes)
			(effects
				(font
					(size 1.27 1.27)
				)
			)
		)
		(property "Value" "4K7R2F-GP"
			(at 0.064008 -3.993896 90)
			(unlocked yes)
			(layer "F.Fab")
			(hide yes)
			(effects
				(font
					(size 1.016 1.016)
					(thickness 0.1524)
				)
			)
		)
		(property "Device Type" "R402H16"
			(at 0.064008 -5.517896 90)
			(unlocked yes)
			(layer "F.Fab")
			(hide yes)
			(effects
				(font
					(size 1.016 1.016)
					(thickness 0.1524)
				)
			)
		)
		(duplicate_pad_numbers_are_jumpers no)
		(fp_line
			(start 0.508 -0.9398)
			(end -0.508 -0.9398)
			(stroke
				(width 0.1524)
				(type default)
			)
			(layer "F.SilkS")
		)
		(fp_line
			(start -0.508 -0.9398)
			(end -0.508 0.9398)
			(stroke
				(width 0.1524)
				(type default)
			)
			(layer "F.SilkS")
		)
		(fp_rect
			(start -0.508 0.9398)
			(end 0.508 -0.9398)
			(stroke
				(width 0)
				(type default)
			)
			(fill no)
			(layer "F.CrtYd")
		)
		(fp_rect
			(start -0.508 0.9398)
			(end 0.508 -0.9398)
			(stroke
				(width 0)
				(type default)
			)
			(fill no)
			(layer "F.Fab")
		)
		(pad "1" smd custom
			(at 0 -0.4445 90)
			(size 0.1397 0.1397)
			(layers "F.Cu" "F.Mask" "F.Paste")
			(net "P3V3_STBY")
			(options
				(clearance outline)
				(anchor circle)
			)
			(primitives
				(gr_poly
					(pts
						(arc
							(start -0.1778 -0.2794)
							(mid -0.249642 -0.249642)
							(end -0.2794 -0.1778)
						)
						(arc
							(start -0.2794 0.1778)
							(mid -0.249642 0.249642)
							(end -0.1778 0.2794)
						)
						(arc
							(start 0.1778 0.2794)
							(mid 0.249642 0.249642)
							(end 0.2794 0.1778)
						)
						(arc
							(start 0.2794 -0.1778)
							(mid 0.249642 -0.249642)
							(end 0.1778 -0.2794)
						)
					)
					(width 0)
					(fill yes)
				)
			)
		)
		(pad "2" smd custom
			(at 0 0.4445 90)
			(size 0.1397 0.1397)
			(layers "F.Cu" "F.Mask" "F.Paste")
			(net "SMCLK_PCH_DEVICE")
			(options
				(clearance outline)
				(anchor circle)
			)
			(primitives
				(gr_poly
					(pts
						(arc
							(start -0.1778 -0.2794)
							(mid -0.249642 -0.249642)
							(end -0.2794 -0.1778)
						)
						(arc
							(start -0.2794 0.1778)
							(mid -0.249642 0.249642)
							(end -0.1778 0.2794)
						)
						(arc
							(start 0.1778 0.2794)
							(mid 0.249642 0.249642)
							(end 0.2794 0.1778)
						)
						(arc
							(start 0.2794 -0.1778)
							(mid 0.249642 -0.249642)
							(end 0.1778 -0.2794)
						)
					)
					(width 0)
					(fill yes)
				)
			)
		)
	)
	(footprint ""
		(layer "F.Cu")
		(at 126.746 2.5908 180)
		(property "Reference" "R155"
			(at 0 0 180)
			(layer "F.SilkS")
			(hide yes)
			(effects
				(font
					(size 1.27 1.27)
				)
			)
		)
		(property "Value" "10KR2F-2-GP"
			(at 0.064008 -3.993896 180)
			(unlocked yes)
			(layer "F.Fab")
			(hide yes)
			(effects
				(font
					(size 1.016 1.016)
					(thickness 0.1524)
				)
			)
		)
		(property "Device Type" "R402H16"
			(at 0.064008 -5.517896 180)
			(unlocked yes)
			(layer "F.Fab")
			(hide yes)
			(effects
				(font
					(size 1.016 1.016)
					(thickness 0.1524)
				)
			)
		)
		(duplicate_pad_numbers_are_jumpers no)
		(fp_line
			(start 0.508 -0.9398)
			(end -0.508 -0.9398)
			(stroke
				(width 0.1524)
				(type default)
			)
			(layer "F.SilkS")
		)
		(fp_line
			(start -0.508 -0.9398)
			(end -0.508 0.9398)
			(stroke
				(width 0.1524)
				(type default)
			)
			(layer "F.SilkS")
		)
		(fp_rect
			(start -0.508 0.9398)
			(end 0.508 -0.9398)
			(stroke
				(width 0)
				(type default)
			)
			(fill no)
			(layer "F.CrtYd")
		)
		(fp_rect
			(start -0.508 0.9398)
			(end 0.508 -0.9398)
			(stroke
				(width 0)
				(type default)
			)
			(fill no)
			(layer "F.Fab")
		)
		(pad "1" smd custom
			(at 0 -0.4445 180)
			(size 0.1397 0.1397)
			(layers "F.Cu" "F.Mask" "F.Paste")
			(net "P3V3_STBY")
			(options
				(clearance outline)
				(anchor circle)
			)
			(primitives
				(gr_poly
					(pts
						(arc
							(start -0.1778 -0.2794)
							(mid -0.249642 -0.249642)
							(end -0.2794 -0.1778)
						)
						(arc
							(start -0.2794 0.1778)
							(mid -0.249642 0.249642)
							(end -0.1778 0.2794)
						)
						(arc
							(start 0.1778 0.2794)
							(mid 0.249642 0.249642)
							(end 0.2794 0.1778)
						)
						(arc
							(start 0.2794 -0.1778)
							(mid 0.249642 -0.249642)
							(end 0.1778 -0.2794)
						)
					)
					(width 0)
					(fill yes)
				)
			)
		)
		(pad "2" smd custom
			(at 0 0.4445 180)
			(size 0.1397 0.1397)
			(layers "F.Cu" "F.Mask" "F.Paste")
			(net "GPIO_P_IO1_7")
			(options
				(clearance outline)
				(anchor circle)
			)
			(primitives
				(gr_poly
					(pts
						(arc
							(start -0.1778 -0.2794)
							(mid -0.249642 -0.249642)
							(end -0.2794 -0.1778)
						)
						(arc
							(start -0.2794 0.1778)
							(mid -0.249642 0.249642)
							(end -0.1778 0.2794)
						)
						(arc
							(start 0.1778 0.2794)
							(mid 0.249642 0.249642)
							(end 0.2794 0.1778)
						)
						(arc
							(start 0.2794 -0.1778)
							(mid 0.249642 -0.249642)
							(end 0.1778 -0.2794)
						)
					)
					(width 0)
					(fill yes)
				)
			)
		)
	)
	(footprint ""
		(layer "F.Cu")
		(at 17.1958 -22.9616 90)
		(property "Reference" "R86"
			(at 0 0 90)
			(layer "F.SilkS")
			(hide yes)
			(effects
				(font
					(size 1.27 1.27)
				)
			)
		)
		(property "Value" "10R2F-L-GP"
			(at 0.064008 -3.993896 90)
			(unlocked yes)
			(layer "F.Fab")
			(hide yes)
			(effects
				(font
					(size 1.016 1.016)
					(thickness 0.1524)
				)
			)
		)
		(property "Device Type" "R402H14"
			(at 0.064008 -5.517896 90)
			(unlocked yes)
			(layer "F.Fab")
			(hide yes)
			(effects
				(font
					(size 1.016 1.016)
					(thickness 0.1524)
				)
			)
		)
		(duplicate_pad_numbers_are_jumpers no)
		(fp_line
			(start 0.508 -0.9398)
			(end -0.508 -0.9398)
			(stroke
				(width 0.1524)
				(type default)
			)
			(layer "F.SilkS")
		)
		(fp_line
			(start -0.508 -0.9398)
			(end -0.508 0.9398)
			(stroke
				(width 0.1524)
				(type default)
			)
			(layer "F.SilkS")
		)
		(fp_rect
			(start -0.508 0.9398)
			(end 0.508 -0.9398)
			(stroke
				(width 0)
				(type default)
			)
			(fill no)
			(layer "F.CrtYd")
		)
		(fp_rect
			(start -0.508 0.9398)
			(end 0.508 -0.9398)
			(stroke
				(width 0)
				(type default)
			)
			(fill no)
			(layer "F.Fab")
		)
		(pad "1" smd custom
			(at 0 -0.4445 90)
			(size 0.1397 0.1397)
			(layers "F.Cu" "F.Mask" "F.Paste")
			(net "P12V")
			(options
				(clearance outline)
				(anchor circle)
			)
			(primitives
				(gr_poly
					(pts
						(arc
							(start -0.1778 -0.2794)
							(mid -0.249642 -0.249642)
							(end -0.2794 -0.1778)
						)
						(arc
							(start -0.2794 0.1778)
							(mid -0.249642 0.249642)
							(end -0.1778 0.2794)
						)
						(arc
							(start 0.1778 0.2794)
							(mid 0.249642 0.249642)
							(end 0.2794 0.1778)
						)
						(arc
							(start 0.2794 -0.1778)
							(mid 0.249642 -0.249642)
							(end 0.1778 -0.2794)
						)
					)
					(width 0)
					(fill yes)
				)
			)
		)
		(pad "2" smd custom
			(at 0 0.4445 90)
			(size 0.1397 0.1397)
			(layers "F.Cu" "F.Mask" "F.Paste")
			(net "SLOT3_P12V_SENSE_VP_R")
			(options
				(clearance outline)
				(anchor circle)
			)
			(primitives
				(gr_poly
					(pts
						(arc
							(start -0.1778 -0.2794)
							(mid -0.249642 -0.249642)
							(end -0.2794 -0.1778)
						)
						(arc
							(start -0.2794 0.1778)
							(mid -0.249642 0.249642)
							(end -0.1778 0.2794)
						)
						(arc
							(start 0.1778 0.2794)
							(mid 0.249642 0.249642)
							(end 0.2794 0.1778)
						)
						(arc
							(start 0.2794 -0.1778)
							(mid 0.249642 -0.249642)
							(end 0.1778 -0.2794)
						)
					)
					(width 0)
					(fill yes)
				)
			)
		)
	)
	(footprint ""
		(layer "F.Cu")
		(at 19.4056 -15.758922 180)
		(property "Reference" "R82"
			(at 0 0 180)
			(layer "F.SilkS")
			(hide yes)
			(effects
				(font
					(size 1.27 1.27)
				)
			)
		)
		(property "Value" "10KR2F-2-GP"
			(at 0.064008 -3.993896 180)
			(unlocked yes)
			(layer "F.Fab")
			(hide yes)
			(effects
				(font
					(size 1.016 1.016)
					(thickness 0.1524)
				)
			)
		)
		(property "Device Type" "R402H16"
			(at 0.064008 -5.517896 180)
			(unlocked yes)
			(layer "F.Fab")
			(hide yes)
			(effects
				(font
					(size 1.016 1.016)
					(thickness 0.1524)
				)
			)
		)
		(duplicate_pad_numbers_are_jumpers no)
		(fp_line
			(start 0.508 -0.9398)
			(end -0.508 -0.9398)
			(stroke
				(width 0.1524)
				(type default)
			)
			(layer "F.SilkS")
		)
		(fp_line
			(start -0.508 -0.9398)
			(end -0.508 0.9398)
			(stroke
				(width 0.1524)
				(type default)
			)
			(layer "F.SilkS")
		)
		(fp_rect
			(start -0.508 0.9398)
			(end 0.508 -0.9398)
			(stroke
				(width 0)
				(type default)
			)
			(fill no)
			(layer "F.CrtYd")
		)
		(fp_rect
			(start -0.508 0.9398)
			(end 0.508 -0.9398)
			(stroke
				(width 0)
				(type default)
			)
			(fill no)
			(layer "F.Fab")
		)
		(pad "1" smd custom
			(at 0 -0.4445 180)
			(size 0.1397 0.1397)
			(layers "F.Cu" "F.Mask" "F.Paste")
			(net "P3V3_STBY")
			(options
				(clearance outline)
				(anchor circle)
			)
			(primitives
				(gr_poly
					(pts
						(arc
							(start -0.1778 -0.2794)
							(mid -0.249642 -0.249642)
							(end -0.2794 -0.1778)
						)
						(arc
							(start -0.2794 0.1778)
							(mid -0.249642 0.249642)
							(end -0.1778 0.2794)
						)
						(arc
							(start 0.1778 0.2794)
							(mid 0.249642 0.249642)
							(end 0.2794 0.1778)
						)
						(arc
							(start 0.2794 -0.1778)
							(mid 0.249642 -0.249642)
							(end 0.1778 -0.2794)
						)
					)
					(width 0)
					(fill yes)
				)
			)
		)
		(pad "2" smd custom
			(at 0 0.4445 180)
			(size 0.1397 0.1397)
			(layers "F.Cu" "F.Mask" "F.Paste")
			(net "SLOT2_VMONITOR_A1")
			(options
				(clearance outline)
				(anchor circle)
			)
			(primitives
				(gr_poly
					(pts
						(arc
							(start -0.1778 -0.2794)
							(mid -0.249642 -0.249642)
							(end -0.2794 -0.1778)
						)
						(arc
							(start -0.2794 0.1778)
							(mid -0.249642 0.249642)
							(end -0.1778 0.2794)
						)
						(arc
							(start 0.1778 0.2794)
							(mid 0.249642 0.249642)
							(end 0.2794 0.1778)
						)
						(arc
							(start 0.2794 -0.1778)
							(mid 0.249642 -0.249642)
							(end 0.1778 -0.2794)
						)
					)
					(width 0)
					(fill yes)
				)
			)
		)
	)
	(footprint ""
		(layer "F.Cu")
		(at 23.0124 -16.1798 -90)
		(property "Reference" "R85"
			(at 0 0 270)
			(layer "F.SilkS")
			(hide yes)
			(effects
				(font
					(size 1.27 1.27)
				)
			)
		)
		(property "Value" "10KR2F-2-GP"
			(at 0.064008 -3.993896 270)
			(unlocked yes)
			(layer "F.Fab")
			(hide yes)
			(effects
				(font
					(size 1.016 1.016)
					(thickness 0.1524)
				)
			)
		)
		(property "Device Type" "R402H16"
			(at 0.064008 -5.517896 270)
			(unlocked yes)
			(layer "F.Fab")
			(hide yes)
			(effects
				(font
					(size 1.016 1.016)
					(thickness 0.1524)
				)
			)
		)
		(duplicate_pad_numbers_are_jumpers no)
		(fp_line
			(start -0.508 -0.9398)
			(end -0.508 0.9398)
			(stroke
				(width 0.1524)
				(type default)
			)
			(layer "F.SilkS")
		)
		(fp_line
			(start 0.508 -0.9398)
			(end -0.508 -0.9398)
			(stroke
				(width 0.1524)
				(type default)
			)
			(layer "F.SilkS")
		)
		(fp_rect
			(start -0.508 0.9398)
			(end 0.508 -0.9398)
			(stroke
				(width 0)
				(type default)
			)
			(fill no)
			(layer "F.CrtYd")
		)
		(fp_rect
			(start -0.508 0.9398)
			(end 0.508 -0.9398)
			(stroke
				(width 0)
				(type default)
			)
			(fill no)
			(layer "F.Fab")
		)
		(pad "1" smd custom
			(at 0 -0.4445 270)
			(size 0.1397 0.1397)
			(layers "F.Cu" "F.Mask" "F.Paste")
			(net "P3V3_STBY")
			(options
				(clearance outline)
				(anchor circle)
			)
			(primitives
				(gr_poly
					(pts
						(arc
							(start -0.1778 -0.2794)
							(mid -0.249642 -0.249642)
							(end -0.2794 -0.1778)
						)
						(arc
							(start -0.2794 0.1778)
							(mid -0.249642 0.249642)
							(end -0.1778 0.2794)
						)
						(arc
							(start 0.1778 0.2794)
							(mid 0.249642 0.249642)
							(end 0.2794 0.1778)
						)
						(arc
							(start 0.2794 -0.1778)
							(mid 0.249642 -0.249642)
							(end 0.1778 -0.2794)
						)
					)
					(width 0)
					(fill yes)
				)
			)
		)
		(pad "2" smd custom
			(at 0 0.4445 270)
			(size 0.1397 0.1397)
			(layers "F.Cu" "F.Mask" "F.Paste")
			(net "SLOT2_VMONITOR_A0")
			(options
				(clearance outline)
				(anchor circle)
			)
			(primitives
				(gr_poly
					(pts
						(arc
							(start -0.1778 -0.2794)
							(mid -0.249642 -0.249642)
							(end -0.2794 -0.1778)
						)
						(arc
							(start -0.2794 0.1778)
							(mid -0.249642 0.249642)
							(end -0.1778 0.2794)
						)
						(arc
							(start 0.1778 0.2794)
							(mid 0.249642 0.249642)
							(end 0.2794 0.1778)
						)
						(arc
							(start 0.2794 -0.1778)
							(mid 0.249642 -0.249642)
							(end 0.1778 -0.2794)
						)
					)
					(width 0)
					(fill yes)
				)
			)
		)
	)
	(footprint ""
		(layer "F.Cu")
		(at 130.1496 0.4826 180)
		(property "Reference" "R95"
			(at 0 0 180)
			(layer "F.SilkS")
			(hide yes)
			(effects
				(font
					(size 1.27 1.27)
				)
			)
		)
		(property "Value" "0R2F-1-GP"
			(at 0.064008 -3.993896 180)
			(unlocked yes)
			(layer "F.Fab")
			(hide yes)
			(effects
				(font
					(size 1.016 1.016)
					(thickness 0.1524)
				)
			)
		)
		(property "Device Type" "R402H16"
			(at 0.064008 -5.517896 180)
			(unlocked yes)
			(layer "F.Fab")
			(hide yes)
			(effects
				(font
					(size 1.016 1.016)
					(thickness 0.1524)
				)
			)
		)
		(duplicate_pad_numbers_are_jumpers no)
		(fp_line
			(start 0.508 -0.9398)
			(end -0.508 -0.9398)
			(stroke
				(width 0.1524)
				(type default)
			)
			(layer "F.SilkS")
		)
		(fp_line
			(start -0.508 -0.9398)
			(end -0.508 0.9398)
			(stroke
				(width 0.1524)
				(type default)
			)
			(layer "F.SilkS")
		)
		(fp_rect
			(start -0.508 0.9398)
			(end 0.508 -0.9398)
			(stroke
				(width 0)
				(type default)
			)
			(fill no)
			(layer "F.CrtYd")
		)
		(fp_rect
			(start -0.508 0.9398)
			(end 0.508 -0.9398)
			(stroke
				(width 0)
				(type default)
			)
			(fill no)
			(layer "F.Fab")
		)
		(pad "1" smd custom
			(at 0 -0.4445 180)
			(size 0.1397 0.1397)
			(layers "F.Cu" "F.Mask" "F.Paste")
			(net "SMDAT_PCH_DEVICE")
			(options
				(clearance outline)
				(anchor circle)
			)
			(primitives
				(gr_poly
					(pts
						(arc
							(start -0.1778 -0.2794)
							(mid -0.249642 -0.249642)
							(end -0.2794 -0.1778)
						)
						(arc
							(start -0.2794 0.1778)
							(mid -0.249642 0.249642)
							(end -0.1778 0.2794)
						)
						(arc
							(start 0.1778 0.2794)
							(mid 0.249642 0.249642)
							(end 0.2794 0.1778)
						)
						(arc
							(start 0.2794 -0.1778)
							(mid 0.249642 -0.249642)
							(end 0.1778 -0.2794)
						)
					)
					(width 0)
					(fill yes)
				)
			)
		)
		(pad "2" smd custom
			(at 0 0.4445 180)
			(size 0.1397 0.1397)
			(layers "F.Cu" "F.Mask" "F.Paste")
			(net "SMDAT_EXP_R_PCH")
			(options
				(clearance outline)
				(anchor circle)
			)
			(primitives
				(gr_poly
					(pts
						(arc
							(start -0.1778 -0.2794)
							(mid -0.249642 -0.249642)
							(end -0.2794 -0.1778)
						)
						(arc
							(start -0.2794 0.1778)
							(mid -0.249642 0.249642)
							(end -0.1778 0.2794)
						)
						(arc
							(start 0.1778 0.2794)
							(mid 0.249642 0.249642)
							(end 0.2794 0.1778)
						)
						(arc
							(start 0.2794 -0.1778)
							(mid 0.249642 -0.249642)
							(end 0.1778 -0.2794)
						)
					)
					(width 0)
					(fill yes)
				)
			)
		)
	)
	(footprint ""
		(layer "F.Cu")
		(at 18.7198 -28.3718 90)
		(property "Reference" "C55"
			(at 0 0 90)
			(layer "F.SilkS")
			(hide yes)
			(effects
				(font
					(size 1.27 1.27)
				)
			)
		)
		(property "Value" "SCD1U25V2KX-2-GP"
			(at 1.1811 -2.7051 90)
			(unlocked yes)
			(layer "F.Fab")
			(hide yes)
			(effects
				(font
					(size 1.016 1.016)
					(thickness 0.1524)
				)
			)
		)
		(property "Device Type" "C402H22"
			(at 1.1811 -4.2291 90)
			(unlocked yes)
			(layer "F.Fab")
			(hide yes)
			(effects
				(font
					(size 1.016 1.016)
					(thickness 0.1524)
				)
			)
		)
		(duplicate_pad_numbers_are_jumpers no)
		(fp_rect
			(start -0.4318 0.9525)
			(end 0.4318 -0.9525)
			(stroke
				(width 0)
				(type default)
			)
			(fill no)
			(layer "F.CrtYd")
		)
		(fp_rect
			(start -0.4318 0.9525)
			(end 0.4318 -0.9525)
			(stroke
				(width 0)
				(type default)
			)
			(fill no)
			(layer "F.Fab")
		)
		(pad "1" smd custom
			(at 0 -0.4445 90)
			(size 0.1524 0.1524)
			(layers "F.Cu" "F.Mask" "F.Paste")
			(net "P12V")
			(options
				(clearance outline)
				(anchor circle)
			)
			(primitives
				(gr_poly
					(pts
						(arc
							(start 0.3048 -0.2032)
							(mid 0.275042 -0.275042)
							(end 0.2032 -0.3048)
						)
						(arc
							(start -0.2032 -0.3048)
							(mid -0.275042 -0.275042)
							(end -0.3048 -0.2032)
						)
						(arc
							(start -0.3048 0.2032)
							(mid -0.275042 0.275042)
							(end -0.2032 0.3048)
						)
						(arc
							(start 0.2032 0.3048)
							(mid 0.275042 0.275042)
							(end 0.3048 0.2032)
						)
					)
					(width 0)
					(fill yes)
				)
			)
		)
		(pad "2" smd custom
			(at 0 0.4445 90)
			(size 0.1524 0.1524)
			(layers "F.Cu" "F.Mask" "F.Paste")
			(net "GND")
			(options
				(clearance outline)
				(anchor circle)
			)
			(primitives
				(gr_poly
					(pts
						(arc
							(start 0.3048 -0.2032)
							(mid 0.275042 -0.275042)
							(end 0.2032 -0.3048)
						)
						(arc
							(start -0.2032 -0.3048)
							(mid -0.275042 -0.275042)
							(end -0.3048 -0.2032)
						)
						(arc
							(start -0.3048 0.2032)
							(mid -0.275042 0.275042)
							(end -0.2032 0.3048)
						)
						(arc
							(start 0.2032 0.3048)
							(mid 0.275042 0.275042)
							(end 0.3048 0.2032)
						)
					)
					(width 0)
					(fill yes)
				)
			)
		)
	)
	(footprint ""
		(layer "F.Cu")
		(at 21.5519 5.8547 90)
		(property "Reference" "R2"
			(at 0 0 90)
			(layer "F.SilkS")
			(hide yes)
			(effects
				(font
					(size 1.27 1.27)
				)
			)
		)
		(property "Value" "475R2F-L1-GP"
			(at 0.064008 -3.993896 90)
			(unlocked yes)
			(layer "F.Fab")
			(hide yes)
			(effects
				(font
					(size 1.016 1.016)
					(thickness 0.1524)
				)
			)
		)
		(property "Device Type" "R402H16"
			(at 0.064008 -5.517896 90)
			(unlocked yes)
			(layer "F.Fab")
			(hide yes)
			(effects
				(font
					(size 1.016 1.016)
					(thickness 0.1524)
				)
			)
		)
		(duplicate_pad_numbers_are_jumpers no)
		(fp_line
			(start 0.508 -0.9398)
			(end -0.508 -0.9398)
			(stroke
				(width 0.1524)
				(type default)
			)
			(layer "F.SilkS")
		)
		(fp_line
			(start -0.508 -0.9398)
			(end -0.508 0.9398)
			(stroke
				(width 0.1524)
				(type default)
			)
			(layer "F.SilkS")
		)
		(fp_rect
			(start -0.508 0.9398)
			(end 0.508 -0.9398)
			(stroke
				(width 0)
				(type default)
			)
			(fill no)
			(layer "F.CrtYd")
		)
		(fp_rect
			(start -0.508 0.9398)
			(end 0.508 -0.9398)
			(stroke
				(width 0)
				(type default)
			)
			(fill no)
			(layer "F.Fab")
		)
		(pad "1" smd custom
			(at 0 -0.4445 90)
			(size 0.1397 0.1397)
			(layers "F.Cu" "F.Mask" "F.Paste")
			(net "GND")
			(options
				(clearance outline)
				(anchor circle)
			)
			(primitives
				(gr_poly
					(pts
						(arc
							(start -0.1778 -0.2794)
							(mid -0.249642 -0.249642)
							(end -0.2794 -0.1778)
						)
						(arc
							(start -0.2794 0.1778)
							(mid -0.249642 0.249642)
							(end -0.1778 0.2794)
						)
						(arc
							(start 0.1778 0.2794)
							(mid 0.249642 0.249642)
							(end 0.2794 0.1778)
						)
						(arc
							(start 0.2794 -0.1778)
							(mid 0.249642 -0.249642)
							(end 0.1778 -0.2794)
						)
					)
					(width 0)
					(fill yes)
				)
			)
		)
		(pad "2" smd custom
			(at 0 0.4445 90)
			(size 0.1397 0.1397)
			(layers "F.Cu" "F.Mask" "F.Paste")
			(net "FM_SLT_CFG1")
			(options
				(clearance outline)
				(anchor circle)
			)
			(primitives
				(gr_poly
					(pts
						(arc
							(start -0.1778 -0.2794)
							(mid -0.249642 -0.249642)
							(end -0.2794 -0.1778)
						)
						(arc
							(start -0.2794 0.1778)
							(mid -0.249642 0.249642)
							(end -0.1778 0.2794)
						)
						(arc
							(start 0.1778 0.2794)
							(mid 0.249642 0.249642)
							(end 0.2794 0.1778)
						)
						(arc
							(start 0.2794 -0.1778)
							(mid 0.249642 -0.249642)
							(end 0.1778 -0.2794)
						)
					)
					(width 0)
					(fill yes)
				)
			)
		)
	)
	(footprint ""
		(layer "F.Cu")
		(at 125.1458 1.5748 -90)
		(property "Reference" "R144"
			(at 0 0 270)
			(layer "F.SilkS")
			(hide yes)
			(effects
				(font
					(size 1.27 1.27)
				)
			)
		)
		(property "Value" "10KR2F-2-GP"
			(at 0.064008 -3.993896 270)
			(unlocked yes)
			(layer "F.Fab")
			(hide yes)
			(effects
				(font
					(size 1.016 1.016)
					(thickness 0.1524)
				)
			)
		)
		(property "Device Type" "R402H16"
			(at 0.064008 -5.517896 270)
			(unlocked yes)
			(layer "F.Fab")
			(hide yes)
			(effects
				(font
					(size 1.016 1.016)
					(thickness 0.1524)
				)
			)
		)
		(duplicate_pad_numbers_are_jumpers no)
		(fp_line
			(start -0.508 -0.9398)
			(end -0.508 0.9398)
			(stroke
				(width 0.1524)
				(type default)
			)
			(layer "F.SilkS")
		)
		(fp_line
			(start 0.508 -0.9398)
			(end -0.508 -0.9398)
			(stroke
				(width 0.1524)
				(type default)
			)
			(layer "F.SilkS")
		)
		(fp_rect
			(start -0.508 0.9398)
			(end 0.508 -0.9398)
			(stroke
				(width 0)
				(type default)
			)
			(fill no)
			(layer "F.CrtYd")
		)
		(fp_rect
			(start -0.508 0.9398)
			(end 0.508 -0.9398)
			(stroke
				(width 0)
				(type default)
			)
			(fill no)
			(layer "F.Fab")
		)
		(pad "1" smd custom
			(at 0 -0.4445 270)
			(size 0.1397 0.1397)
			(layers "F.Cu" "F.Mask" "F.Paste")
			(net "GPIO_P_IO1_6")
			(options
				(clearance outline)
				(anchor circle)
			)
			(primitives
				(gr_poly
					(pts
						(arc
							(start -0.1778 -0.2794)
							(mid -0.249642 -0.249642)
							(end -0.2794 -0.1778)
						)
						(arc
							(start -0.2794 0.1778)
							(mid -0.249642 0.249642)
							(end -0.1778 0.2794)
						)
						(arc
							(start 0.1778 0.2794)
							(mid 0.249642 0.249642)
							(end 0.2794 0.1778)
						)
						(arc
							(start 0.2794 -0.1778)
							(mid 0.249642 -0.249642)
							(end 0.1778 -0.2794)
						)
					)
					(width 0)
					(fill yes)
				)
			)
		)
		(pad "2" smd custom
			(at 0 0.4445 270)
			(size 0.1397 0.1397)
			(layers "F.Cu" "F.Mask" "F.Paste")
			(net "GND")
			(options
				(clearance outline)
				(anchor circle)
			)
			(primitives
				(gr_poly
					(pts
						(arc
							(start -0.1778 -0.2794)
							(mid -0.249642 -0.249642)
							(end -0.2794 -0.1778)
						)
						(arc
							(start -0.2794 0.1778)
							(mid -0.249642 0.249642)
							(end -0.1778 0.2794)
						)
						(arc
							(start 0.1778 0.2794)
							(mid 0.249642 0.249642)
							(end 0.2794 0.1778)
						)
						(arc
							(start 0.2794 -0.1778)
							(mid 0.249642 -0.249642)
							(end 0.1778 -0.2794)
						)
					)
					(width 0)
					(fill yes)
				)
			)
		)
	)
	(footprint ""
		(layer "F.Cu")
		(at 53.5432 -15.9004 -90)
		(property "Reference" "R30"
			(at 0 0 270)
			(layer "F.SilkS")
			(hide yes)
			(effects
				(font
					(size 1.27 1.27)
				)
			)
		)
		(property "Value" "0R2F-1-GP"
			(at 0.064008 -3.993896 270)
			(unlocked yes)
			(layer "F.Fab")
			(hide yes)
			(effects
				(font
					(size 1.016 1.016)
					(thickness 0.1524)
				)
			)
		)
		(property "Device Type" "R402H16"
			(at 0.064008 -5.517896 270)
			(unlocked yes)
			(layer "F.Fab")
			(hide yes)
			(effects
				(font
					(size 1.016 1.016)
					(thickness 0.1524)
				)
			)
		)
		(duplicate_pad_numbers_are_jumpers no)
		(fp_line
			(start -0.508 -0.9398)
			(end -0.508 0.9398)
			(stroke
				(width 0.1524)
				(type default)
			)
			(layer "F.SilkS")
		)
		(fp_line
			(start 0.508 -0.9398)
			(end -0.508 -0.9398)
			(stroke
				(width 0.1524)
				(type default)
			)
			(layer "F.SilkS")
		)
		(fp_rect
			(start -0.508 0.9398)
			(end 0.508 -0.9398)
			(stroke
				(width 0)
				(type default)
			)
			(fill no)
			(layer "F.CrtYd")
		)
		(fp_rect
			(start -0.508 0.9398)
			(end 0.508 -0.9398)
			(stroke
				(width 0)
				(type default)
			)
			(fill no)
			(layer "F.Fab")
		)
		(pad "1" smd custom
			(at 0 -0.4445 270)
			(size 0.1397 0.1397)
			(layers "F.Cu" "F.Mask" "F.Paste")
			(net "SMB_PCIE_SLOT2_ALERT_N")
			(options
				(clearance outline)
				(anchor circle)
			)
			(primitives
				(gr_poly
					(pts
						(arc
							(start -0.1778 -0.2794)
							(mid -0.249642 -0.249642)
							(end -0.2794 -0.1778)
						)
						(arc
							(start -0.2794 0.1778)
							(mid -0.249642 0.249642)
							(end -0.1778 0.2794)
						)
						(arc
							(start 0.1778 0.2794)
							(mid 0.249642 0.249642)
							(end 0.2794 0.1778)
						)
						(arc
							(start 0.2794 -0.1778)
							(mid 0.249642 -0.249642)
							(end 0.1778 -0.2794)
						)
					)
					(width 0)
					(fill yes)
				)
			)
		)
		(pad "2" smd custom
			(at 0 0.4445 270)
			(size 0.1397 0.1397)
			(layers "F.Cu" "F.Mask" "F.Paste")
			(net "SMB_ALERT_S2_B12_N")
			(options
				(clearance outline)
				(anchor circle)
			)
			(primitives
				(gr_poly
					(pts
						(arc
							(start -0.1778 -0.2794)
							(mid -0.249642 -0.249642)
							(end -0.2794 -0.1778)
						)
						(arc
							(start -0.2794 0.1778)
							(mid -0.249642 0.249642)
							(end -0.1778 0.2794)
						)
						(arc
							(start 0.1778 0.2794)
							(mid 0.249642 0.249642)
							(end 0.2794 0.1778)
						)
						(arc
							(start 0.2794 -0.1778)
							(mid 0.249642 -0.249642)
							(end 0.1778 -0.2794)
						)
					)
					(width 0)
					(fill yes)
				)
			)
		)
	)
	(footprint ""
		(layer "F.Cu")
		(at 127.635 -23.5458 -90)
		(property "Reference" "RU22"
			(at 0 0 270)
			(layer "F.SilkS")
			(hide yes)
			(effects
				(font
					(size 1.27 1.27)
				)
			)
		)
		(property "Value" "10KR2F-2-GP"
			(at 0.064008 -3.993896 270)
			(unlocked yes)
			(layer "F.Fab")
			(hide yes)
			(effects
				(font
					(size 1.016 1.016)
					(thickness 0.1524)
				)
			)
		)
		(property "Device Type" "R402H16"
			(at 0.064008 -5.517896 270)
			(unlocked yes)
			(layer "F.Fab")
			(hide yes)
			(effects
				(font
					(size 1.016 1.016)
					(thickness 0.1524)
				)
			)
		)
		(duplicate_pad_numbers_are_jumpers no)
		(fp_line
			(start -0.508 -0.9398)
			(end -0.508 0.9398)
			(stroke
				(width 0.1524)
				(type default)
			)
			(layer "F.SilkS")
		)
		(fp_line
			(start 0.508 -0.9398)
			(end -0.508 -0.9398)
			(stroke
				(width 0.1524)
				(type default)
			)
			(layer "F.SilkS")
		)
		(fp_rect
			(start -0.508 0.9398)
			(end 0.508 -0.9398)
			(stroke
				(width 0)
				(type default)
			)
			(fill no)
			(layer "F.CrtYd")
		)
		(fp_rect
			(start -0.508 0.9398)
			(end 0.508 -0.9398)
			(stroke
				(width 0)
				(type default)
			)
			(fill no)
			(layer "F.Fab")
		)
		(pad "1" smd custom
			(at 0 -0.4445 270)
			(size 0.1397 0.1397)
			(layers "F.Cu" "F.Mask" "F.Paste")
			(net "P3V3_USB_HUB")
			(options
				(clearance outline)
				(anchor circle)
			)
			(primitives
				(gr_poly
					(pts
						(arc
							(start -0.1778 -0.2794)
							(mid -0.249642 -0.249642)
							(end -0.2794 -0.1778)
						)
						(arc
							(start -0.2794 0.1778)
							(mid -0.249642 0.249642)
							(end -0.1778 0.2794)
						)
						(arc
							(start 0.1778 0.2794)
							(mid 0.249642 0.249642)
							(end 0.2794 0.1778)
						)
						(arc
							(start 0.2794 -0.1778)
							(mid 0.249642 -0.249642)
							(end 0.1778 -0.2794)
						)
					)
					(width 0)
					(fill yes)
				)
			)
		)
		(pad "2" smd custom
			(at 0 0.4445 270)
			(size 0.1397 0.1397)
			(layers "F.Cu" "F.Mask" "F.Paste")
			(net "VBUS_DET")
			(options
				(clearance outline)
				(anchor circle)
			)
			(primitives
				(gr_poly
					(pts
						(arc
							(start -0.1778 -0.2794)
							(mid -0.249642 -0.249642)
							(end -0.2794 -0.1778)
						)
						(arc
							(start -0.2794 0.1778)
							(mid -0.249642 0.249642)
							(end -0.1778 0.2794)
						)
						(arc
							(start 0.1778 0.2794)
							(mid 0.249642 0.249642)
							(end 0.2794 0.1778)
						)
						(arc
							(start 0.2794 -0.1778)
							(mid 0.249642 -0.249642)
							(end 0.1778 -0.2794)
						)
					)
					(width 0)
					(fill yes)
				)
			)
		)
	)
	(footprint ""
		(layer "F.Cu")
		(at 108.7882 3.1496)
		(property "Reference" "R17"
			(at 0 0 0)
			(layer "F.SilkS")
			(hide yes)
			(effects
				(font
					(size 1.27 1.27)
				)
			)
		)
		(property "Value" "10KR2F-2-GP"
			(at 0.064008 -3.993896 0)
			(unlocked yes)
			(layer "F.Fab")
			(hide yes)
			(effects
				(font
					(size 1.016 1.016)
					(thickness 0.1524)
				)
			)
		)
		(property "Device Type" "R402H16"
			(at 0.064008 -5.517896 0)
			(unlocked yes)
			(layer "F.Fab")
			(hide yes)
			(effects
				(font
					(size 1.016 1.016)
					(thickness 0.1524)
				)
			)
		)
		(duplicate_pad_numbers_are_jumpers no)
		(fp_line
			(start -0.508 -0.9398)
			(end -0.508 0.9398)
			(stroke
				(width 0.1524)
				(type default)
			)
			(layer "F.SilkS")
		)
		(fp_line
			(start 0.508 -0.9398)
			(end -0.508 -0.9398)
			(stroke
				(width 0.1524)
				(type default)
			)
			(layer "F.SilkS")
		)
		(fp_rect
			(start -0.508 0.9398)
			(end 0.508 -0.9398)
			(stroke
				(width 0)
				(type default)
			)
			(fill no)
			(layer "F.CrtYd")
		)
		(fp_rect
			(start -0.508 0.9398)
			(end 0.508 -0.9398)
			(stroke
				(width 0)
				(type default)
			)
			(fill no)
			(layer "F.Fab")
		)
		(pad "1" smd custom
			(at 0 -0.4445)
			(size 0.1397 0.1397)
			(layers "F.Cu" "F.Mask" "F.Paste")
			(net "SMB_B_HUB_A0")
			(options
				(clearance outline)
				(anchor circle)
			)
			(primitives
				(gr_poly
					(pts
						(arc
							(start -0.1778 -0.2794)
							(mid -0.249642 -0.249642)
							(end -0.2794 -0.1778)
						)
						(arc
							(start -0.2794 0.1778)
							(mid -0.249642 0.249642)
							(end -0.1778 0.2794)
						)
						(arc
							(start 0.1778 0.2794)
							(mid 0.249642 0.249642)
							(end 0.2794 0.1778)
						)
						(arc
							(start 0.2794 -0.1778)
							(mid 0.249642 -0.249642)
							(end 0.1778 -0.2794)
						)
					)
					(width 0)
					(fill yes)
				)
			)
		)
		(pad "2" smd custom
			(at 0 0.4445)
			(size 0.1397 0.1397)
			(layers "F.Cu" "F.Mask" "F.Paste")
			(net "GND")
			(options
				(clearance outline)
				(anchor circle)
			)
			(primitives
				(gr_poly
					(pts
						(arc
							(start -0.1778 -0.2794)
							(mid -0.249642 -0.249642)
							(end -0.2794 -0.1778)
						)
						(arc
							(start -0.2794 0.1778)
							(mid -0.249642 0.249642)
							(end -0.1778 0.2794)
						)
						(arc
							(start 0.1778 0.2794)
							(mid 0.249642 0.249642)
							(end 0.2794 0.1778)
						)
						(arc
							(start 0.2794 -0.1778)
							(mid 0.249642 -0.249642)
							(end 0.1778 -0.2794)
						)
					)
					(width 0)
					(fill yes)
				)
			)
		)
	)
	(footprint ""
		(layer "F.Cu")
		(at 25.1206 -31.9532 180)
		(property "Reference" "C91"
			(at 0 0 180)
			(layer "F.SilkS")
			(hide yes)
			(effects
				(font
					(size 1.27 1.27)
				)
			)
		)
		(property "Value" "SC22U16V5MX-4-GP"
			(at -0.0762 -6.1214 180)
			(unlocked yes)
			(layer "F.Fab")
			(hide yes)
			(effects
				(font
					(size 1.016 1.016)
					(thickness 0.1524)
				)
			)
		)
		(property "Device Type" "C805H58"
			(at -0.0762 -8.1534 180)
			(unlocked yes)
			(layer "F.Fab")
			(hide yes)
			(effects
				(font
					(size 1.016 1.016)
					(thickness 0.1524)
				)
			)
		)
		(duplicate_pad_numbers_are_jumpers no)
		(fp_line
			(start 0.635 0)
			(end -0.635 0)
			(stroke
				(width 0.508)
				(type default)
			)
			(layer "F.SilkS")
		)
		(fp_rect
			(start -0.9652 1.778)
			(end 0.9652 -1.778)
			(stroke
				(width 0)
				(type default)
			)
			(fill no)
			(layer "F.CrtYd")
		)
		(fp_poly
			(pts
				(xy -0.9652 -1.778) (xy 0.9652 -1.778) (xy 0.9652 1.778) (xy -0.9652 1.778)
			)
			(stroke
				(width 0)
				(type default)
			)
			(fill no)
			(layer "F.Fab")
		)
		(pad "1" smd rect
			(at 0 -0.9652 180)
			(size 1.397 1.143)
			(layers "F.Cu" "F.Mask" "F.Paste")
			(net "P12V_SLOT3")
		)
		(pad "2" smd rect
			(at 0 0.9652 180)
			(size 1.397 1.143)
			(layers "F.Cu" "F.Mask" "F.Paste")
			(net "GND")
		)
	)
	(footprint ""
		(layer "F.Cu")
		(at 124.4092 -21.1074)
		(property "Reference" "R66"
			(at 0 0 0)
			(layer "F.SilkS")
			(hide yes)
			(effects
				(font
					(size 1.27 1.27)
				)
			)
		)
		(property "Value" "4K7R2F-GP"
			(at 0.064008 -3.993896 0)
			(unlocked yes)
			(layer "F.Fab")
			(hide yes)
			(effects
				(font
					(size 1.016 1.016)
					(thickness 0.1524)
				)
			)
		)
		(property "Device Type" "R402H16"
			(at 0.064008 -5.517896 0)
			(unlocked yes)
			(layer "F.Fab")
			(hide yes)
			(effects
				(font
					(size 1.016 1.016)
					(thickness 0.1524)
				)
			)
		)
		(duplicate_pad_numbers_are_jumpers no)
		(fp_line
			(start -0.508 -0.9398)
			(end -0.508 0.9398)
			(stroke
				(width 0.1524)
				(type default)
			)
			(layer "F.SilkS")
		)
		(fp_line
			(start 0.508 -0.9398)
			(end -0.508 -0.9398)
			(stroke
				(width 0.1524)
				(type default)
			)
			(layer "F.SilkS")
		)
		(fp_rect
			(start -0.508 0.9398)
			(end 0.508 -0.9398)
			(stroke
				(width 0)
				(type default)
			)
			(fill no)
			(layer "F.CrtYd")
		)
		(fp_rect
			(start -0.508 0.9398)
			(end 0.508 -0.9398)
			(stroke
				(width 0)
				(type default)
			)
			(fill no)
			(layer "F.Fab")
		)
		(pad "1" smd custom
			(at 0 -0.4445)
			(size 0.1397 0.1397)
			(layers "F.Cu" "F.Mask" "F.Paste")
			(net "P3V3_STBY")
			(options
				(clearance outline)
				(anchor circle)
			)
			(primitives
				(gr_poly
					(pts
						(arc
							(start -0.1778 -0.2794)
							(mid -0.249642 -0.249642)
							(end -0.2794 -0.1778)
						)
						(arc
							(start -0.2794 0.1778)
							(mid -0.249642 0.249642)
							(end -0.1778 0.2794)
						)
						(arc
							(start 0.1778 0.2794)
							(mid 0.249642 0.249642)
							(end 0.2794 0.1778)
						)
						(arc
							(start 0.2794 -0.1778)
							(mid 0.249642 -0.249642)
							(end 0.1778 -0.2794)
						)
					)
					(width 0)
					(fill yes)
				)
			)
		)
		(pad "2" smd custom
			(at 0 0.4445)
			(size 0.1397 0.1397)
			(layers "F.Cu" "F.Mask" "F.Paste")
			(net "GPIO_B_EXP_INT_N")
			(options
				(clearance outline)
				(anchor circle)
			)
			(primitives
				(gr_poly
					(pts
						(arc
							(start -0.1778 -0.2794)
							(mid -0.249642 -0.249642)
							(end -0.2794 -0.1778)
						)
						(arc
							(start -0.2794 0.1778)
							(mid -0.249642 0.249642)
							(end -0.1778 0.2794)
						)
						(arc
							(start 0.1778 0.2794)
							(mid 0.249642 0.249642)
							(end 0.2794 0.1778)
						)
						(arc
							(start 0.2794 -0.1778)
							(mid 0.249642 -0.249642)
							(end 0.1778 -0.2794)
						)
					)
					(width 0)
					(fill yes)
				)
			)
		)
	)
	(footprint ""
		(layer "F.Cu")
		(at 131.699 -21.971 -90)
		(property "Reference" "R116"
			(at 0 0 270)
			(layer "F.SilkS")
			(hide yes)
			(effects
				(font
					(size 1.27 1.27)
				)
			)
		)
		(property "Value" "10KR2F-2-GP"
			(at 0.064008 -3.993896 270)
			(unlocked yes)
			(layer "F.Fab")
			(hide yes)
			(effects
				(font
					(size 1.016 1.016)
					(thickness 0.1524)
				)
			)
		)
		(property "Device Type" "R402H16"
			(at 0.064008 -5.517896 270)
			(unlocked yes)
			(layer "F.Fab")
			(hide yes)
			(effects
				(font
					(size 1.016 1.016)
					(thickness 0.1524)
				)
			)
		)
		(duplicate_pad_numbers_are_jumpers no)
		(fp_line
			(start -0.508 -0.9398)
			(end -0.508 0.9398)
			(stroke
				(width 0.1524)
				(type default)
			)
			(layer "F.SilkS")
		)
		(fp_line
			(start 0.508 -0.9398)
			(end -0.508 -0.9398)
			(stroke
				(width 0.1524)
				(type default)
			)
			(layer "F.SilkS")
		)
		(fp_rect
			(start -0.508 0.9398)
			(end 0.508 -0.9398)
			(stroke
				(width 0)
				(type default)
			)
			(fill no)
			(layer "F.CrtYd")
		)
		(fp_rect
			(start -0.508 0.9398)
			(end 0.508 -0.9398)
			(stroke
				(width 0)
				(type default)
			)
			(fill no)
			(layer "F.Fab")
		)
		(pad "1" smd custom
			(at 0 -0.4445 270)
			(size 0.1397 0.1397)
			(layers "F.Cu" "F.Mask" "F.Paste")
			(net "P3V3_STBY")
			(options
				(clearance outline)
				(anchor circle)
			)
			(primitives
				(gr_poly
					(pts
						(arc
							(start -0.1778 -0.2794)
							(mid -0.249642 -0.249642)
							(end -0.2794 -0.1778)
						)
						(arc
							(start -0.2794 0.1778)
							(mid -0.249642 0.249642)
							(end -0.1778 0.2794)
						)
						(arc
							(start 0.1778 0.2794)
							(mid 0.249642 0.249642)
							(end 0.2794 0.1778)
						)
						(arc
							(start 0.2794 -0.1778)
							(mid 0.249642 -0.249642)
							(end 0.1778 -0.2794)
						)
					)
					(width 0)
					(fill yes)
				)
			)
		)
		(pad "2" smd custom
			(at 0 0.4445 270)
			(size 0.1397 0.1397)
			(layers "F.Cu" "F.Mask" "F.Paste")
			(net "GPIO_B_EXP_A0")
			(options
				(clearance outline)
				(anchor circle)
			)
			(primitives
				(gr_poly
					(pts
						(arc
							(start -0.1778 -0.2794)
							(mid -0.249642 -0.249642)
							(end -0.2794 -0.1778)
						)
						(arc
							(start -0.2794 0.1778)
							(mid -0.249642 0.249642)
							(end -0.1778 0.2794)
						)
						(arc
							(start 0.1778 0.2794)
							(mid 0.249642 0.249642)
							(end 0.2794 0.1778)
						)
						(arc
							(start 0.2794 -0.1778)
							(mid 0.249642 -0.249642)
							(end 0.1778 -0.2794)
						)
					)
					(width 0)
					(fill yes)
				)
			)
		)
	)
	(footprint ""
		(layer "F.Cu")
		(at 17.10055 -18.89125 135)
		(property "Reference" "R80"
			(at 0 0 135)
			(layer "F.SilkS")
			(hide yes)
			(effects
				(font
					(size 1.27 1.27)
				)
			)
		)
		(property "Value" "10R2F-L-GP"
			(at 0.063939 -3.993984 135)
			(unlocked yes)
			(layer "F.Fab")
			(hide yes)
			(effects
				(font
					(size 1.016 1.016)
					(thickness 0.1524)
				)
			)
		)
		(property "Device Type" "R402H14"
			(at 0.063939 -5.518113 135)
			(unlocked yes)
			(layer "F.Fab")
			(hide yes)
			(effects
				(font
					(size 1.016 1.016)
					(thickness 0.1524)
				)
			)
		)
		(duplicate_pad_numbers_are_jumpers no)
		(fp_line
			(start 0.507923 -0.940053)
			(end -0.507923 -0.940053)
			(stroke
				(width 0.1524)
				(type default)
			)
			(layer "F.SilkS")
		)
		(fp_line
			(start -0.507923 -0.940053)
			(end -0.507923 0.939694)
			(stroke
				(width 0.1524)
				(type default)
			)
			(layer "F.SilkS")
		)
		(fp_poly
			(pts
				(xy -0.507923 -0.939906) (xy 0.508077 -0.939905) (xy 0.508076 0.939694) (xy -0.507923 0.939694)
			)
			(stroke
				(width 0)
				(type default)
			)
			(fill no)
			(layer "F.CrtYd")
		)
		(fp_poly
			(pts
				(xy -0.507923 -0.939906) (xy 0.508077 -0.939905) (xy 0.508076 0.939694) (xy -0.507923 0.939694)
			)
			(stroke
				(width 0)
				(type default)
			)
			(fill no)
			(layer "F.Fab")
		)
		(pad "1" smd custom
			(at 0 -0.4445 135)
			(size 0.1397 0.1397)
			(layers "F.Cu" "F.Mask" "F.Paste")
			(net "P12V")
			(options
				(clearance outline)
				(anchor circle)
			)
			(primitives
				(gr_poly
					(pts
						(arc
							(start -0.1778 -0.2794)
							(mid -0.249642 -0.249642)
							(end -0.2794 -0.1778)
						)
						(arc
							(start -0.2794 0.1778)
							(mid -0.249642 0.249642)
							(end -0.1778 0.2794)
						)
						(arc
							(start 0.1778 0.2794)
							(mid 0.249642 0.249642)
							(end 0.2794 0.1778)
						)
						(arc
							(start 0.2794 -0.1778)
							(mid 0.249642 -0.249642)
							(end 0.1778 -0.2794)
						)
					)
					(width 0)
					(fill yes)
				)
			)
		)
		(pad "2" smd custom
			(at 0 0.4445 135)
			(size 0.1397 0.1397)
			(layers "F.Cu" "F.Mask" "F.Paste")
			(net "SLOT2_P12V_SENSE_VP_R")
			(options
				(clearance outline)
				(anchor circle)
			)
			(primitives
				(gr_poly
					(pts
						(arc
							(start -0.1778 -0.2794)
							(mid -0.249642 -0.249642)
							(end -0.2794 -0.1778)
						)
						(arc
							(start -0.2794 0.1778)
							(mid -0.249642 0.249642)
							(end -0.1778 0.2794)
						)
						(arc
							(start 0.1778 0.2794)
							(mid 0.249642 0.249642)
							(end 0.2794 0.1778)
						)
						(arc
							(start 0.2794 -0.1778)
							(mid 0.249642 -0.249642)
							(end 0.1778 -0.2794)
						)
					)
					(width 0)
					(fill yes)
				)
			)
		)
	)
	(footprint ""
		(layer "F.Cu")
		(at 96.647 -16.8656)
		(property "Reference" "R73"
			(at 0 0 0)
			(layer "F.SilkS")
			(hide yes)
			(effects
				(font
					(size 1.27 1.27)
				)
			)
		)
		(property "Value" "0R2F-1-GP"
			(at 0.064008 -3.993896 0)
			(unlocked yes)
			(layer "F.Fab")
			(hide yes)
			(effects
				(font
					(size 1.016 1.016)
					(thickness 0.1524)
				)
			)
		)
		(property "Device Type" "R402H16"
			(at 0.064008 -5.517896 0)
			(unlocked yes)
			(layer "F.Fab")
			(hide yes)
			(effects
				(font
					(size 1.016 1.016)
					(thickness 0.1524)
				)
			)
		)
		(duplicate_pad_numbers_are_jumpers no)
		(fp_line
			(start -0.508 -0.9398)
			(end -0.508 0.9398)
			(stroke
				(width 0.1524)
				(type default)
			)
			(layer "F.SilkS")
		)
		(fp_line
			(start 0.508 -0.9398)
			(end -0.508 -0.9398)
			(stroke
				(width 0.1524)
				(type default)
			)
			(layer "F.SilkS")
		)
		(fp_rect
			(start -0.508 0.9398)
			(end 0.508 -0.9398)
			(stroke
				(width 0)
				(type default)
			)
			(fill no)
			(layer "F.CrtYd")
		)
		(fp_rect
			(start -0.508 0.9398)
			(end 0.508 -0.9398)
			(stroke
				(width 0)
				(type default)
			)
			(fill no)
			(layer "F.Fab")
		)
		(pad "1" smd custom
			(at 0 -0.4445)
			(size 0.1397 0.1397)
			(layers "F.Cu" "F.Mask" "F.Paste")
			(net "PERST_SLOT_N")
			(options
				(clearance outline)
				(anchor circle)
			)
			(primitives
				(gr_poly
					(pts
						(arc
							(start -0.1778 -0.2794)
							(mid -0.249642 -0.249642)
							(end -0.2794 -0.1778)
						)
						(arc
							(start -0.2794 0.1778)
							(mid -0.249642 0.249642)
							(end -0.1778 0.2794)
						)
						(arc
							(start 0.1778 0.2794)
							(mid 0.249642 0.249642)
							(end 0.2794 0.1778)
						)
						(arc
							(start 0.2794 -0.1778)
							(mid 0.249642 -0.249642)
							(end 0.1778 -0.2794)
						)
					)
					(width 0)
					(fill yes)
				)
			)
		)
		(pad "2" smd custom
			(at 0 0.4445)
			(size 0.1397 0.1397)
			(layers "F.Cu" "F.Mask" "F.Paste")
			(net "USB_RESET_N")
			(options
				(clearance outline)
				(anchor circle)
			)
			(primitives
				(gr_poly
					(pts
						(arc
							(start -0.1778 -0.2794)
							(mid -0.249642 -0.249642)
							(end -0.2794 -0.1778)
						)
						(arc
							(start -0.2794 0.1778)
							(mid -0.249642 0.249642)
							(end -0.1778 0.2794)
						)
						(arc
							(start 0.1778 0.2794)
							(mid 0.249642 0.249642)
							(end 0.2794 0.1778)
						)
						(arc
							(start 0.2794 -0.1778)
							(mid 0.249642 -0.249642)
							(end 0.1778 -0.2794)
						)
					)
					(width 0)
					(fill yes)
				)
			)
		)
	)
	(footprint ""
		(layer "F.Cu")
		(at 123.2916 -22.8346 90)
		(property "Reference" "RU28"
			(at 0 0 90)
			(layer "F.SilkS")
			(hide yes)
			(effects
				(font
					(size 1.27 1.27)
				)
			)
		)
		(property "Value" "10KR2F-2-GP"
			(at 0.064008 -3.993896 90)
			(unlocked yes)
			(layer "F.Fab")
			(hide yes)
			(effects
				(font
					(size 1.016 1.016)
					(thickness 0.1524)
				)
			)
		)
		(property "Device Type" "R402H16"
			(at 0.064008 -5.517896 90)
			(unlocked yes)
			(layer "F.Fab")
			(hide yes)
			(effects
				(font
					(size 1.016 1.016)
					(thickness 0.1524)
				)
			)
		)
		(duplicate_pad_numbers_are_jumpers no)
		(fp_line
			(start 0.508 -0.9398)
			(end -0.508 -0.9398)
			(stroke
				(width 0.1524)
				(type default)
			)
			(layer "F.SilkS")
		)
		(fp_line
			(start -0.508 -0.9398)
			(end -0.508 0.9398)
			(stroke
				(width 0.1524)
				(type default)
			)
			(layer "F.SilkS")
		)
		(fp_rect
			(start -0.508 0.9398)
			(end 0.508 -0.9398)
			(stroke
				(width 0)
				(type default)
			)
			(fill no)
			(layer "F.CrtYd")
		)
		(fp_rect
			(start -0.508 0.9398)
			(end 0.508 -0.9398)
			(stroke
				(width 0)
				(type default)
			)
			(fill no)
			(layer "F.Fab")
		)
		(pad "1" smd custom
			(at 0 -0.4445 90)
			(size 0.1397 0.1397)
			(layers "F.Cu" "F.Mask" "F.Paste")
			(net "SMCLK_USB_HUB_R")
			(options
				(clearance outline)
				(anchor circle)
			)
			(primitives
				(gr_poly
					(pts
						(arc
							(start -0.1778 -0.2794)
							(mid -0.249642 -0.249642)
							(end -0.2794 -0.1778)
						)
						(arc
							(start -0.2794 0.1778)
							(mid -0.249642 0.249642)
							(end -0.1778 0.2794)
						)
						(arc
							(start 0.1778 0.2794)
							(mid 0.249642 0.249642)
							(end 0.2794 0.1778)
						)
						(arc
							(start 0.2794 -0.1778)
							(mid 0.249642 -0.249642)
							(end 0.1778 -0.2794)
						)
					)
					(width 0)
					(fill yes)
				)
			)
		)
		(pad "2" smd custom
			(at 0 0.4445 90)
			(size 0.1397 0.1397)
			(layers "F.Cu" "F.Mask" "F.Paste")
			(net "GND")
			(options
				(clearance outline)
				(anchor circle)
			)
			(primitives
				(gr_poly
					(pts
						(arc
							(start -0.1778 -0.2794)
							(mid -0.249642 -0.249642)
							(end -0.2794 -0.1778)
						)
						(arc
							(start -0.2794 0.1778)
							(mid -0.249642 0.249642)
							(end -0.1778 0.2794)
						)
						(arc
							(start 0.1778 0.2794)
							(mid 0.249642 0.249642)
							(end 0.2794 0.1778)
						)
						(arc
							(start 0.2794 -0.1778)
							(mid 0.249642 -0.249642)
							(end 0.1778 -0.2794)
						)
					)
					(width 0)
					(fill yes)
				)
			)
		)
	)
	(footprint ""
		(layer "F.Cu")
		(at 111.6584 -1.4732 -90)
		(property "Reference" "R58"
			(at 0 0 270)
			(layer "F.SilkS")
			(hide yes)
			(effects
				(font
					(size 1.27 1.27)
				)
			)
		)
		(property "Value" "10KR2F-2-GP"
			(at 0.064008 -3.993896 270)
			(unlocked yes)
			(layer "F.Fab")
			(hide yes)
			(effects
				(font
					(size 1.016 1.016)
					(thickness 0.1524)
				)
			)
		)
		(property "Device Type" "R402H16"
			(at 0.064008 -5.517896 270)
			(unlocked yes)
			(layer "F.Fab")
			(hide yes)
			(effects
				(font
					(size 1.016 1.016)
					(thickness 0.1524)
				)
			)
		)
		(duplicate_pad_numbers_are_jumpers no)
		(fp_line
			(start -0.508 -0.9398)
			(end -0.508 0.9398)
			(stroke
				(width 0.1524)
				(type default)
			)
			(layer "F.SilkS")
		)
		(fp_line
			(start 0.508 -0.9398)
			(end -0.508 -0.9398)
			(stroke
				(width 0.1524)
				(type default)
			)
			(layer "F.SilkS")
		)
		(fp_rect
			(start -0.508 0.9398)
			(end 0.508 -0.9398)
			(stroke
				(width 0)
				(type default)
			)
			(fill no)
			(layer "F.CrtYd")
		)
		(fp_rect
			(start -0.508 0.9398)
			(end 0.508 -0.9398)
			(stroke
				(width 0)
				(type default)
			)
			(fill no)
			(layer "F.Fab")
		)
		(pad "1" smd custom
			(at 0 -0.4445 270)
			(size 0.1397 0.1397)
			(layers "F.Cu" "F.Mask" "F.Paste")
			(net "PU_I2CMUX_INT2_N")
			(options
				(clearance outline)
				(anchor circle)
			)
			(primitives
				(gr_poly
					(pts
						(arc
							(start -0.1778 -0.2794)
							(mid -0.249642 -0.249642)
							(end -0.2794 -0.1778)
						)
						(arc
							(start -0.2794 0.1778)
							(mid -0.249642 0.249642)
							(end -0.1778 0.2794)
						)
						(arc
							(start 0.1778 0.2794)
							(mid 0.249642 0.249642)
							(end 0.2794 0.1778)
						)
						(arc
							(start 0.2794 -0.1778)
							(mid 0.249642 -0.249642)
							(end 0.1778 -0.2794)
						)
					)
					(width 0)
					(fill yes)
				)
			)
		)
		(pad "2" smd custom
			(at 0 0.4445 270)
			(size 0.1397 0.1397)
			(layers "F.Cu" "F.Mask" "F.Paste")
			(net "P3V3_STBY")
			(options
				(clearance outline)
				(anchor circle)
			)
			(primitives
				(gr_poly
					(pts
						(arc
							(start -0.1778 -0.2794)
							(mid -0.249642 -0.249642)
							(end -0.2794 -0.1778)
						)
						(arc
							(start -0.2794 0.1778)
							(mid -0.249642 0.249642)
							(end -0.1778 0.2794)
						)
						(arc
							(start 0.1778 0.2794)
							(mid 0.249642 0.249642)
							(end 0.2794 0.1778)
						)
						(arc
							(start 0.2794 -0.1778)
							(mid 0.249642 -0.249642)
							(end 0.1778 -0.2794)
						)
					)
					(width 0)
					(fill yes)
				)
			)
		)
	)
	(footprint ""
		(layer "F.Cu")
		(at 101.219 -21.6916)
		(property "Reference" "R79"
			(at 0 0 0)
			(layer "F.SilkS")
			(hide yes)
			(effects
				(font
					(size 1.27 1.27)
				)
			)
		)
		(property "Value" "4K7R2F-GP"
			(at 0.064008 -3.993896 0)
			(unlocked yes)
			(layer "F.Fab")
			(hide yes)
			(effects
				(font
					(size 1.016 1.016)
					(thickness 0.1524)
				)
			)
		)
		(property "Device Type" "R402H16"
			(at 0.064008 -5.517896 0)
			(unlocked yes)
			(layer "F.Fab")
			(hide yes)
			(effects
				(font
					(size 1.016 1.016)
					(thickness 0.1524)
				)
			)
		)
		(duplicate_pad_numbers_are_jumpers no)
		(fp_line
			(start -0.508 -0.9398)
			(end -0.508 0.9398)
			(stroke
				(width 0.1524)
				(type default)
			)
			(layer "F.SilkS")
		)
		(fp_line
			(start 0.508 -0.9398)
			(end -0.508 -0.9398)
			(stroke
				(width 0.1524)
				(type default)
			)
			(layer "F.SilkS")
		)
		(fp_rect
			(start -0.508 0.9398)
			(end 0.508 -0.9398)
			(stroke
				(width 0)
				(type default)
			)
			(fill no)
			(layer "F.CrtYd")
		)
		(fp_rect
			(start -0.508 0.9398)
			(end 0.508 -0.9398)
			(stroke
				(width 0)
				(type default)
			)
			(fill no)
			(layer "F.Fab")
		)
		(pad "1" smd custom
			(at 0 -0.4445)
			(size 0.1397 0.1397)
			(layers "F.Cu" "F.Mask" "F.Paste")
			(net "P3V3")
			(options
				(clearance outline)
				(anchor circle)
			)
			(primitives
				(gr_poly
					(pts
						(arc
							(start -0.1778 -0.2794)
							(mid -0.249642 -0.249642)
							(end -0.2794 -0.1778)
						)
						(arc
							(start -0.2794 0.1778)
							(mid -0.249642 0.249642)
							(end -0.1778 0.2794)
						)
						(arc
							(start 0.1778 0.2794)
							(mid 0.249642 0.249642)
							(end 0.2794 0.1778)
						)
						(arc
							(start 0.2794 -0.1778)
							(mid 0.249642 -0.249642)
							(end 0.1778 -0.2794)
						)
					)
					(width 0)
					(fill yes)
				)
			)
		)
		(pad "2" smd custom
			(at 0 0.4445)
			(size 0.1397 0.1397)
			(layers "F.Cu" "F.Mask" "F.Paste")
			(net "RESET_O_2_R")
			(options
				(clearance outline)
				(anchor circle)
			)
			(primitives
				(gr_poly
					(pts
						(arc
							(start -0.1778 -0.2794)
							(mid -0.249642 -0.249642)
							(end -0.2794 -0.1778)
						)
						(arc
							(start -0.2794 0.1778)
							(mid -0.249642 0.249642)
							(end -0.1778 0.2794)
						)
						(arc
							(start 0.1778 0.2794)
							(mid 0.249642 0.249642)
							(end 0.2794 0.1778)
						)
						(arc
							(start 0.2794 -0.1778)
							(mid 0.249642 -0.249642)
							(end 0.1778 -0.2794)
						)
					)
					(width 0)
					(fill yes)
				)
			)
		)
	)
	(footprint ""
		(layer "F.Cu")
		(at 130.5814 1.9812 -90)
		(property "Reference" "R25"
			(at 0 0 270)
			(layer "F.SilkS")
			(hide yes)
			(effects
				(font
					(size 1.27 1.27)
				)
			)
		)
		(property "Value" "4K7R2F-GP"
			(at 0.064008 -3.993896 270)
			(unlocked yes)
			(layer "F.Fab")
			(hide yes)
			(effects
				(font
					(size 1.016 1.016)
					(thickness 0.1524)
				)
			)
		)
		(property "Device Type" "R402H16"
			(at 0.064008 -5.517896 270)
			(unlocked yes)
			(layer "F.Fab")
			(hide yes)
			(effects
				(font
					(size 1.016 1.016)
					(thickness 0.1524)
				)
			)
		)
		(duplicate_pad_numbers_are_jumpers no)
		(fp_line
			(start -0.508 -0.9398)
			(end -0.508 0.9398)
			(stroke
				(width 0.1524)
				(type default)
			)
			(layer "F.SilkS")
		)
		(fp_line
			(start 0.508 -0.9398)
			(end -0.508 -0.9398)
			(stroke
				(width 0.1524)
				(type default)
			)
			(layer "F.SilkS")
		)
		(fp_rect
			(start -0.508 0.9398)
			(end 0.508 -0.9398)
			(stroke
				(width 0)
				(type default)
			)
			(fill no)
			(layer "F.CrtYd")
		)
		(fp_rect
			(start -0.508 0.9398)
			(end 0.508 -0.9398)
			(stroke
				(width 0)
				(type default)
			)
			(fill no)
			(layer "F.Fab")
		)
		(pad "1" smd custom
			(at 0 -0.4445 270)
			(size 0.1397 0.1397)
			(layers "F.Cu" "F.Mask" "F.Paste")
			(net "P3V3_STBY")
			(options
				(clearance outline)
				(anchor circle)
			)
			(primitives
				(gr_poly
					(pts
						(arc
							(start -0.1778 -0.2794)
							(mid -0.249642 -0.249642)
							(end -0.2794 -0.1778)
						)
						(arc
							(start -0.2794 0.1778)
							(mid -0.249642 0.249642)
							(end -0.1778 0.2794)
						)
						(arc
							(start 0.1778 0.2794)
							(mid 0.249642 0.249642)
							(end 0.2794 0.1778)
						)
						(arc
							(start 0.2794 -0.1778)
							(mid 0.249642 -0.249642)
							(end 0.1778 -0.2794)
						)
					)
					(width 0)
					(fill yes)
				)
			)
		)
		(pad "2" smd custom
			(at 0 0.4445 270)
			(size 0.1397 0.1397)
			(layers "F.Cu" "F.Mask" "F.Paste")
			(net "SMDAT_PCH_DEVICE")
			(options
				(clearance outline)
				(anchor circle)
			)
			(primitives
				(gr_poly
					(pts
						(arc
							(start -0.1778 -0.2794)
							(mid -0.249642 -0.249642)
							(end -0.2794 -0.1778)
						)
						(arc
							(start -0.2794 0.1778)
							(mid -0.249642 0.249642)
							(end -0.1778 0.2794)
						)
						(arc
							(start 0.1778 0.2794)
							(mid 0.249642 0.249642)
							(end 0.2794 0.1778)
						)
						(arc
							(start 0.2794 -0.1778)
							(mid 0.249642 -0.249642)
							(end 0.1778 -0.2794)
						)
					)
					(width 0)
					(fill yes)
				)
			)
		)
	)
	(footprint ""
		(layer "F.Cu")
		(at 33.0581 -3.6195 -90)
		(property "Reference" "C799"
			(at 0 0 270)
			(layer "F.SilkS")
			(hide yes)
			(effects
				(font
					(size 1.27 1.27)
				)
			)
		)
		(property "Value" "SC22U6D3V5MX-5-GP"
			(at -0.0762 -6.1214 270)
			(unlocked yes)
			(layer "F.Fab")
			(hide yes)
			(effects
				(font
					(size 1.016 1.016)
					(thickness 0.1524)
				)
			)
		)
		(property "Device Type" "C805H56"
			(at -0.0762 -8.1534 270)
			(unlocked yes)
			(layer "F.Fab")
			(hide yes)
			(effects
				(font
					(size 1.016 1.016)
					(thickness 0.1524)
				)
			)
		)
		(duplicate_pad_numbers_are_jumpers no)
		(fp_line
			(start 0.635 0)
			(end -0.635 0)
			(stroke
				(width 0.508)
				(type default)
			)
			(layer "F.SilkS")
		)
		(fp_rect
			(start -0.9652 1.778)
			(end 0.9652 -1.778)
			(stroke
				(width 0)
				(type default)
			)
			(fill no)
			(layer "F.CrtYd")
		)
		(fp_poly
			(pts
				(xy -0.9652 -1.778) (xy 0.9652 -1.778) (xy 0.9652 1.778) (xy -0.9652 1.778)
			)
			(stroke
				(width 0)
				(type default)
			)
			(fill no)
			(layer "F.Fab")
		)
		(pad "1" smd rect
			(at 0 -0.9652 270)
			(size 1.397 1.143)
			(layers "F.Cu" "F.Mask" "F.Paste")
			(net "P3V3")
		)
		(pad "2" smd rect
			(at 0 0.9652 270)
			(size 1.397 1.143)
			(layers "F.Cu" "F.Mask" "F.Paste")
			(net "GND")
		)
	)
	(footprint ""
		(layer "F.Cu")
		(at 132.2324 -7.8232 90)
		(property "Reference" "R146"
			(at 0 0 90)
			(layer "F.SilkS")
			(hide yes)
			(effects
				(font
					(size 1.27 1.27)
				)
			)
		)
		(property "Value" "10KR2F-2-GP"
			(at 0.064008 -3.993896 90)
			(unlocked yes)
			(layer "F.Fab")
			(hide yes)
			(effects
				(font
					(size 1.016 1.016)
					(thickness 0.1524)
				)
			)
		)
		(property "Device Type" "R402H16"
			(at 0.064008 -5.517896 90)
			(unlocked yes)
			(layer "F.Fab")
			(hide yes)
			(effects
				(font
					(size 1.016 1.016)
					(thickness 0.1524)
				)
			)
		)
		(duplicate_pad_numbers_are_jumpers no)
		(fp_line
			(start 0.508 -0.9398)
			(end -0.508 -0.9398)
			(stroke
				(width 0.1524)
				(type default)
			)
			(layer "F.SilkS")
		)
		(fp_line
			(start -0.508 -0.9398)
			(end -0.508 0.9398)
			(stroke
				(width 0.1524)
				(type default)
			)
			(layer "F.SilkS")
		)
		(fp_rect
			(start -0.508 0.9398)
			(end 0.508 -0.9398)
			(stroke
				(width 0)
				(type default)
			)
			(fill no)
			(layer "F.CrtYd")
		)
		(fp_rect
			(start -0.508 0.9398)
			(end 0.508 -0.9398)
			(stroke
				(width 0)
				(type default)
			)
			(fill no)
			(layer "F.Fab")
		)
		(pad "1" smd custom
			(at 0 -0.4445 90)
			(size 0.1397 0.1397)
			(layers "F.Cu" "F.Mask" "F.Paste")
			(net "GPIO_P_EXP_A1")
			(options
				(clearance outline)
				(anchor circle)
			)
			(primitives
				(gr_poly
					(pts
						(arc
							(start -0.1778 -0.2794)
							(mid -0.249642 -0.249642)
							(end -0.2794 -0.1778)
						)
						(arc
							(start -0.2794 0.1778)
							(mid -0.249642 0.249642)
							(end -0.1778 0.2794)
						)
						(arc
							(start 0.1778 0.2794)
							(mid 0.249642 0.249642)
							(end 0.2794 0.1778)
						)
						(arc
							(start 0.2794 -0.1778)
							(mid 0.249642 -0.249642)
							(end 0.1778 -0.2794)
						)
					)
					(width 0)
					(fill yes)
				)
			)
		)
		(pad "2" smd custom
			(at 0 0.4445 90)
			(size 0.1397 0.1397)
			(layers "F.Cu" "F.Mask" "F.Paste")
			(net "GND")
			(options
				(clearance outline)
				(anchor circle)
			)
			(primitives
				(gr_poly
					(pts
						(arc
							(start -0.1778 -0.2794)
							(mid -0.249642 -0.249642)
							(end -0.2794 -0.1778)
						)
						(arc
							(start -0.2794 0.1778)
							(mid -0.249642 0.249642)
							(end -0.1778 0.2794)
						)
						(arc
							(start 0.1778 0.2794)
							(mid 0.249642 0.249642)
							(end 0.2794 0.1778)
						)
						(arc
							(start 0.2794 -0.1778)
							(mid 0.249642 -0.249642)
							(end 0.1778 -0.2794)
						)
					)
					(width 0)
					(fill yes)
				)
			)
		)
	)
	(footprint ""
		(layer "F.Cu")
		(at 33.44164 -24.08682 180)
		(property "Reference" "R37"
			(at 0 0 180)
			(layer "F.SilkS")
			(hide yes)
			(effects
				(font
					(size 1.27 1.27)
				)
			)
		)
		(property "Value" "0R2F-1-GP"
			(at 0.064008 -3.993896 180)
			(unlocked yes)
			(layer "F.Fab")
			(hide yes)
			(effects
				(font
					(size 1.016 1.016)
					(thickness 0.1524)
				)
			)
		)
		(property "Device Type" "R402H16"
			(at 0.064008 -5.517896 180)
			(unlocked yes)
			(layer "F.Fab")
			(hide yes)
			(effects
				(font
					(size 1.016 1.016)
					(thickness 0.1524)
				)
			)
		)
		(duplicate_pad_numbers_are_jumpers no)
		(fp_line
			(start 0.508 -0.9398)
			(end -0.508 -0.9398)
			(stroke
				(width 0.1524)
				(type default)
			)
			(layer "F.SilkS")
		)
		(fp_line
			(start -0.508 -0.9398)
			(end -0.508 0.9398)
			(stroke
				(width 0.1524)
				(type default)
			)
			(layer "F.SilkS")
		)
		(fp_rect
			(start -0.508 0.9398)
			(end 0.508 -0.9398)
			(stroke
				(width 0)
				(type default)
			)
			(fill no)
			(layer "F.CrtYd")
		)
		(fp_rect
			(start -0.508 0.9398)
			(end 0.508 -0.9398)
			(stroke
				(width 0)
				(type default)
			)
			(fill no)
			(layer "F.Fab")
		)
		(pad "1" smd custom
			(at 0 -0.4445 180)
			(size 0.1397 0.1397)
			(layers "F.Cu" "F.Mask" "F.Paste")
			(net "SMDAT_PCH_SLOT3")
			(options
				(clearance outline)
				(anchor circle)
			)
			(primitives
				(gr_poly
					(pts
						(arc
							(start -0.1778 -0.2794)
							(mid -0.249642 -0.249642)
							(end -0.2794 -0.1778)
						)
						(arc
							(start -0.2794 0.1778)
							(mid -0.249642 0.249642)
							(end -0.1778 0.2794)
						)
						(arc
							(start 0.1778 0.2794)
							(mid 0.249642 0.249642)
							(end 0.2794 0.1778)
						)
						(arc
							(start 0.2794 -0.1778)
							(mid 0.249642 -0.249642)
							(end 0.1778 -0.2794)
						)
					)
					(width 0)
					(fill yes)
				)
			)
		)
		(pad "2" smd custom
			(at 0 0.4445 180)
			(size 0.1397 0.1397)
			(layers "F.Cu" "F.Mask" "F.Paste")
			(net "SMDAT_PCH_SLOT3_R")
			(options
				(clearance outline)
				(anchor circle)
			)
			(primitives
				(gr_poly
					(pts
						(arc
							(start -0.1778 -0.2794)
							(mid -0.249642 -0.249642)
							(end -0.2794 -0.1778)
						)
						(arc
							(start -0.2794 0.1778)
							(mid -0.249642 0.249642)
							(end -0.1778 0.2794)
						)
						(arc
							(start 0.1778 0.2794)
							(mid 0.249642 0.249642)
							(end 0.2794 0.1778)
						)
						(arc
							(start 0.2794 -0.1778)
							(mid 0.249642 -0.249642)
							(end 0.1778 -0.2794)
						)
					)
					(width 0)
					(fill yes)
				)
			)
		)
	)
	(footprint ""
		(layer "F.Cu")
		(at 28.3972 -2.0828 180)
		(property "Reference" "PC5"
			(at 0 0 180)
			(layer "F.SilkS")
			(hide yes)
			(effects
				(font
					(size 1.27 1.27)
				)
			)
		)
		(property "Value" "SCD1U16V3KX-3GP"
			(at 0 -2.8194 180)
			(unlocked yes)
			(layer "F.Fab")
			(hide yes)
			(effects
				(font
					(size 1.016 1.016)
					(thickness 0.1524)
				)
			)
		)
		(property "Device Type" "C603H36"
			(at 0 -4.3434 180)
			(unlocked yes)
			(layer "F.Fab")
			(hide yes)
			(effects
				(font
					(size 1.016 1.016)
					(thickness 0.1524)
				)
			)
		)
		(duplicate_pad_numbers_are_jumpers no)
		(fp_line
			(start 0.508 0)
			(end -0.508 0)
			(stroke
				(width 0.2032)
				(type default)
			)
			(layer "F.SilkS")
		)
		(fp_rect
			(start -0.5842 1.3335)
			(end 0.5842 -1.3335)
			(stroke
				(width 0)
				(type default)
			)
			(fill no)
			(layer "F.CrtYd")
		)
		(fp_rect
			(start -0.5842 1.3335)
			(end 0.5842 -1.3335)
			(stroke
				(width 0)
				(type default)
			)
			(fill no)
			(layer "F.Fab")
		)
		(pad "1" smd custom
			(at 0 -0.762 180)
			(size 0.2159 0.2159)
			(layers "F.Cu" "F.Mask" "F.Paste")
			(net "P3V3_VR")
			(options
				(clearance outline)
				(anchor circle)
			)
			(primitives
				(gr_poly
					(pts
						(arc
							(start -0.3302 -0.4318)
							(mid -0.402042 -0.402042)
							(end -0.4318 -0.3302)
						)
						(arc
							(start -0.4318 0.3302)
							(mid -0.402042 0.402042)
							(end -0.3302 0.4318)
						)
						(arc
							(start 0.3302 0.4318)
							(mid 0.402042 0.402042)
							(end 0.4318 0.3302)
						)
						(arc
							(start 0.4318 -0.3302)
							(mid 0.402042 -0.402042)
							(end 0.3302 -0.4318)
						)
					)
					(width 0)
					(fill yes)
				)
			)
		)
		(pad "2" smd custom
			(at 0 0.762 180)
			(size 0.2159 0.2159)
			(layers "F.Cu" "F.Mask" "F.Paste")
			(net "GND")
			(options
				(clearance outline)
				(anchor circle)
			)
			(primitives
				(gr_poly
					(pts
						(arc
							(start -0.3302 -0.4318)
							(mid -0.402042 -0.402042)
							(end -0.4318 -0.3302)
						)
						(arc
							(start -0.4318 0.3302)
							(mid -0.402042 0.402042)
							(end -0.3302 0.4318)
						)
						(arc
							(start 0.3302 0.4318)
							(mid 0.402042 0.402042)
							(end 0.4318 0.3302)
						)
						(arc
							(start 0.4318 -0.3302)
							(mid 0.402042 -0.402042)
							(end 0.3302 -0.4318)
						)
					)
					(width 0)
					(fill yes)
				)
			)
		)
	)
	(footprint ""
		(layer "F.Cu")
		(at 26.1874 -7.239 -90)
		(property "Reference" "C13"
			(at 0 0 270)
			(layer "F.SilkS")
			(hide yes)
			(effects
				(font
					(size 1.27 1.27)
				)
			)
		)
		(property "Value" "SCD1U25V3KX-GP"
			(at 0 -2.8194 270)
			(unlocked yes)
			(layer "F.Fab")
			(hide yes)
			(effects
				(font
					(size 1.016 1.016)
					(thickness 0.1524)
				)
			)
		)
		(property "Device Type" "C603H36"
			(at 0 -4.3434 270)
			(unlocked yes)
			(layer "F.Fab")
			(hide yes)
			(effects
				(font
					(size 1.016 1.016)
					(thickness 0.1524)
				)
			)
		)
		(duplicate_pad_numbers_are_jumpers no)
		(fp_line
			(start 0.508 0)
			(end -0.508 0)
			(stroke
				(width 0.2032)
				(type default)
			)
			(layer "F.SilkS")
		)
		(fp_rect
			(start -0.5842 1.3335)
			(end 0.5842 -1.3335)
			(stroke
				(width 0)
				(type default)
			)
			(fill no)
			(layer "F.CrtYd")
		)
		(fp_rect
			(start -0.5842 1.3335)
			(end 0.5842 -1.3335)
			(stroke
				(width 0)
				(type default)
			)
			(fill no)
			(layer "F.Fab")
		)
		(pad "1" smd custom
			(at 0 -0.762 270)
			(size 0.2159 0.2159)
			(layers "F.Cu" "F.Mask" "F.Paste")
			(net "P12V_SLOT2")
			(options
				(clearance outline)
				(anchor circle)
			)
			(primitives
				(gr_poly
					(pts
						(arc
							(start -0.3302 -0.4318)
							(mid -0.402042 -0.402042)
							(end -0.4318 -0.3302)
						)
						(arc
							(start -0.4318 0.3302)
							(mid -0.402042 0.402042)
							(end -0.3302 0.4318)
						)
						(arc
							(start 0.3302 0.4318)
							(mid 0.402042 0.402042)
							(end 0.4318 0.3302)
						)
						(arc
							(start 0.4318 -0.3302)
							(mid 0.402042 -0.402042)
							(end 0.3302 -0.4318)
						)
					)
					(width 0)
					(fill yes)
				)
			)
		)
		(pad "2" smd custom
			(at 0 0.762 270)
			(size 0.2159 0.2159)
			(layers "F.Cu" "F.Mask" "F.Paste")
			(net "GND")
			(options
				(clearance outline)
				(anchor circle)
			)
			(primitives
				(gr_poly
					(pts
						(arc
							(start -0.3302 -0.4318)
							(mid -0.402042 -0.402042)
							(end -0.4318 -0.3302)
						)
						(arc
							(start -0.4318 0.3302)
							(mid -0.402042 0.402042)
							(end -0.3302 0.4318)
						)
						(arc
							(start 0.3302 0.4318)
							(mid 0.402042 0.402042)
							(end 0.4318 0.3302)
						)
						(arc
							(start 0.4318 -0.3302)
							(mid 0.402042 -0.402042)
							(end 0.3302 -0.4318)
						)
					)
					(width 0)
					(fill yes)
				)
			)
		)
	)
	(footprint ""
		(layer "F.Cu")
		(at 130.4036 -24.4856 90)
		(property "Reference" "RU33"
			(at 0 0 90)
			(layer "F.SilkS")
			(hide yes)
			(effects
				(font
					(size 1.27 1.27)
				)
			)
		)
		(property "Value" "100KR2F-L1-GP"
			(at 0.064008 -3.993896 90)
			(unlocked yes)
			(layer "F.Fab")
			(hide yes)
			(effects
				(font
					(size 1.016 1.016)
					(thickness 0.1524)
				)
			)
		)
		(property "Device Type" "R402H16"
			(at 0.064008 -5.517896 90)
			(unlocked yes)
			(layer "F.Fab")
			(hide yes)
			(effects
				(font
					(size 1.016 1.016)
					(thickness 0.1524)
				)
			)
		)
		(duplicate_pad_numbers_are_jumpers no)
		(fp_line
			(start 0.508 -0.9398)
			(end -0.508 -0.9398)
			(stroke
				(width 0.1524)
				(type default)
			)
			(layer "F.SilkS")
		)
		(fp_line
			(start -0.508 -0.9398)
			(end -0.508 0.9398)
			(stroke
				(width 0.1524)
				(type default)
			)
			(layer "F.SilkS")
		)
		(fp_rect
			(start -0.508 0.9398)
			(end 0.508 -0.9398)
			(stroke
				(width 0)
				(type default)
			)
			(fill no)
			(layer "F.CrtYd")
		)
		(fp_rect
			(start -0.508 0.9398)
			(end 0.508 -0.9398)
			(stroke
				(width 0)
				(type default)
			)
			(fill no)
			(layer "F.Fab")
		)
		(pad "1" smd custom
			(at 0 -0.4445 90)
			(size 0.1397 0.1397)
			(layers "F.Cu" "F.Mask" "F.Paste")
			(net "NON_REM0")
			(options
				(clearance outline)
				(anchor circle)
			)
			(primitives
				(gr_poly
					(pts
						(arc
							(start -0.1778 -0.2794)
							(mid -0.249642 -0.249642)
							(end -0.2794 -0.1778)
						)
						(arc
							(start -0.2794 0.1778)
							(mid -0.249642 0.249642)
							(end -0.1778 0.2794)
						)
						(arc
							(start 0.1778 0.2794)
							(mid 0.249642 0.249642)
							(end 0.2794 0.1778)
						)
						(arc
							(start 0.2794 -0.1778)
							(mid 0.249642 -0.249642)
							(end 0.1778 -0.2794)
						)
					)
					(width 0)
					(fill yes)
				)
			)
		)
		(pad "2" smd custom
			(at 0 0.4445 90)
			(size 0.1397 0.1397)
			(layers "F.Cu" "F.Mask" "F.Paste")
			(net "GND")
			(options
				(clearance outline)
				(anchor circle)
			)
			(primitives
				(gr_poly
					(pts
						(arc
							(start -0.1778 -0.2794)
							(mid -0.249642 -0.249642)
							(end -0.2794 -0.1778)
						)
						(arc
							(start -0.2794 0.1778)
							(mid -0.249642 0.249642)
							(end -0.1778 0.2794)
						)
						(arc
							(start 0.1778 0.2794)
							(mid 0.249642 0.249642)
							(end 0.2794 0.1778)
						)
						(arc
							(start 0.2794 -0.1778)
							(mid 0.249642 -0.249642)
							(end 0.1778 -0.2794)
						)
					)
					(width 0)
					(fill yes)
				)
			)
		)
	)
	(footprint ""
		(layer "F.Cu")
		(at 127.9144 0.4826 180)
		(property "Reference" "R145"
			(at 0 0 180)
			(layer "F.SilkS")
			(hide yes)
			(effects
				(font
					(size 1.27 1.27)
				)
			)
		)
		(property "Value" "10KR2F-2-GP"
			(at 0.064008 -3.993896 180)
			(unlocked yes)
			(layer "F.Fab")
			(hide yes)
			(effects
				(font
					(size 1.016 1.016)
					(thickness 0.1524)
				)
			)
		)
		(property "Device Type" "R402H16"
			(at 0.064008 -5.517896 180)
			(unlocked yes)
			(layer "F.Fab")
			(hide yes)
			(effects
				(font
					(size 1.016 1.016)
					(thickness 0.1524)
				)
			)
		)
		(duplicate_pad_numbers_are_jumpers no)
		(fp_line
			(start 0.508 -0.9398)
			(end -0.508 -0.9398)
			(stroke
				(width 0.1524)
				(type default)
			)
			(layer "F.SilkS")
		)
		(fp_line
			(start -0.508 -0.9398)
			(end -0.508 0.9398)
			(stroke
				(width 0.1524)
				(type default)
			)
			(layer "F.SilkS")
		)
		(fp_rect
			(start -0.508 0.9398)
			(end 0.508 -0.9398)
			(stroke
				(width 0)
				(type default)
			)
			(fill no)
			(layer "F.CrtYd")
		)
		(fp_rect
			(start -0.508 0.9398)
			(end 0.508 -0.9398)
			(stroke
				(width 0)
				(type default)
			)
			(fill no)
			(layer "F.Fab")
		)
		(pad "1" smd custom
			(at 0 -0.4445 180)
			(size 0.1397 0.1397)
			(layers "F.Cu" "F.Mask" "F.Paste")
			(net "P3V3_STBY")
			(options
				(clearance outline)
				(anchor circle)
			)
			(primitives
				(gr_poly
					(pts
						(arc
							(start -0.1778 -0.2794)
							(mid -0.249642 -0.249642)
							(end -0.2794 -0.1778)
						)
						(arc
							(start -0.2794 0.1778)
							(mid -0.249642 0.249642)
							(end -0.1778 0.2794)
						)
						(arc
							(start 0.1778 0.2794)
							(mid 0.249642 0.249642)
							(end 0.2794 0.1778)
						)
						(arc
							(start 0.2794 -0.1778)
							(mid 0.249642 -0.249642)
							(end 0.1778 -0.2794)
						)
					)
					(width 0)
					(fill yes)
				)
			)
		)
		(pad "2" smd custom
			(at 0 0.4445 180)
			(size 0.1397 0.1397)
			(layers "F.Cu" "F.Mask" "F.Paste")
			(net "GPIO_P_EXP_A0")
			(options
				(clearance outline)
				(anchor circle)
			)
			(primitives
				(gr_poly
					(pts
						(arc
							(start -0.1778 -0.2794)
							(mid -0.249642 -0.249642)
							(end -0.2794 -0.1778)
						)
						(arc
							(start -0.2794 0.1778)
							(mid -0.249642 0.249642)
							(end -0.1778 0.2794)
						)
						(arc
							(start 0.1778 0.2794)
							(mid 0.249642 0.249642)
							(end 0.2794 0.1778)
						)
						(arc
							(start 0.2794 -0.1778)
							(mid 0.249642 -0.249642)
							(end 0.1778 -0.2794)
						)
					)
					(width 0)
					(fill yes)
				)
			)
		)
	)
	(footprint ""
		(layer "F.Cu")
		(at 112.3188 3.7592)
		(property "Reference" "C57"
			(at 0 0 0)
			(layer "F.SilkS")
			(hide yes)
			(effects
				(font
					(size 1.27 1.27)
				)
			)
		)
		(property "Value" "SCD1U16V2KX-3GP"
			(at 1.1811 -2.7051 0)
			(unlocked yes)
			(layer "F.Fab")
			(hide yes)
			(effects
				(font
					(size 1.016 1.016)
					(thickness 0.1524)
				)
			)
		)
		(property "Device Type" "C402H22"
			(at 1.1811 -4.2291 0)
			(unlocked yes)
			(layer "F.Fab")
			(hide yes)
			(effects
				(font
					(size 1.016 1.016)
					(thickness 0.1524)
				)
			)
		)
		(duplicate_pad_numbers_are_jumpers no)
		(fp_rect
			(start -0.4318 0.9525)
			(end 0.4318 -0.9525)
			(stroke
				(width 0)
				(type default)
			)
			(fill no)
			(layer "F.CrtYd")
		)
		(fp_rect
			(start -0.4318 0.9525)
			(end 0.4318 -0.9525)
			(stroke
				(width 0)
				(type default)
			)
			(fill no)
			(layer "F.Fab")
		)
		(pad "1" smd custom
			(at 0 -0.4445)
			(size 0.1524 0.1524)
			(layers "F.Cu" "F.Mask" "F.Paste")
			(net "P3V3_STBY")
			(options
				(clearance outline)
				(anchor circle)
			)
			(primitives
				(gr_poly
					(pts
						(arc
							(start 0.3048 -0.2032)
							(mid 0.275042 -0.275042)
							(end 0.2032 -0.3048)
						)
						(arc
							(start -0.2032 -0.3048)
							(mid -0.275042 -0.275042)
							(end -0.3048 -0.2032)
						)
						(arc
							(start -0.3048 0.2032)
							(mid -0.275042 0.275042)
							(end -0.2032 0.3048)
						)
						(arc
							(start 0.2032 0.3048)
							(mid 0.275042 0.275042)
							(end 0.3048 0.2032)
						)
					)
					(width 0)
					(fill yes)
				)
			)
		)
		(pad "2" smd custom
			(at 0 0.4445)
			(size 0.1524 0.1524)
			(layers "F.Cu" "F.Mask" "F.Paste")
			(net "GND")
			(options
				(clearance outline)
				(anchor circle)
			)
			(primitives
				(gr_poly
					(pts
						(arc
							(start 0.3048 -0.2032)
							(mid 0.275042 -0.275042)
							(end 0.2032 -0.3048)
						)
						(arc
							(start -0.2032 -0.3048)
							(mid -0.275042 -0.275042)
							(end -0.3048 -0.2032)
						)
						(arc
							(start -0.3048 0.2032)
							(mid -0.275042 0.275042)
							(end -0.2032 0.3048)
						)
						(arc
							(start 0.2032 0.3048)
							(mid 0.275042 0.275042)
							(end 0.3048 0.2032)
						)
					)
					(width 0)
					(fill yes)
				)
			)
		)
	)
	(footprint ""
		(layer "F.Cu")
		(at 132.207 -5.715 -90)
		(property "Reference" "R153"
			(at 0 0 270)
			(layer "F.SilkS")
			(hide yes)
			(effects
				(font
					(size 1.27 1.27)
				)
			)
		)
		(property "Value" "10KR2F-2-GP"
			(at 0.064008 -3.993896 270)
			(unlocked yes)
			(layer "F.Fab")
			(hide yes)
			(effects
				(font
					(size 1.016 1.016)
					(thickness 0.1524)
				)
			)
		)
		(property "Device Type" "R402H16"
			(at 0.064008 -5.517896 270)
			(unlocked yes)
			(layer "F.Fab")
			(hide yes)
			(effects
				(font
					(size 1.016 1.016)
					(thickness 0.1524)
				)
			)
		)
		(duplicate_pad_numbers_are_jumpers no)
		(fp_line
			(start -0.508 -0.9398)
			(end -0.508 0.9398)
			(stroke
				(width 0.1524)
				(type default)
			)
			(layer "F.SilkS")
		)
		(fp_line
			(start 0.508 -0.9398)
			(end -0.508 -0.9398)
			(stroke
				(width 0.1524)
				(type default)
			)
			(layer "F.SilkS")
		)
		(fp_rect
			(start -0.508 0.9398)
			(end 0.508 -0.9398)
			(stroke
				(width 0)
				(type default)
			)
			(fill no)
			(layer "F.CrtYd")
		)
		(fp_rect
			(start -0.508 0.9398)
			(end 0.508 -0.9398)
			(stroke
				(width 0)
				(type default)
			)
			(fill no)
			(layer "F.Fab")
		)
		(pad "1" smd custom
			(at 0 -0.4445 270)
			(size 0.1397 0.1397)
			(layers "F.Cu" "F.Mask" "F.Paste")
			(net "P3V3_STBY")
			(options
				(clearance outline)
				(anchor circle)
			)
			(primitives
				(gr_poly
					(pts
						(arc
							(start -0.1778 -0.2794)
							(mid -0.249642 -0.249642)
							(end -0.2794 -0.1778)
						)
						(arc
							(start -0.2794 0.1778)
							(mid -0.249642 0.249642)
							(end -0.1778 0.2794)
						)
						(arc
							(start 0.1778 0.2794)
							(mid 0.249642 0.249642)
							(end 0.2794 0.1778)
						)
						(arc
							(start 0.2794 -0.1778)
							(mid 0.249642 -0.249642)
							(end 0.1778 -0.2794)
						)
					)
					(width 0)
					(fill yes)
				)
			)
		)
		(pad "2" smd custom
			(at 0 0.4445 270)
			(size 0.1397 0.1397)
			(layers "F.Cu" "F.Mask" "F.Paste")
			(net "GPIO_P_EXP_A2")
			(options
				(clearance outline)
				(anchor circle)
			)
			(primitives
				(gr_poly
					(pts
						(arc
							(start -0.1778 -0.2794)
							(mid -0.249642 -0.249642)
							(end -0.2794 -0.1778)
						)
						(arc
							(start -0.2794 0.1778)
							(mid -0.249642 0.249642)
							(end -0.1778 0.2794)
						)
						(arc
							(start 0.1778 0.2794)
							(mid 0.249642 0.249642)
							(end 0.2794 0.1778)
						)
						(arc
							(start 0.2794 -0.1778)
							(mid 0.249642 -0.249642)
							(end 0.1778 -0.2794)
						)
					)
					(width 0)
					(fill yes)
				)
			)
		)
	)
	(footprint ""
		(layer "F.Cu")
		(at 35.052 -23.622 90)
		(property "Reference" "C22"
			(at 0 0 90)
			(layer "F.SilkS")
			(hide yes)
			(effects
				(font
					(size 1.27 1.27)
				)
			)
		)
		(property "Value" "SCD1U16V2KX-3GP"
			(at 1.1811 -2.7051 90)
			(unlocked yes)
			(layer "F.Fab")
			(hide yes)
			(effects
				(font
					(size 1.016 1.016)
					(thickness 0.1524)
				)
			)
		)
		(property "Device Type" "C402H22"
			(at 1.1811 -4.2291 90)
			(unlocked yes)
			(layer "F.Fab")
			(hide yes)
			(effects
				(font
					(size 1.016 1.016)
					(thickness 0.1524)
				)
			)
		)
		(duplicate_pad_numbers_are_jumpers no)
		(fp_rect
			(start -0.4318 0.9525)
			(end 0.4318 -0.9525)
			(stroke
				(width 0)
				(type default)
			)
			(fill no)
			(layer "F.CrtYd")
		)
		(fp_rect
			(start -0.4318 0.9525)
			(end 0.4318 -0.9525)
			(stroke
				(width 0)
				(type default)
			)
			(fill no)
			(layer "F.Fab")
		)
		(pad "1" smd custom
			(at 0 -0.4445 90)
			(size 0.1524 0.1524)
			(layers "F.Cu" "F.Mask" "F.Paste")
			(net "P3V3")
			(options
				(clearance outline)
				(anchor circle)
			)
			(primitives
				(gr_poly
					(pts
						(arc
							(start 0.3048 -0.2032)
							(mid 0.275042 -0.275042)
							(end 0.2032 -0.3048)
						)
						(arc
							(start -0.2032 -0.3048)
							(mid -0.275042 -0.275042)
							(end -0.3048 -0.2032)
						)
						(arc
							(start -0.3048 0.2032)
							(mid -0.275042 0.275042)
							(end -0.2032 0.3048)
						)
						(arc
							(start 0.2032 0.3048)
							(mid 0.275042 0.275042)
							(end 0.3048 0.2032)
						)
					)
					(width 0)
					(fill yes)
				)
			)
		)
		(pad "2" smd custom
			(at 0 0.4445 90)
			(size 0.1524 0.1524)
			(layers "F.Cu" "F.Mask" "F.Paste")
			(net "GND")
			(options
				(clearance outline)
				(anchor circle)
			)
			(primitives
				(gr_poly
					(pts
						(arc
							(start 0.3048 -0.2032)
							(mid 0.275042 -0.275042)
							(end 0.2032 -0.3048)
						)
						(arc
							(start -0.2032 -0.3048)
							(mid -0.275042 -0.275042)
							(end -0.3048 -0.2032)
						)
						(arc
							(start -0.3048 0.2032)
							(mid -0.275042 0.275042)
							(end -0.2032 0.3048)
						)
						(arc
							(start 0.2032 0.3048)
							(mid 0.275042 0.275042)
							(end 0.3048 0.2032)
						)
					)
					(width 0)
					(fill yes)
				)
			)
		)
	)
	(footprint ""
		(layer "F.Cu")
		(at 131.6736 -17.78 -90)
		(property "Reference" "R128"
			(at 0 0 270)
			(layer "F.SilkS")
			(hide yes)
			(effects
				(font
					(size 1.27 1.27)
				)
			)
		)
		(property "Value" "10KR2F-2-GP"
			(at 0.064008 -3.993896 270)
			(unlocked yes)
			(layer "F.Fab")
			(hide yes)
			(effects
				(font
					(size 1.016 1.016)
					(thickness 0.1524)
				)
			)
		)
		(property "Device Type" "R402H16"
			(at 0.064008 -5.517896 270)
			(unlocked yes)
			(layer "F.Fab")
			(hide yes)
			(effects
				(font
					(size 1.016 1.016)
					(thickness 0.1524)
				)
			)
		)
		(duplicate_pad_numbers_are_jumpers no)
		(fp_line
			(start -0.508 -0.9398)
			(end -0.508 0.9398)
			(stroke
				(width 0.1524)
				(type default)
			)
			(layer "F.SilkS")
		)
		(fp_line
			(start 0.508 -0.9398)
			(end -0.508 -0.9398)
			(stroke
				(width 0.1524)
				(type default)
			)
			(layer "F.SilkS")
		)
		(fp_rect
			(start -0.508 0.9398)
			(end 0.508 -0.9398)
			(stroke
				(width 0)
				(type default)
			)
			(fill no)
			(layer "F.CrtYd")
		)
		(fp_rect
			(start -0.508 0.9398)
			(end 0.508 -0.9398)
			(stroke
				(width 0)
				(type default)
			)
			(fill no)
			(layer "F.Fab")
		)
		(pad "1" smd custom
			(at 0 -0.4445 270)
			(size 0.1397 0.1397)
			(layers "F.Cu" "F.Mask" "F.Paste")
			(net "P3V3_STBY")
			(options
				(clearance outline)
				(anchor circle)
			)
			(primitives
				(gr_poly
					(pts
						(arc
							(start -0.1778 -0.2794)
							(mid -0.249642 -0.249642)
							(end -0.2794 -0.1778)
						)
						(arc
							(start -0.2794 0.1778)
							(mid -0.249642 0.249642)
							(end -0.1778 0.2794)
						)
						(arc
							(start 0.1778 0.2794)
							(mid 0.249642 0.249642)
							(end 0.2794 0.1778)
						)
						(arc
							(start 0.2794 -0.1778)
							(mid 0.249642 -0.249642)
							(end 0.1778 -0.2794)
						)
					)
					(width 0)
					(fill yes)
				)
			)
		)
		(pad "2" smd custom
			(at 0 0.4445 270)
			(size 0.1397 0.1397)
			(layers "F.Cu" "F.Mask" "F.Paste")
			(net "GPIO_B_IO1_6")
			(options
				(clearance outline)
				(anchor circle)
			)
			(primitives
				(gr_poly
					(pts
						(arc
							(start -0.1778 -0.2794)
							(mid -0.249642 -0.249642)
							(end -0.2794 -0.1778)
						)
						(arc
							(start -0.2794 0.1778)
							(mid -0.249642 0.249642)
							(end -0.1778 0.2794)
						)
						(arc
							(start 0.1778 0.2794)
							(mid 0.249642 0.249642)
							(end 0.2794 0.1778)
						)
						(arc
							(start 0.2794 -0.1778)
							(mid 0.249642 -0.249642)
							(end 0.1778 -0.2794)
						)
					)
					(width 0)
					(fill yes)
				)
			)
		)
	)
	(footprint ""
		(layer "F.Cu")
		(at 131.699 -16.7386 90)
		(property "Reference" "R129"
			(at 0 0 90)
			(layer "F.SilkS")
			(hide yes)
			(effects
				(font
					(size 1.27 1.27)
				)
			)
		)
		(property "Value" "10KR2F-2-GP"
			(at 0.064008 -3.993896 90)
			(unlocked yes)
			(layer "F.Fab")
			(hide yes)
			(effects
				(font
					(size 1.016 1.016)
					(thickness 0.1524)
				)
			)
		)
		(property "Device Type" "R402H16"
			(at 0.064008 -5.517896 90)
			(unlocked yes)
			(layer "F.Fab")
			(hide yes)
			(effects
				(font
					(size 1.016 1.016)
					(thickness 0.1524)
				)
			)
		)
		(duplicate_pad_numbers_are_jumpers no)
		(fp_line
			(start 0.508 -0.9398)
			(end -0.508 -0.9398)
			(stroke
				(width 0.1524)
				(type default)
			)
			(layer "F.SilkS")
		)
		(fp_line
			(start -0.508 -0.9398)
			(end -0.508 0.9398)
			(stroke
				(width 0.1524)
				(type default)
			)
			(layer "F.SilkS")
		)
		(fp_rect
			(start -0.508 0.9398)
			(end 0.508 -0.9398)
			(stroke
				(width 0)
				(type default)
			)
			(fill no)
			(layer "F.CrtYd")
		)
		(fp_rect
			(start -0.508 0.9398)
			(end 0.508 -0.9398)
			(stroke
				(width 0)
				(type default)
			)
			(fill no)
			(layer "F.Fab")
		)
		(pad "1" smd custom
			(at 0 -0.4445 90)
			(size 0.1397 0.1397)
			(layers "F.Cu" "F.Mask" "F.Paste")
			(net "GPIO_B_IO1_6")
			(options
				(clearance outline)
				(anchor circle)
			)
			(primitives
				(gr_poly
					(pts
						(arc
							(start -0.1778 -0.2794)
							(mid -0.249642 -0.249642)
							(end -0.2794 -0.1778)
						)
						(arc
							(start -0.2794 0.1778)
							(mid -0.249642 0.249642)
							(end -0.1778 0.2794)
						)
						(arc
							(start 0.1778 0.2794)
							(mid 0.249642 0.249642)
							(end 0.2794 0.1778)
						)
						(arc
							(start 0.2794 -0.1778)
							(mid 0.249642 -0.249642)
							(end 0.1778 -0.2794)
						)
					)
					(width 0)
					(fill yes)
				)
			)
		)
		(pad "2" smd custom
			(at 0 0.4445 90)
			(size 0.1397 0.1397)
			(layers "F.Cu" "F.Mask" "F.Paste")
			(net "GND")
			(options
				(clearance outline)
				(anchor circle)
			)
			(primitives
				(gr_poly
					(pts
						(arc
							(start -0.1778 -0.2794)
							(mid -0.249642 -0.249642)
							(end -0.2794 -0.1778)
						)
						(arc
							(start -0.2794 0.1778)
							(mid -0.249642 0.249642)
							(end -0.1778 0.2794)
						)
						(arc
							(start 0.1778 0.2794)
							(mid 0.249642 0.249642)
							(end 0.2794 0.1778)
						)
						(arc
							(start 0.2794 -0.1778)
							(mid 0.249642 -0.249642)
							(end 0.1778 -0.2794)
						)
					)
					(width 0)
					(fill yes)
				)
			)
		)
	)
	(footprint ""
		(layer "F.Cu")
		(at 127.4318 -1.016 -90)
		(property "Reference" "R152"
			(at 0 0 270)
			(layer "F.SilkS")
			(hide yes)
			(effects
				(font
					(size 1.27 1.27)
				)
			)
		)
		(property "Value" "10KR2F-2-GP"
			(at 0.064008 -3.993896 270)
			(unlocked yes)
			(layer "F.Fab")
			(hide yes)
			(effects
				(font
					(size 1.016 1.016)
					(thickness 0.1524)
				)
			)
		)
		(property "Device Type" "R402H16"
			(at 0.064008 -5.517896 270)
			(unlocked yes)
			(layer "F.Fab")
			(hide yes)
			(effects
				(font
					(size 1.016 1.016)
					(thickness 0.1524)
				)
			)
		)
		(duplicate_pad_numbers_are_jumpers no)
		(fp_line
			(start -0.508 -0.9398)
			(end -0.508 0.9398)
			(stroke
				(width 0.1524)
				(type default)
			)
			(layer "F.SilkS")
		)
		(fp_line
			(start 0.508 -0.9398)
			(end -0.508 -0.9398)
			(stroke
				(width 0.1524)
				(type default)
			)
			(layer "F.SilkS")
		)
		(fp_rect
			(start -0.508 0.9398)
			(end 0.508 -0.9398)
			(stroke
				(width 0)
				(type default)
			)
			(fill no)
			(layer "F.CrtYd")
		)
		(fp_rect
			(start -0.508 0.9398)
			(end 0.508 -0.9398)
			(stroke
				(width 0)
				(type default)
			)
			(fill no)
			(layer "F.Fab")
		)
		(pad "1" smd custom
			(at 0 -0.4445 270)
			(size 0.1397 0.1397)
			(layers "F.Cu" "F.Mask" "F.Paste")
			(net "GPIO_P_EXP_A0")
			(options
				(clearance outline)
				(anchor circle)
			)
			(primitives
				(gr_poly
					(pts
						(arc
							(start -0.1778 -0.2794)
							(mid -0.249642 -0.249642)
							(end -0.2794 -0.1778)
						)
						(arc
							(start -0.2794 0.1778)
							(mid -0.249642 0.249642)
							(end -0.1778 0.2794)
						)
						(arc
							(start 0.1778 0.2794)
							(mid 0.249642 0.249642)
							(end 0.2794 0.1778)
						)
						(arc
							(start 0.2794 -0.1778)
							(mid 0.249642 -0.249642)
							(end 0.1778 -0.2794)
						)
					)
					(width 0)
					(fill yes)
				)
			)
		)
		(pad "2" smd custom
			(at 0 0.4445 270)
			(size 0.1397 0.1397)
			(layers "F.Cu" "F.Mask" "F.Paste")
			(net "GND")
			(options
				(clearance outline)
				(anchor circle)
			)
			(primitives
				(gr_poly
					(pts
						(arc
							(start -0.1778 -0.2794)
							(mid -0.249642 -0.249642)
							(end -0.2794 -0.1778)
						)
						(arc
							(start -0.2794 0.1778)
							(mid -0.249642 0.249642)
							(end -0.1778 0.2794)
						)
						(arc
							(start 0.1778 0.2794)
							(mid 0.249642 0.249642)
							(end 0.2794 0.1778)
						)
						(arc
							(start 0.2794 -0.1778)
							(mid 0.249642 -0.249642)
							(end 0.1778 -0.2794)
						)
					)
					(width 0)
					(fill yes)
				)
			)
		)
	)
	(footprint ""
		(layer "F.Cu")
		(at 21.7424 4.826 90)
		(property "Reference" "R57"
			(at 0 0 90)
			(layer "F.SilkS")
			(hide yes)
			(effects
				(font
					(size 1.27 1.27)
				)
			)
		)
		(property "Value" "4K7R2F-GP"
			(at 0.064008 -3.993896 90)
			(unlocked yes)
			(layer "F.Fab")
			(hide yes)
			(effects
				(font
					(size 1.016 1.016)
					(thickness 0.1524)
				)
			)
		)
		(property "Device Type" "R402H16"
			(at 0.064008 -5.517896 90)
			(unlocked yes)
			(layer "F.Fab")
			(hide yes)
			(effects
				(font
					(size 1.016 1.016)
					(thickness 0.1524)
				)
			)
		)
		(duplicate_pad_numbers_are_jumpers no)
		(fp_line
			(start 0.508 -0.9398)
			(end -0.508 -0.9398)
			(stroke
				(width 0.1524)
				(type default)
			)
			(layer "F.SilkS")
		)
		(fp_line
			(start -0.508 -0.9398)
			(end -0.508 0.9398)
			(stroke
				(width 0.1524)
				(type default)
			)
			(layer "F.SilkS")
		)
		(fp_rect
			(start -0.508 0.9398)
			(end 0.508 -0.9398)
			(stroke
				(width 0)
				(type default)
			)
			(fill no)
			(layer "F.CrtYd")
		)
		(fp_rect
			(start -0.508 0.9398)
			(end 0.508 -0.9398)
			(stroke
				(width 0)
				(type default)
			)
			(fill no)
			(layer "F.Fab")
		)
		(pad "1" smd custom
			(at 0 -0.4445 90)
			(size 0.1397 0.1397)
			(layers "F.Cu" "F.Mask" "F.Paste")
			(net "P3V3_STBY")
			(options
				(clearance outline)
				(anchor circle)
			)
			(primitives
				(gr_poly
					(pts
						(arc
							(start -0.1778 -0.2794)
							(mid -0.249642 -0.249642)
							(end -0.2794 -0.1778)
						)
						(arc
							(start -0.2794 0.1778)
							(mid -0.249642 0.249642)
							(end -0.1778 0.2794)
						)
						(arc
							(start 0.1778 0.2794)
							(mid 0.249642 0.249642)
							(end 0.2794 0.1778)
						)
						(arc
							(start 0.2794 -0.1778)
							(mid 0.249642 -0.249642)
							(end 0.1778 -0.2794)
						)
					)
					(width 0)
					(fill yes)
				)
			)
		)
		(pad "2" smd custom
			(at 0 0.4445 90)
			(size 0.1397 0.1397)
			(layers "F.Cu" "F.Mask" "F.Paste")
			(net "FM_SLT_CFG1")
			(options
				(clearance outline)
				(anchor circle)
			)
			(primitives
				(gr_poly
					(pts
						(arc
							(start -0.1778 -0.2794)
							(mid -0.249642 -0.249642)
							(end -0.2794 -0.1778)
						)
						(arc
							(start -0.2794 0.1778)
							(mid -0.249642 0.249642)
							(end -0.1778 0.2794)
						)
						(arc
							(start 0.1778 0.2794)
							(mid 0.249642 0.249642)
							(end 0.2794 0.1778)
						)
						(arc
							(start 0.2794 -0.1778)
							(mid 0.249642 -0.249642)
							(end 0.1778 -0.2794)
						)
					)
					(width 0)
					(fill yes)
				)
			)
		)
	)
	(footprint ""
		(layer "F.Cu")
		(at 123.3424 -21.1074)
		(property "Reference" "R165"
			(at 0 0 0)
			(layer "F.SilkS")
			(hide yes)
			(effects
				(font
					(size 1.27 1.27)
				)
			)
		)
		(property "Value" "0R2F-1-GP"
			(at 0.064008 -3.993896 0)
			(unlocked yes)
			(layer "F.Fab")
			(hide yes)
			(effects
				(font
					(size 1.016 1.016)
					(thickness 0.1524)
				)
			)
		)
		(property "Device Type" "R402H16"
			(at 0.064008 -5.517896 0)
			(unlocked yes)
			(layer "F.Fab")
			(hide yes)
			(effects
				(font
					(size 1.016 1.016)
					(thickness 0.1524)
				)
			)
		)
		(duplicate_pad_numbers_are_jumpers no)
		(fp_line
			(start -0.508 -0.9398)
			(end -0.508 0.9398)
			(stroke
				(width 0.1524)
				(type default)
			)
			(layer "F.SilkS")
		)
		(fp_line
			(start 0.508 -0.9398)
			(end -0.508 -0.9398)
			(stroke
				(width 0.1524)
				(type default)
			)
			(layer "F.SilkS")
		)
		(fp_rect
			(start -0.508 0.9398)
			(end 0.508 -0.9398)
			(stroke
				(width 0)
				(type default)
			)
			(fill no)
			(layer "F.CrtYd")
		)
		(fp_rect
			(start -0.508 0.9398)
			(end 0.508 -0.9398)
			(stroke
				(width 0)
				(type default)
			)
			(fill no)
			(layer "F.Fab")
		)
		(pad "1" smd custom
			(at 0 -0.4445)
			(size 0.1397 0.1397)
			(layers "F.Cu" "F.Mask" "F.Paste")
			(net "SMB_BMC_DEVICE_ALERT_N")
			(options
				(clearance outline)
				(anchor circle)
			)
			(primitives
				(gr_poly
					(pts
						(arc
							(start -0.1778 -0.2794)
							(mid -0.249642 -0.249642)
							(end -0.2794 -0.1778)
						)
						(arc
							(start -0.2794 0.1778)
							(mid -0.249642 0.249642)
							(end -0.1778 0.2794)
						)
						(arc
							(start 0.1778 0.2794)
							(mid 0.249642 0.249642)
							(end 0.2794 0.1778)
						)
						(arc
							(start 0.2794 -0.1778)
							(mid 0.249642 -0.249642)
							(end 0.1778 -0.2794)
						)
					)
					(width 0)
					(fill yes)
				)
			)
		)
		(pad "2" smd custom
			(at 0 0.4445)
			(size 0.1397 0.1397)
			(layers "F.Cu" "F.Mask" "F.Paste")
			(net "GPIO_B_EXP_INT_N")
			(options
				(clearance outline)
				(anchor circle)
			)
			(primitives
				(gr_poly
					(pts
						(arc
							(start -0.1778 -0.2794)
							(mid -0.249642 -0.249642)
							(end -0.2794 -0.1778)
						)
						(arc
							(start -0.2794 0.1778)
							(mid -0.249642 0.249642)
							(end -0.1778 0.2794)
						)
						(arc
							(start 0.1778 0.2794)
							(mid 0.249642 0.249642)
							(end 0.2794 0.1778)
						)
						(arc
							(start 0.2794 -0.1778)
							(mid 0.249642 -0.249642)
							(end 0.1778 -0.2794)
						)
					)
					(width 0)
					(fill yes)
				)
			)
		)
	)
	(footprint ""
		(layer "F.Cu")
		(at 34.7472 -19.177 -90)
		(property "Reference" "TC4"
			(at 0 0 270)
			(layer "F.SilkS")
			(hide yes)
			(effects
				(font
					(size 1.27 1.27)
				)
			)
		)
		(property "Value" "SE100U25VM-10GP"
			(at 0 -9.0932 270)
			(unlocked yes)
			(layer "F.Fab")
			(hide yes)
			(effects
				(font
					(size 1.016 1.016)
					(thickness 0.1524)
				)
			)
		)
		(property "Device Type" "SE341618H315"
			(at 0 -10.6172 270)
			(unlocked yes)
			(layer "F.Fab")
			(hide yes)
			(effects
				(font
					(size 1.016 1.016)
					(thickness 0.1524)
				)
			)
		)
		(duplicate_pad_numbers_are_jumpers no)
		(fp_line
			(start -3.556 4.4831)
			(end -3.556 -3.4671)
			(stroke
				(width 0.1524)
				(type default)
			)
			(layer "F.SilkS")
		)
		(fp_line
			(start 3.556 4.4831)
			(end -3.556 4.4831)
			(stroke
				(width 0.1524)
				(type default)
			)
			(layer "F.SilkS")
		)
		(fp_line
			(start -3.556 -3.4671)
			(end -2.54 -4.4831)
			(stroke
				(width 0.1524)
				(type default)
			)
			(layer "F.SilkS")
		)
		(fp_line
			(start 3.556 -3.4671)
			(end 3.556 4.4831)
			(stroke
				(width 0.1524)
				(type default)
			)
			(layer "F.SilkS")
		)
		(fp_line
			(start -2.54 -4.4831)
			(end 2.54 -4.4831)
			(stroke
				(width 0.1524)
				(type default)
			)
			(layer "F.SilkS")
		)
		(fp_line
			(start 2.54 -4.4831)
			(end 3.556 -3.4671)
			(stroke
				(width 0.1524)
				(type default)
			)
			(layer "F.SilkS")
		)
		(fp_rect
			(start -3.81 4.7371)
			(end 3.81 -4.7371)
			(stroke
				(width 0)
				(type default)
			)
			(fill no)
			(layer "F.CrtYd")
		)
		(fp_rect
			(start -3.81 4.7371)
			(end 3.81 -4.7371)
			(stroke
				(width 0)
				(type default)
			)
			(fill no)
			(layer "F.Fab")
		)
		(pad "1" smd rect
			(at 0 -2.4384 270)
			(size 1.5494 3.5814)
			(layers "F.Cu" "F.Mask" "F.Paste")
			(net "P3V3")
		)
		(pad "2" smd rect
			(at 0 2.4384 270)
			(size 1.5494 3.5814)
			(layers "F.Cu" "F.Mask" "F.Paste")
			(net "GND")
		)
	)
	(footprint ""
		(layer "F.Cu")
		(at 118.8212 -30.2006 90)
		(property "Reference" "RU23"
			(at 0 0 90)
			(layer "F.SilkS")
			(hide yes)
			(effects
				(font
					(size 1.27 1.27)
				)
			)
		)
		(property "Value" "10KR2F-2-GP"
			(at 0.064008 -3.993896 90)
			(unlocked yes)
			(layer "F.Fab")
			(hide yes)
			(effects
				(font
					(size 1.016 1.016)
					(thickness 0.1524)
				)
			)
		)
		(property "Device Type" "R402H16"
			(at 0.064008 -5.517896 90)
			(unlocked yes)
			(layer "F.Fab")
			(hide yes)
			(effects
				(font
					(size 1.016 1.016)
					(thickness 0.1524)
				)
			)
		)
		(duplicate_pad_numbers_are_jumpers no)
		(fp_line
			(start 0.508 -0.9398)
			(end -0.508 -0.9398)
			(stroke
				(width 0.1524)
				(type default)
			)
			(layer "F.SilkS")
		)
		(fp_line
			(start -0.508 -0.9398)
			(end -0.508 0.9398)
			(stroke
				(width 0.1524)
				(type default)
			)
			(layer "F.SilkS")
		)
		(fp_rect
			(start -0.508 0.9398)
			(end 0.508 -0.9398)
			(stroke
				(width 0)
				(type default)
			)
			(fill no)
			(layer "F.CrtYd")
		)
		(fp_rect
			(start -0.508 0.9398)
			(end 0.508 -0.9398)
			(stroke
				(width 0)
				(type default)
			)
			(fill no)
			(layer "F.Fab")
		)
		(pad "1" smd custom
			(at 0 -0.4445 90)
			(size 0.1397 0.1397)
			(layers "F.Cu" "F.Mask" "F.Paste")
			(net "P3V3_USB_HUB")
			(options
				(clearance outline)
				(anchor circle)
			)
			(primitives
				(gr_poly
					(pts
						(arc
							(start -0.1778 -0.2794)
							(mid -0.249642 -0.249642)
							(end -0.2794 -0.1778)
						)
						(arc
							(start -0.2794 0.1778)
							(mid -0.249642 0.249642)
							(end -0.1778 0.2794)
						)
						(arc
							(start 0.1778 0.2794)
							(mid 0.249642 0.249642)
							(end 0.2794 0.1778)
						)
						(arc
							(start 0.2794 -0.1778)
							(mid 0.249642 -0.249642)
							(end 0.1778 -0.2794)
						)
					)
					(width 0)
					(fill yes)
				)
			)
		)
		(pad "2" smd custom
			(at 0 0.4445 90)
			(size 0.1397 0.1397)
			(layers "F.Cu" "F.Mask" "F.Paste")
			(net "TP_USB_DP3")
			(options
				(clearance outline)
				(anchor circle)
			)
			(primitives
				(gr_poly
					(pts
						(arc
							(start -0.1778 -0.2794)
							(mid -0.249642 -0.249642)
							(end -0.2794 -0.1778)
						)
						(arc
							(start -0.2794 0.1778)
							(mid -0.249642 0.249642)
							(end -0.1778 0.2794)
						)
						(arc
							(start 0.1778 0.2794)
							(mid 0.249642 0.249642)
							(end 0.2794 0.1778)
						)
						(arc
							(start 0.2794 -0.1778)
							(mid 0.249642 -0.249642)
							(end 0.1778 -0.2794)
						)
					)
					(width 0)
					(fill yes)
				)
			)
		)
	)
	(footprint ""
		(layer "F.Cu")
		(at 126.7968 -5.9944 180)
		(property "Reference" "U21"
			(at 0 0 180)
			(layer "F.SilkS")
			(hide yes)
			(effects
				(font
					(size 1.27 1.27)
				)
			)
		)
		(property "Value" "PCA9555PW-GP"
			(at 0 -12.1412 180)
			(unlocked yes)
			(layer "F.Fab")
			(hide yes)
			(effects
				(font
					(size 1.016 1.016)
					(thickness 0.1524)
				)
			)
		)
		(property "Device Type" "TSOIC24H44"
			(at 0 -13.6652 180)
			(unlocked yes)
			(layer "F.Fab")
			(hide yes)
			(effects
				(font
					(size 1.016 1.016)
					(thickness 0.1524)
				)
			)
		)
		(duplicate_pad_numbers_are_jumpers no)
		(fp_line
			(start 3.683 1.778)
			(end -4.1148 1.778)
			(stroke
				(width 0.1524)
				(type default)
			)
			(layer "F.SilkS")
		)
		(fp_line
			(start 3.683 -1.778)
			(end 3.683 1.778)
			(stroke
				(width 0.1524)
				(type default)
			)
			(layer "F.SilkS")
		)
		(fp_line
			(start -3.8354 0)
			(end -4.1148 0.2794)
			(stroke
				(width 0.1524)
				(type default)
			)
			(layer "F.SilkS")
		)
		(fp_line
			(start -3.8354 0)
			(end -4.1148 -0.2794)
			(stroke
				(width 0.1524)
				(type default)
			)
			(layer "F.SilkS")
		)
		(fp_line
			(start -4.0386 1.778)
			(end -4.0386 3.556)
			(stroke
				(width 0.3556)
				(type default)
			)
			(layer "F.SilkS")
		)
		(fp_line
			(start -4.1148 -1.778)
			(end 3.683 -1.778)
			(stroke
				(width 0.1524)
				(type default)
			)
			(layer "F.SilkS")
		)
		(fp_line
			(start -4.1148 -1.778)
			(end -4.1148 1.778)
			(stroke
				(width 0.1524)
				(type default)
			)
			(layer "F.SilkS")
		)
		(fp_poly
			(pts
				(xy -3.7592 -1.778) (xy 3.683 -1.778) (xy 3.683 1.778) (xy -3.7592 1.778)
			)
			(stroke
				(width 0)
				(type default)
			)
			(fill yes)
			(layer "F.SilkS")
		)
		(fp_poly
			(pts
				(xy -4.22656 3.81) (xy 4.22656 3.81) (xy 4.22656 -3.81) (xy -4.22656 -3.81)
			)
			(stroke
				(width 0)
				(type default)
			)
			(fill no)
			(layer "F.CrtYd")
		)
		(fp_poly
			(pts
				(xy -4.22656 -3.81) (xy 4.22656 -3.81) (xy 4.22656 3.81) (xy -4.22656 3.81)
			)
			(stroke
				(width 0)
				(type default)
			)
			(fill no)
			(layer "F.Fab")
		)
		(pad "1" smd rect
			(at -3.57632 2.8194 180)
			(size 0.3556 1.524)
			(layers "F.Cu" "F.Mask" "F.Paste")
			(net "GPIO_P_EXP_INT_N")
		)
		(pad "2" smd rect
			(at -2.92608 2.8194 180)
			(size 0.3556 1.524)
			(layers "F.Cu" "F.Mask" "F.Paste")
			(net "GPIO_P_EXP_A1")
		)
		(pad "3" smd rect
			(at -2.27584 2.8194 180)
			(size 0.3556 1.524)
			(layers "F.Cu" "F.Mask" "F.Paste")
			(net "GPIO_P_EXP_A2")
		)
		(pad "4" smd rect
			(at -1.6256 2.8194 180)
			(size 0.3556 1.524)
			(layers "F.Cu" "F.Mask" "F.Paste")
			(net "PCIE_SLOT2_PRSNT2_1_N")
		)
		(pad "5" smd rect
			(at -0.97536 2.8194 180)
			(size 0.3556 1.524)
			(layers "F.Cu" "F.Mask" "F.Paste")
			(net "PCIE_SLOT2_PRSNT2_2_N")
		)
		(pad "6" smd rect
			(at -0.32512 2.8194 180)
			(size 0.3556 1.524)
			(layers "F.Cu" "F.Mask" "F.Paste")
			(net "PCIE_SLOT2_PRSNT2_3_N")
		)
		(pad "7" smd rect
			(at 0.32512 2.8194 180)
			(size 0.3556 1.524)
			(layers "F.Cu" "F.Mask" "F.Paste")
			(net "PCIE_SLOT2_PRSNT2_4_N")
		)
		(pad "8" smd rect
			(at 0.97536 2.8194 180)
			(size 0.3556 1.524)
			(layers "F.Cu" "F.Mask" "F.Paste")
			(net "PCIE_SLOT3_PRSNT2_1_N")
		)
		(pad "9" smd rect
			(at 1.6256 2.8194 180)
			(size 0.3556 1.524)
			(layers "F.Cu" "F.Mask" "F.Paste")
			(net "PCIE_SLOT3_PRSNT2_2_N")
		)
		(pad "10" smd rect
			(at 2.27584 2.8194 180)
			(size 0.3556 1.524)
			(layers "F.Cu" "F.Mask" "F.Paste")
			(net "PCIE_SLOT3_PRSNT2_3_N")
		)
		(pad "11" smd rect
			(at 2.92608 2.8194 180)
			(size 0.3556 1.524)
			(layers "F.Cu" "F.Mask" "F.Paste")
			(net "PCIE_SLOT3_PRSNT2_4_N")
		)
		(pad "12" smd rect
			(at 3.57632 2.8194 180)
			(size 0.3556 1.524)
			(layers "F.Cu" "F.Mask" "F.Paste")
			(net "GND")
		)
		(pad "13" smd rect
			(at 3.57632 -2.8194 180)
			(size 0.3556 1.524)
			(layers "F.Cu" "F.Mask" "F.Paste")
			(net "GPIO_P_IO1_0")
		)
		(pad "14" smd rect
			(at 2.92608 -2.8194 180)
			(size 0.3556 1.524)
			(layers "F.Cu" "F.Mask" "F.Paste")
			(net "FM_SLT_CFG0")
		)
		(pad "15" smd rect
			(at 2.27584 -2.8194 180)
			(size 0.3556 1.524)
			(layers "F.Cu" "F.Mask" "F.Paste")
			(net "FM_SLT_CFG1")
		)
		(pad "16" smd rect
			(at 1.6256 -2.8194 180)
			(size 0.3556 1.524)
			(layers "F.Cu" "F.Mask" "F.Paste")
			(net "GPIO_P_IO1_3")
		)
		(pad "17" smd rect
			(at 0.97536 -2.8194 180)
			(size 0.3556 1.524)
			(layers "F.Cu" "F.Mask" "F.Paste")
			(net "GPIO_P_IO1_4")
		)
		(pad "18" smd rect
			(at 0.32512 -2.8194 180)
			(size 0.3556 1.524)
			(layers "F.Cu" "F.Mask" "F.Paste")
			(net "GPIO_P_IO1_5")
		)
		(pad "19" smd rect
			(at -0.32512 -2.8194 180)
			(size 0.3556 1.524)
			(layers "F.Cu" "F.Mask" "F.Paste")
			(net "GPIO_P_IO1_6")
		)
		(pad "20" smd rect
			(at -0.97536 -2.8194 180)
			(size 0.3556 1.524)
			(layers "F.Cu" "F.Mask" "F.Paste")
			(net "GPIO_P_IO1_7")
		)
		(pad "21" smd rect
			(at -1.6256 -2.8194 180)
			(size 0.3556 1.524)
			(layers "F.Cu" "F.Mask" "F.Paste")
			(net "GPIO_P_EXP_A0")
		)
		(pad "22" smd rect
			(at -2.27584 -2.8194 180)
			(size 0.3556 1.524)
			(layers "F.Cu" "F.Mask" "F.Paste")
			(net "SMCLK_EXP_R_PCH")
		)
		(pad "23" smd rect
			(at -2.92608 -2.8194 180)
			(size 0.3556 1.524)
			(layers "F.Cu" "F.Mask" "F.Paste")
			(net "SMDAT_EXP_R_PCH")
		)
		(pad "24" smd rect
			(at -3.57632 -2.8194 180)
			(size 0.3556 1.524)
			(layers "F.Cu" "F.Mask" "F.Paste")
			(net "P3V3_STBY")
		)
	)
	(footprint ""
		(layer "F.Cu")
		(at 131.7498 -11.4808 -90)
		(property "Reference" "R122"
			(at 0 0 270)
			(layer "F.SilkS")
			(hide yes)
			(effects
				(font
					(size 1.27 1.27)
				)
			)
		)
		(property "Value" "10KR2F-2-GP"
			(at 0.064008 -3.993896 270)
			(unlocked yes)
			(layer "F.Fab")
			(hide yes)
			(effects
				(font
					(size 1.016 1.016)
					(thickness 0.1524)
				)
			)
		)
		(property "Device Type" "R402H16"
			(at 0.064008 -5.517896 270)
			(unlocked yes)
			(layer "F.Fab")
			(hide yes)
			(effects
				(font
					(size 1.016 1.016)
					(thickness 0.1524)
				)
			)
		)
		(duplicate_pad_numbers_are_jumpers no)
		(fp_line
			(start -0.508 -0.9398)
			(end -0.508 0.9398)
			(stroke
				(width 0.1524)
				(type default)
			)
			(layer "F.SilkS")
		)
		(fp_line
			(start 0.508 -0.9398)
			(end -0.508 -0.9398)
			(stroke
				(width 0.1524)
				(type default)
			)
			(layer "F.SilkS")
		)
		(fp_rect
			(start -0.508 0.9398)
			(end 0.508 -0.9398)
			(stroke
				(width 0)
				(type default)
			)
			(fill no)
			(layer "F.CrtYd")
		)
		(fp_rect
			(start -0.508 0.9398)
			(end 0.508 -0.9398)
			(stroke
				(width 0)
				(type default)
			)
			(fill no)
			(layer "F.Fab")
		)
		(pad "1" smd custom
			(at 0 -0.4445 270)
			(size 0.1397 0.1397)
			(layers "F.Cu" "F.Mask" "F.Paste")
			(net "P3V3_STBY")
			(options
				(clearance outline)
				(anchor circle)
			)
			(primitives
				(gr_poly
					(pts
						(arc
							(start -0.1778 -0.2794)
							(mid -0.249642 -0.249642)
							(end -0.2794 -0.1778)
						)
						(arc
							(start -0.2794 0.1778)
							(mid -0.249642 0.249642)
							(end -0.1778 0.2794)
						)
						(arc
							(start 0.1778 0.2794)
							(mid 0.249642 0.249642)
							(end 0.2794 0.1778)
						)
						(arc
							(start 0.2794 -0.1778)
							(mid 0.249642 -0.249642)
							(end 0.1778 -0.2794)
						)
					)
					(width 0)
					(fill yes)
				)
			)
		)
		(pad "2" smd custom
			(at 0 0.4445 270)
			(size 0.1397 0.1397)
			(layers "F.Cu" "F.Mask" "F.Paste")
			(net "GPIO_B_IO1_3")
			(options
				(clearance outline)
				(anchor circle)
			)
			(primitives
				(gr_poly
					(pts
						(arc
							(start -0.1778 -0.2794)
							(mid -0.249642 -0.249642)
							(end -0.2794 -0.1778)
						)
						(arc
							(start -0.2794 0.1778)
							(mid -0.249642 0.249642)
							(end -0.1778 0.2794)
						)
						(arc
							(start 0.1778 0.2794)
							(mid 0.249642 0.249642)
							(end 0.2794 0.1778)
						)
						(arc
							(start 0.2794 -0.1778)
							(mid 0.249642 -0.249642)
							(end 0.1778 -0.2794)
						)
					)
					(width 0)
					(fill yes)
				)
			)
		)
	)
	(footprint ""
		(layer "F.Cu")
		(at 42.729912 -10.500106)
		(property "Reference" "SLOT2"
			(at 0 0 0)
			(layer "F.SilkS")
			(hide yes)
			(effects
				(font
					(size 1.27 1.27)
				)
			)
		)
		(property "Value" "PCISLT164-129-GP"
			(at -15.9639 4.8514 0)
			(unlocked yes)
			(layer "F.Fab")
			(hide yes)
			(effects
				(font
					(size 1.016 1.016)
					(thickness 0.1524)
				)
			)
		)
		(property "Device Type" "10018783-10203TLF"
			(at -15.9639 3.3274 0)
			(unlocked yes)
			(layer "F.Fab")
			(hide yes)
			(effects
				(font
					(size 1.016 1.016)
					(thickness 0.1524)
				)
			)
		)
		(duplicate_pad_numbers_are_jumpers no)
		(fp_line
			(start -14.9098 -4.0386)
			(end 74.5998 -4.0386)
			(stroke
				(width 0.1524)
				(type default)
			)
			(layer "F.SilkS")
		)
		(fp_line
			(start -14.9098 5.3594)
			(end -14.9098 -4.0386)
			(stroke
				(width 0.1524)
				(type default)
			)
			(layer "F.SilkS")
		)
		(fp_line
			(start 74.5998 -4.0386)
			(end 74.5998 5.3594)
			(stroke
				(width 0.1524)
				(type default)
			)
			(layer "F.SilkS")
		)
		(fp_line
			(start 74.5998 5.3594)
			(end -14.9098 5.3594)
			(stroke
				(width 0.1524)
				(type default)
			)
			(layer "F.SilkS")
		)
		(fp_rect
			(start -14.6558 5.1054)
			(end 74.3458 -3.683)
			(stroke
				(width 0)
				(type default)
			)
			(fill no)
			(layer "F.CrtYd")
		)
		(fp_poly
			(pts
				(xy -15.1638 5.6134) (xy -15.1638 0.00254) (xy -14.6558 0.00254) (xy -14.6558 5.1054) (xy 74.3458 5.1054)
				(xy 74.3458 -3.683) (xy -14.6558 -3.683) (xy -14.6558 -0.00254) (xy -15.1638 -0.00254) (xy -15.1638 -4.2926)
				(xy 74.8538 -4.2926) (xy 74.8538 5.6134)
			)
			(stroke
				(width 0)
				(type default)
			)
			(fill no)
			(layer "F.CrtYd")
		)
		(fp_rect
			(start -15.1638 5.6134)
			(end 74.8538 -4.2926)
			(stroke
				(width 0)
				(type default)
			)
			(fill no)
			(layer "F.Fab")
		)
		(pad "" np_thru_hole circle
			(at 0 0)
			(size 0.254 0.254)
			(drill 2.3622)
			(layers "*.Cu" "*.Mask")
			(clearance 1.4097)
			(thermal_gap 1.4097)
		)
		(pad "" np_thru_hole circle
			(at 73.14946 0)
			(size 0.254 0.254)
			(drill 2.3622)
			(layers "*.Cu" "*.Mask")
			(clearance 1.4097)
			(thermal_gap 1.4097)
		)
		(pad "A1" thru_hole circle
			(at -11.64971 -1.24968)
			(size 1.0668 1.0668)
			(drill 0.7112)
			(layers "*.Cu" "*.Mask")
			(remove_unused_layers no)
			(net "PD_SLOT2_PRSNT1")
			(clearance 0.1778)
			(thermal_gap 0.1778)
		)
		(pad "A2" thru_hole circle
			(at -10.65022 -3.24993)
			(size 1.0668 1.0668)
			(drill 0.7112)
			(layers "*.Cu" "*.Mask")
			(remove_unused_layers no)
			(net "P12V_SLOT2")
			(clearance 0.1778)
			(thermal_gap 0.1778)
		)
		(pad "A3" thru_hole circle
			(at -9.64946 -1.24968)
			(size 1.0668 1.0668)
			(drill 0.7112)
			(layers "*.Cu" "*.Mask")
			(remove_unused_layers no)
			(net "P12V_SLOT2")
			(clearance 0.1778)
			(thermal_gap 0.1778)
		)
		(pad "A4" thru_hole circle
			(at -8.64997 -3.24993)
			(size 1.0668 1.0668)
			(drill 0.7112)
			(layers "*.Cu" "*.Mask")
			(remove_unused_layers no)
			(net "GND")
			(clearance 0.1778)
			(thermal_gap 0.1778)
		)
		(pad "A5" thru_hole circle
			(at -7.65048 -1.24968)
			(size 1.0668 1.0668)
			(drill 0.7112)
			(layers "*.Cu" "*.Mask")
			(remove_unused_layers no)
			(net "Net_102")
			(clearance 0.1778)
			(thermal_gap 0.1778)
		)
		(pad "A6" thru_hole circle
			(at -6.64972 -3.24993)
			(size 1.0668 1.0668)
			(drill 0.7112)
			(layers "*.Cu" "*.Mask")
			(remove_unused_layers no)
			(net "Net_103")
			(clearance 0.1778)
			(thermal_gap 0.1778)
		)
		(pad "A7" thru_hole circle
			(at -5.65023 -1.24968)
			(size 1.0668 1.0668)
			(drill 0.7112)
			(layers "*.Cu" "*.Mask")
			(remove_unused_layers no)
			(net "SMCLK_PCH_SLOT2_R")
			(clearance 0.1778)
			(thermal_gap 0.1778)
		)
		(pad "A8" thru_hole circle
			(at -4.64947 -3.24993)
			(size 1.0668 1.0668)
			(drill 0.7112)
			(layers "*.Cu" "*.Mask")
			(remove_unused_layers no)
			(net "SMDAT_PCH_SLOT2_R")
			(clearance 0.1778)
			(thermal_gap 0.1778)
		)
		(pad "A9" thru_hole circle
			(at -3.64998 -1.24968)
			(size 1.0668 1.0668)
			(drill 0.7112)
			(layers "*.Cu" "*.Mask")
			(remove_unused_layers no)
			(net "P3V3")
			(clearance 0.1778)
			(thermal_gap 0.1778)
		)
		(pad "A10" thru_hole circle
			(at -2.65049 -3.24993)
			(size 1.0668 1.0668)
			(drill 0.7112)
			(layers "*.Cu" "*.Mask")
			(remove_unused_layers no)
			(net "P3V3")
			(clearance 0.1778)
			(thermal_gap 0.1778)
		)
		(pad "A11" thru_hole circle
			(at -1.64973 -1.24968)
			(size 1.0668 1.0668)
			(drill 0.7112)
			(layers "*.Cu" "*.Mask")
			(remove_unused_layers no)
			(net "RESET_BUF_N_SLOT2")
			(clearance 0.1778)
			(thermal_gap 0.1778)
		)
		(pad "A12" thru_hole circle
			(at 1.35001 -3.24993)
			(size 1.0668 1.0668)
			(drill 0.7112)
			(layers "*.Cu" "*.Mask")
			(remove_unused_layers no)
			(net "GND")
			(clearance 0.1778)
			(thermal_gap 0.1778)
		)
		(pad "A13" thru_hole circle
			(at 2.3495 -1.24968)
			(size 1.0668 1.0668)
			(drill 0.7112)
			(layers "*.Cu" "*.Mask")
			(remove_unused_layers no)
			(net "CLK_100M_PCH_SLOTX24_S5_DP")
			(clearance 0.1778)
			(thermal_gap 0.1778)
		)
		(pad "A14" thru_hole circle
			(at 3.35026 -3.24993)
			(size 1.0668 1.0668)
			(drill 0.7112)
			(layers "*.Cu" "*.Mask")
			(remove_unused_layers no)
			(net "CLK_100M_PCH_SLOTX24_S5_DN")
			(clearance 0.1778)
			(thermal_gap 0.1778)
		)
		(pad "A15" thru_hole circle
			(at 4.34975 -1.24968)
			(size 1.0668 1.0668)
			(drill 0.7112)
			(layers "*.Cu" "*.Mask")
			(remove_unused_layers no)
			(net "GND")
			(clearance 0.1778)
			(thermal_gap 0.1778)
		)
		(pad "A16" thru_hole circle
			(at 5.35051 -3.24993)
			(size 1.0668 1.0668)
			(drill 0.7112)
			(layers "*.Cu" "*.Mask")
			(remove_unused_layers no)
			(net "P3E_CPU0_PE1_PCH_CON_RXP<15>")
			(clearance 0.1778)
			(thermal_gap 0.1778)
		)
		(pad "A17" thru_hole circle
			(at 6.35 -1.24968)
			(size 1.0668 1.0668)
			(drill 0.7112)
			(layers "*.Cu" "*.Mask")
			(remove_unused_layers no)
			(net "P3E_CPU0_PE1_PCH_CON_RXN<15>")
			(clearance 0.1778)
			(thermal_gap 0.1778)
		)
		(pad "A18" thru_hole circle
			(at 7.34949 -3.24993)
			(size 1.0668 1.0668)
			(drill 0.7112)
			(layers "*.Cu" "*.Mask")
			(remove_unused_layers no)
			(net "GND")
			(clearance 0.1778)
			(thermal_gap 0.1778)
		)
		(pad "A19" thru_hole circle
			(at 8.35025 -1.24968)
			(size 1.0668 1.0668)
			(drill 0.7112)
			(layers "*.Cu" "*.Mask")
			(remove_unused_layers no)
			(net "Net_99")
			(clearance 0.1778)
			(thermal_gap 0.1778)
		)
		(pad "A20" thru_hole circle
			(at 9.34974 -3.24993)
			(size 1.0668 1.0668)
			(drill 0.7112)
			(layers "*.Cu" "*.Mask")
			(remove_unused_layers no)
			(net "GND")
			(clearance 0.1778)
			(thermal_gap 0.1778)
		)
		(pad "A21" thru_hole circle
			(at 10.3505 -1.24968)
			(size 1.0668 1.0668)
			(drill 0.7112)
			(layers "*.Cu" "*.Mask")
			(remove_unused_layers no)
			(net "P3E_CPU0_PE1_PCH_CON_RXP<14>")
			(clearance 0.1778)
			(thermal_gap 0.1778)
		)
		(pad "A22" thru_hole circle
			(at 11.34999 -3.24993)
			(size 1.0668 1.0668)
			(drill 0.7112)
			(layers "*.Cu" "*.Mask")
			(remove_unused_layers no)
			(net "P3E_CPU0_PE1_PCH_CON_RXN<14>")
			(clearance 0.1778)
			(thermal_gap 0.1778)
		)
		(pad "A23" thru_hole circle
			(at 12.34948 -1.24968)
			(size 1.0668 1.0668)
			(drill 0.7112)
			(layers "*.Cu" "*.Mask")
			(remove_unused_layers no)
			(net "GND")
			(clearance 0.1778)
			(thermal_gap 0.1778)
		)
		(pad "A24" thru_hole circle
			(at 13.35024 -3.24993)
			(size 1.0668 1.0668)
			(drill 0.7112)
			(layers "*.Cu" "*.Mask")
			(remove_unused_layers no)
			(net "GND")
			(clearance 0.1778)
			(thermal_gap 0.1778)
		)
		(pad "A25" thru_hole circle
			(at 14.34973 -1.24968)
			(size 1.0668 1.0668)
			(drill 0.7112)
			(layers "*.Cu" "*.Mask")
			(remove_unused_layers no)
			(net "P3E_CPU0_PE1_PCH_CON_RXP<13>")
			(clearance 0.1778)
			(thermal_gap 0.1778)
		)
		(pad "A26" thru_hole circle
			(at 15.35049 -3.24993)
			(size 1.0668 1.0668)
			(drill 0.7112)
			(layers "*.Cu" "*.Mask")
			(remove_unused_layers no)
			(net "P3E_CPU0_PE1_PCH_CON_RXN<13>")
			(clearance 0.1778)
			(thermal_gap 0.1778)
		)
		(pad "A27" thru_hole circle
			(at 16.34998 -1.24968)
			(size 1.0668 1.0668)
			(drill 0.7112)
			(layers "*.Cu" "*.Mask")
			(remove_unused_layers no)
			(net "GND")
			(clearance 0.1778)
			(thermal_gap 0.1778)
		)
		(pad "A28" thru_hole circle
			(at 17.34947 -3.24993)
			(size 1.0668 1.0668)
			(drill 0.7112)
			(layers "*.Cu" "*.Mask")
			(remove_unused_layers no)
			(net "GND")
			(clearance 0.1778)
			(thermal_gap 0.1778)
		)
		(pad "A29" thru_hole circle
			(at 18.35023 -1.24968)
			(size 1.0668 1.0668)
			(drill 0.7112)
			(layers "*.Cu" "*.Mask")
			(remove_unused_layers no)
			(net "P3E_CPU0_PE1_PCH_CON_RXP<12>")
			(clearance 0.1778)
			(thermal_gap 0.1778)
		)
		(pad "A30" thru_hole circle
			(at 19.34972 -3.24993)
			(size 1.0668 1.0668)
			(drill 0.7112)
			(layers "*.Cu" "*.Mask")
			(remove_unused_layers no)
			(net "P3E_CPU0_PE1_PCH_CON_RXN<12>")
			(clearance 0.1778)
			(thermal_gap 0.1778)
		)
		(pad "A31" thru_hole circle
			(at 20.35048 -1.24968)
			(size 1.0668 1.0668)
			(drill 0.7112)
			(layers "*.Cu" "*.Mask")
			(remove_unused_layers no)
			(net "GND")
			(clearance 0.1778)
			(thermal_gap 0.1778)
		)
		(pad "A32" thru_hole circle
			(at 21.34997 -3.24993)
			(size 1.0668 1.0668)
			(drill 0.7112)
			(layers "*.Cu" "*.Mask")
			(remove_unused_layers no)
			(net "USB_HUB_PCIE_DP0")
			(clearance 0.1778)
			(thermal_gap 0.1778)
		)
		(pad "A33" thru_hole circle
			(at 22.34946 -1.24968)
			(size 1.0668 1.0668)
			(drill 0.7112)
			(layers "*.Cu" "*.Mask")
			(remove_unused_layers no)
			(net "USB_HUB_PCIE_DN0")
			(clearance 0.1778)
			(thermal_gap 0.1778)
		)
		(pad "A34" thru_hole circle
			(at 23.35022 -3.24993)
			(size 1.0668 1.0668)
			(drill 0.7112)
			(layers "*.Cu" "*.Mask")
			(remove_unused_layers no)
			(net "GND")
			(clearance 0.1778)
			(thermal_gap 0.1778)
		)
		(pad "A35" thru_hole circle
			(at 24.34971 -1.24968)
			(size 1.0668 1.0668)
			(drill 0.7112)
			(layers "*.Cu" "*.Mask")
			(remove_unused_layers no)
			(net "P3E_CPU0_PE1_PCH_CON_RXP<11>")
			(clearance 0.1778)
			(thermal_gap 0.1778)
		)
		(pad "A36" thru_hole circle
			(at 25.35047 -3.24993)
			(size 1.0668 1.0668)
			(drill 0.7112)
			(layers "*.Cu" "*.Mask")
			(remove_unused_layers no)
			(net "P3E_CPU0_PE1_PCH_CON_RXN<11>")
			(clearance 0.1778)
			(thermal_gap 0.1778)
		)
		(pad "A37" thru_hole circle
			(at 26.34996 -1.24968)
			(size 1.0668 1.0668)
			(drill 0.7112)
			(layers "*.Cu" "*.Mask")
			(remove_unused_layers no)
			(net "GND")
			(clearance 0.1778)
			(thermal_gap 0.1778)
		)
		(pad "A38" thru_hole circle
			(at 27.34945 -3.24993)
			(size 1.0668 1.0668)
			(drill 0.7112)
			(layers "*.Cu" "*.Mask")
			(remove_unused_layers no)
			(net "GND")
			(clearance 0.1778)
			(thermal_gap 0.1778)
		)
		(pad "A39" thru_hole circle
			(at 28.35021 -1.24968)
			(size 1.0668 1.0668)
			(drill 0.7112)
			(layers "*.Cu" "*.Mask")
			(remove_unused_layers no)
			(net "P3E_CPU0_PE1_PCH_CON_RXP<10>")
			(clearance 0.1778)
			(thermal_gap 0.1778)
		)
		(pad "A40" thru_hole circle
			(at 29.3497 -3.24993)
			(size 1.0668 1.0668)
			(drill 0.7112)
			(layers "*.Cu" "*.Mask")
			(remove_unused_layers no)
			(net "P3E_CPU0_PE1_PCH_CON_RXN<10>")
			(clearance 0.1778)
			(thermal_gap 0.1778)
		)
		(pad "A41" thru_hole circle
			(at 30.35046 -1.24968)
			(size 1.0668 1.0668)
			(drill 0.7112)
			(layers "*.Cu" "*.Mask")
			(remove_unused_layers no)
			(net "GND")
			(clearance 0.1778)
			(thermal_gap 0.1778)
		)
		(pad "A42" thru_hole circle
			(at 31.34995 -3.24993)
			(size 1.0668 1.0668)
			(drill 0.7112)
			(layers "*.Cu" "*.Mask")
			(remove_unused_layers no)
			(net "GND")
			(clearance 0.1778)
			(thermal_gap 0.1778)
		)
		(pad "A43" thru_hole circle
			(at 32.34944 -1.24968)
			(size 1.0668 1.0668)
			(drill 0.7112)
			(layers "*.Cu" "*.Mask")
			(remove_unused_layers no)
			(net "P3E_CPU0_PE1_PCH_CON_RXP<9>")
			(clearance 0.1778)
			(thermal_gap 0.1778)
		)
		(pad "A44" thru_hole circle
			(at 33.3502 -3.24993)
			(size 1.0668 1.0668)
			(drill 0.7112)
			(layers "*.Cu" "*.Mask")
			(remove_unused_layers no)
			(net "P3E_CPU0_PE1_PCH_CON_RXN<9>")
			(clearance 0.1778)
			(thermal_gap 0.1778)
		)
		(pad "A45" thru_hole circle
			(at 34.34969 -1.24968)
			(size 1.0668 1.0668)
			(drill 0.7112)
			(layers "*.Cu" "*.Mask")
			(remove_unused_layers no)
			(net "GND")
			(clearance 0.1778)
			(thermal_gap 0.1778)
		)
		(pad "A46" thru_hole circle
			(at 35.35045 -3.24993)
			(size 1.0668 1.0668)
			(drill 0.7112)
			(layers "*.Cu" "*.Mask")
			(remove_unused_layers no)
			(net "GND")
			(clearance 0.1778)
			(thermal_gap 0.1778)
		)
		(pad "A47" thru_hole circle
			(at 36.34994 -1.24968)
			(size 1.0668 1.0668)
			(drill 0.7112)
			(layers "*.Cu" "*.Mask")
			(remove_unused_layers no)
			(net "P3E_CPU0_PE1_PCH_CON_RXP<8>")
			(clearance 0.1778)
			(thermal_gap 0.1778)
		)
		(pad "A48" thru_hole circle
			(at 37.34943 -3.24993)
			(size 1.0668 1.0668)
			(drill 0.7112)
			(layers "*.Cu" "*.Mask")
			(remove_unused_layers no)
			(net "P3E_CPU0_PE1_PCH_CON_RXN<8>")
			(clearance 0.1778)
			(thermal_gap 0.1778)
		)
		(pad "A49" thru_hole circle
			(at 38.35019 -1.24968)
			(size 1.0668 1.0668)
			(drill 0.7112)
			(layers "*.Cu" "*.Mask")
			(remove_unused_layers no)
			(net "GND")
			(clearance 0.1778)
			(thermal_gap 0.1778)
		)
		(pad "A50" thru_hole circle
			(at 39.34968 -3.24993)
			(size 1.0668 1.0668)
			(drill 0.7112)
			(layers "*.Cu" "*.Mask")
			(remove_unused_layers no)
			(net "Net_98")
			(clearance 0.1778)
			(thermal_gap 0.1778)
		)
		(pad "A51" thru_hole circle
			(at 40.35044 -1.24968)
			(size 1.0668 1.0668)
			(drill 0.7112)
			(layers "*.Cu" "*.Mask")
			(remove_unused_layers no)
			(net "GND")
			(clearance 0.1778)
			(thermal_gap 0.1778)
		)
		(pad "A52" thru_hole circle
			(at 41.34993 -3.24993)
			(size 1.0668 1.0668)
			(drill 0.7112)
			(layers "*.Cu" "*.Mask")
			(remove_unused_layers no)
			(net "P3E_CPU0_PE1_SS_C_RXP<7>")
			(clearance 0.1778)
			(thermal_gap 0.1778)
		)
		(pad "A53" thru_hole circle
			(at 42.34942 -1.24968)
			(size 1.0668 1.0668)
			(drill 0.7112)
			(layers "*.Cu" "*.Mask")
			(remove_unused_layers no)
			(net "P3E_CPU0_PE1_SS_C_RXN<7>")
			(clearance 0.1778)
			(thermal_gap 0.1778)
		)
		(pad "A54" thru_hole circle
			(at 43.35018 -3.24993)
			(size 1.0668 1.0668)
			(drill 0.7112)
			(layers "*.Cu" "*.Mask")
			(remove_unused_layers no)
			(net "GND")
			(clearance 0.1778)
			(thermal_gap 0.1778)
		)
		(pad "A55" thru_hole circle
			(at 44.34967 -1.24968)
			(size 1.0668 1.0668)
			(drill 0.7112)
			(layers "*.Cu" "*.Mask")
			(remove_unused_layers no)
			(net "GND")
			(clearance 0.1778)
			(thermal_gap 0.1778)
		)
		(pad "A56" thru_hole circle
			(at 45.35043 -3.24993)
			(size 1.0668 1.0668)
			(drill 0.7112)
			(layers "*.Cu" "*.Mask")
			(remove_unused_layers no)
			(net "P3E_CPU0_PE1_SS_C_RXP<6>")
			(clearance 0.1778)
			(thermal_gap 0.1778)
		)
		(pad "A57" thru_hole circle
			(at 46.34992 -1.24968)
			(size 1.0668 1.0668)
			(drill 0.7112)
			(layers "*.Cu" "*.Mask")
			(remove_unused_layers no)
			(net "P3E_CPU0_PE1_SS_C_RXN<6>")
			(clearance 0.1778)
			(thermal_gap 0.1778)
		)
		(pad "A58" thru_hole circle
			(at 47.34941 -3.24993)
			(size 1.0668 1.0668)
			(drill 0.7112)
			(layers "*.Cu" "*.Mask")
			(remove_unused_layers no)
			(net "GND")
			(clearance 0.1778)
			(thermal_gap 0.1778)
		)
		(pad "A59" thru_hole circle
			(at 48.35017 -1.24968)
			(size 1.0668 1.0668)
			(drill 0.7112)
			(layers "*.Cu" "*.Mask")
			(remove_unused_layers no)
			(net "GND")
			(clearance 0.1778)
			(thermal_gap 0.1778)
		)
		(pad "A60" thru_hole circle
			(at 49.34966 -3.24993)
			(size 1.0668 1.0668)
			(drill 0.7112)
			(layers "*.Cu" "*.Mask")
			(remove_unused_layers no)
			(net "P3E_CPU0_PE1_SS_C_RXP<5>")
			(clearance 0.1778)
			(thermal_gap 0.1778)
		)
		(pad "A61" thru_hole circle
			(at 50.35042 -1.24968)
			(size 1.0668 1.0668)
			(drill 0.7112)
			(layers "*.Cu" "*.Mask")
			(remove_unused_layers no)
			(net "P3E_CPU0_PE1_SS_C_RXN<5>")
			(clearance 0.1778)
			(thermal_gap 0.1778)
		)
		(pad "A62" thru_hole circle
			(at 51.34991 -3.24993)
			(size 1.0668 1.0668)
			(drill 0.7112)
			(layers "*.Cu" "*.Mask")
			(remove_unused_layers no)
			(net "GND")
			(clearance 0.1778)
			(thermal_gap 0.1778)
		)
		(pad "A63" thru_hole circle
			(at 52.3494 -1.24968)
			(size 1.0668 1.0668)
			(drill 0.7112)
			(layers "*.Cu" "*.Mask")
			(remove_unused_layers no)
			(net "GND")
			(clearance 0.1778)
			(thermal_gap 0.1778)
		)
		(pad "A64" thru_hole circle
			(at 53.35016 -3.24993)
			(size 1.0668 1.0668)
			(drill 0.7112)
			(layers "*.Cu" "*.Mask")
			(remove_unused_layers no)
			(net "P3E_CPU0_PE1_SS_C_RXP<4>")
			(clearance 0.1778)
			(thermal_gap 0.1778)
		)
		(pad "A65" thru_hole circle
			(at 54.34965 -1.24968)
			(size 1.0668 1.0668)
			(drill 0.7112)
			(layers "*.Cu" "*.Mask")
			(remove_unused_layers no)
			(net "P3E_CPU0_PE1_SS_C_RXN<4>")
			(clearance 0.1778)
			(thermal_gap 0.1778)
		)
		(pad "A66" thru_hole circle
			(at 55.35041 -3.24993)
			(size 1.0668 1.0668)
			(drill 0.7112)
			(layers "*.Cu" "*.Mask")
			(remove_unused_layers no)
			(net "GND")
			(clearance 0.1778)
			(thermal_gap 0.1778)
		)
		(pad "A67" thru_hole circle
			(at 56.3499 -1.24968)
			(size 1.0668 1.0668)
			(drill 0.7112)
			(layers "*.Cu" "*.Mask")
			(remove_unused_layers no)
			(net "GND")
			(clearance 0.1778)
			(thermal_gap 0.1778)
		)
		(pad "A68" thru_hole circle
			(at 57.34939 -3.24993)
			(size 1.0668 1.0668)
			(drill 0.7112)
			(layers "*.Cu" "*.Mask")
			(remove_unused_layers no)
			(net "P3E_CPU0_PE1_SS_C_RXP<3>")
			(clearance 0.1778)
			(thermal_gap 0.1778)
		)
		(pad "A69" thru_hole circle
			(at 58.35015 -1.24968)
			(size 1.0668 1.0668)
			(drill 0.7112)
			(layers "*.Cu" "*.Mask")
			(remove_unused_layers no)
			(net "P3E_CPU0_PE1_SS_C_RXN<3>")
			(clearance 0.1778)
			(thermal_gap 0.1778)
		)
		(pad "A70" thru_hole circle
			(at 59.34964 -3.24993)
			(size 1.0668 1.0668)
			(drill 0.7112)
			(layers "*.Cu" "*.Mask")
			(remove_unused_layers no)
			(net "GND")
			(clearance 0.1778)
			(thermal_gap 0.1778)
		)
		(pad "A71" thru_hole circle
			(at 60.3504 -1.24968)
			(size 1.0668 1.0668)
			(drill 0.7112)
			(layers "*.Cu" "*.Mask")
			(remove_unused_layers no)
			(net "GND")
			(clearance 0.1778)
			(thermal_gap 0.1778)
		)
		(pad "A72" thru_hole circle
			(at 61.34989 -3.24993)
			(size 1.0668 1.0668)
			(drill 0.7112)
			(layers "*.Cu" "*.Mask")
			(remove_unused_layers no)
			(net "P3E_CPU0_PE1_SS_C_RXP<2>")
			(clearance 0.1778)
			(thermal_gap 0.1778)
		)
		(pad "A73" thru_hole circle
			(at 62.34938 -1.24968)
			(size 1.0668 1.0668)
			(drill 0.7112)
			(layers "*.Cu" "*.Mask")
			(remove_unused_layers no)
			(net "P3E_CPU0_PE1_SS_C_RXN<2>")
			(clearance 0.1778)
			(thermal_gap 0.1778)
		)
		(pad "A74" thru_hole circle
			(at 63.35014 -3.24993)
			(size 1.0668 1.0668)
			(drill 0.7112)
			(layers "*.Cu" "*.Mask")
			(remove_unused_layers no)
			(net "GND")
			(clearance 0.1778)
			(thermal_gap 0.1778)
		)
		(pad "A75" thru_hole circle
			(at 64.34963 -1.24968)
			(size 1.0668 1.0668)
			(drill 0.7112)
			(layers "*.Cu" "*.Mask")
			(remove_unused_layers no)
			(net "GND")
			(clearance 0.1778)
			(thermal_gap 0.1778)
		)
		(pad "A76" thru_hole circle
			(at 65.35039 -3.24993)
			(size 1.0668 1.0668)
			(drill 0.7112)
			(layers "*.Cu" "*.Mask")
			(remove_unused_layers no)
			(net "P3E_CPU0_PE1_SS_C_RXP<1>")
			(clearance 0.1778)
			(thermal_gap 0.1778)
		)
		(pad "A77" thru_hole circle
			(at 66.34988 -1.24968)
			(size 1.0668 1.0668)
			(drill 0.7112)
			(layers "*.Cu" "*.Mask")
			(remove_unused_layers no)
			(net "P3E_CPU0_PE1_SS_C_RXN<1>")
			(clearance 0.1778)
			(thermal_gap 0.1778)
		)
		(pad "A78" thru_hole circle
			(at 67.34937 -3.24993)
			(size 1.0668 1.0668)
			(drill 0.7112)
			(layers "*.Cu" "*.Mask")
			(remove_unused_layers no)
			(net "GND")
			(clearance 0.1778)
			(thermal_gap 0.1778)
		)
		(pad "A79" thru_hole circle
			(at 68.35013 -1.24968)
			(size 1.0668 1.0668)
			(drill 0.7112)
			(layers "*.Cu" "*.Mask")
			(remove_unused_layers no)
			(net "GND")
			(clearance 0.1778)
			(thermal_gap 0.1778)
		)
		(pad "A80" thru_hole circle
			(at 69.34962 -3.24993)
			(size 1.0668 1.0668)
			(drill 0.7112)
			(layers "*.Cu" "*.Mask")
			(remove_unused_layers no)
			(net "P3E_CPU0_PE1_SS_C_RXP<0>")
			(clearance 0.1778)
			(thermal_gap 0.1778)
		)
		(pad "A81" thru_hole circle
			(at 70.35038 -1.24968)
			(size 1.0668 1.0668)
			(drill 0.7112)
			(layers "*.Cu" "*.Mask")
			(remove_unused_layers no)
			(net "P3E_CPU0_PE1_SS_C_RXN<0>")
			(clearance 0.1778)
			(thermal_gap 0.1778)
		)
		(pad "A82" thru_hole circle
			(at 71.34987 -3.24993)
			(size 1.0668 1.0668)
			(drill 0.7112)
			(layers "*.Cu" "*.Mask")
			(remove_unused_layers no)
			(net "GND")
			(clearance 0.1778)
			(thermal_gap 0.1778)
		)
		(pad "B1" thru_hole circle
			(at -11.64971 1.24968)
			(size 1.0668 1.0668)
			(drill 0.7112)
			(layers "*.Cu" "*.Mask")
			(remove_unused_layers no)
			(net "P12V_SLOT2")
			(clearance 0.1778)
			(thermal_gap 0.1778)
		)
		(pad "B2" thru_hole circle
			(at -10.65022 3.24993)
			(size 1.0668 1.0668)
			(drill 0.7112)
			(layers "*.Cu" "*.Mask")
			(remove_unused_layers no)
			(net "P12V_SLOT2")
			(clearance 0.1778)
			(thermal_gap 0.1778)
		)
		(pad "B3" thru_hole circle
			(at -9.64946 1.24968)
			(size 1.0668 1.0668)
			(drill 0.7112)
			(layers "*.Cu" "*.Mask")
			(remove_unused_layers no)
			(net "P12V_SLOT2")
			(clearance 0.1778)
			(thermal_gap 0.1778)
		)
		(pad "B4" thru_hole circle
			(at -8.64997 3.24993)
			(size 1.0668 1.0668)
			(drill 0.7112)
			(layers "*.Cu" "*.Mask")
			(remove_unused_layers no)
			(net "GND")
			(clearance 0.1778)
			(thermal_gap 0.1778)
		)
		(pad "B5" thru_hole circle
			(at -7.65048 1.24968)
			(size 1.0668 1.0668)
			(drill 0.7112)
			(layers "*.Cu" "*.Mask")
			(remove_unused_layers no)
			(net "SMCLK_BMC_SLOT2_R")
			(clearance 0.1778)
			(thermal_gap 0.1778)
		)
		(pad "B6" thru_hole circle
			(at -6.64972 3.24993)
			(size 1.0668 1.0668)
			(drill 0.7112)
			(layers "*.Cu" "*.Mask")
			(remove_unused_layers no)
			(net "SMDAT_BMC_SLOT2_R")
			(clearance 0.1778)
			(thermal_gap 0.1778)
		)
		(pad "B7" thru_hole circle
			(at -5.65023 1.24968)
			(size 1.0668 1.0668)
			(drill 0.7112)
			(layers "*.Cu" "*.Mask")
			(remove_unused_layers no)
			(net "GND")
			(clearance 0.1778)
			(thermal_gap 0.1778)
		)
		(pad "B8" thru_hole circle
			(at -4.64947 3.24993)
			(size 1.0668 1.0668)
			(drill 0.7112)
			(layers "*.Cu" "*.Mask")
			(remove_unused_layers no)
			(net "P3V3")
			(clearance 0.1778)
			(thermal_gap 0.1778)
		)
		(pad "B9" thru_hole circle
			(at -3.64998 1.24968)
			(size 1.0668 1.0668)
			(drill 0.7112)
			(layers "*.Cu" "*.Mask")
			(remove_unused_layers no)
			(net "Net_101")
			(clearance 0.1778)
			(thermal_gap 0.1778)
		)
		(pad "B10" thru_hole circle
			(at -2.65049 3.24993)
			(size 1.0668 1.0668)
			(drill 0.7112)
			(layers "*.Cu" "*.Mask")
			(remove_unused_layers no)
			(net "P3V3_STBY")
			(clearance 0.1778)
			(thermal_gap 0.1778)
		)
		(pad "B11" thru_hole circle
			(at -1.64973 1.24968)
			(size 1.0668 1.0668)
			(drill 0.7112)
			(layers "*.Cu" "*.Mask")
			(remove_unused_layers no)
			(net "FM_PE_SLOTX24_WAKE_N")
			(clearance 0.1778)
			(thermal_gap 0.1778)
		)
		(pad "B12" thru_hole circle
			(at 1.35001 3.24993)
			(size 1.0668 1.0668)
			(drill 0.7112)
			(layers "*.Cu" "*.Mask")
			(remove_unused_layers no)
			(net "SMB_ALERT_S2_B12_N")
			(clearance 0.1778)
			(thermal_gap 0.1778)
		)
		(pad "B13" thru_hole circle
			(at 2.3495 1.24968)
			(size 1.0668 1.0668)
			(drill 0.7112)
			(layers "*.Cu" "*.Mask")
			(remove_unused_layers no)
			(net "GND")
			(clearance 0.1778)
			(thermal_gap 0.1778)
		)
		(pad "B14" thru_hole circle
			(at 3.35026 3.24993)
			(size 1.0668 1.0668)
			(drill 0.7112)
			(layers "*.Cu" "*.Mask")
			(remove_unused_layers no)
			(net "P3E_CPU0_PE1_PCH_CON_TXP<15>")
			(clearance 0.1778)
			(thermal_gap 0.1778)
		)
		(pad "B15" thru_hole circle
			(at 4.34975 1.24968)
			(size 1.0668 1.0668)
			(drill 0.7112)
			(layers "*.Cu" "*.Mask")
			(remove_unused_layers no)
			(net "P3E_CPU0_PE1_PCH_CON_TXN<15>")
			(clearance 0.1778)
			(thermal_gap 0.1778)
		)
		(pad "B16" thru_hole circle
			(at 5.35051 3.24993)
			(size 1.0668 1.0668)
			(drill 0.7112)
			(layers "*.Cu" "*.Mask")
			(remove_unused_layers no)
			(net "GND")
			(clearance 0.1778)
			(thermal_gap 0.1778)
		)
		(pad "B17" thru_hole circle
			(at 6.35 1.24968)
			(size 1.0668 1.0668)
			(drill 0.7112)
			(layers "*.Cu" "*.Mask")
			(remove_unused_layers no)
			(net "PCIE_SLOT2_PRSNT2_1_N")
			(clearance 0.1778)
			(thermal_gap 0.1778)
		)
		(pad "B18" thru_hole circle
			(at 7.34949 3.24993)
			(size 1.0668 1.0668)
			(drill 0.7112)
			(layers "*.Cu" "*.Mask")
			(remove_unused_layers no)
			(net "GND")
			(clearance 0.1778)
			(thermal_gap 0.1778)
		)
		(pad "B19" thru_hole circle
			(at 8.35025 1.24968)
			(size 1.0668 1.0668)
			(drill 0.7112)
			(layers "*.Cu" "*.Mask")
			(remove_unused_layers no)
			(net "P3E_CPU0_PE1_PCH_CON_TXP<14>")
			(clearance 0.1778)
			(thermal_gap 0.1778)
		)
		(pad "B20" thru_hole circle
			(at 9.34974 3.24993)
			(size 1.0668 1.0668)
			(drill 0.7112)
			(layers "*.Cu" "*.Mask")
			(remove_unused_layers no)
			(net "P3E_CPU0_PE1_PCH_CON_TXN<14>")
			(clearance 0.1778)
			(thermal_gap 0.1778)
		)
		(pad "B21" thru_hole circle
			(at 10.3505 1.24968)
			(size 1.0668 1.0668)
			(drill 0.7112)
			(layers "*.Cu" "*.Mask")
			(remove_unused_layers no)
			(net "GND")
			(clearance 0.1778)
			(thermal_gap 0.1778)
		)
		(pad "B22" thru_hole circle
			(at 11.34999 3.24993)
			(size 1.0668 1.0668)
			(drill 0.7112)
			(layers "*.Cu" "*.Mask")
			(remove_unused_layers no)
			(net "GND")
			(clearance 0.1778)
			(thermal_gap 0.1778)
		)
		(pad "B23" thru_hole circle
			(at 12.34948 1.24968)
			(size 1.0668 1.0668)
			(drill 0.7112)
			(layers "*.Cu" "*.Mask")
			(remove_unused_layers no)
			(net "P3E_CPU0_PE1_PCH_CON_TXP<13>")
			(clearance 0.1778)
			(thermal_gap 0.1778)
		)
		(pad "B24" thru_hole circle
			(at 13.35024 3.24993)
			(size 1.0668 1.0668)
			(drill 0.7112)
			(layers "*.Cu" "*.Mask")
			(remove_unused_layers no)
			(net "P3E_CPU0_PE1_PCH_CON_TXN<13>")
			(clearance 0.1778)
			(thermal_gap 0.1778)
		)
		(pad "B25" thru_hole circle
			(at 14.34973 1.24968)
			(size 1.0668 1.0668)
			(drill 0.7112)
			(layers "*.Cu" "*.Mask")
			(remove_unused_layers no)
			(net "GND")
			(clearance 0.1778)
			(thermal_gap 0.1778)
		)
		(pad "B26" thru_hole circle
			(at 15.35049 3.24993)
			(size 1.0668 1.0668)
			(drill 0.7112)
			(layers "*.Cu" "*.Mask")
			(remove_unused_layers no)
			(net "GND")
			(clearance 0.1778)
			(thermal_gap 0.1778)
		)
		(pad "B27" thru_hole circle
			(at 16.34998 1.24968)
			(size 1.0668 1.0668)
			(drill 0.7112)
			(layers "*.Cu" "*.Mask")
			(remove_unused_layers no)
			(net "P3E_CPU0_PE1_PCH_CON_TXP<12>")
			(clearance 0.1778)
			(thermal_gap 0.1778)
		)
		(pad "B28" thru_hole circle
			(at 17.34947 3.24993)
			(size 1.0668 1.0668)
			(drill 0.7112)
			(layers "*.Cu" "*.Mask")
			(remove_unused_layers no)
			(net "P3E_CPU0_PE1_PCH_CON_TXN<12>")
			(clearance 0.1778)
			(thermal_gap 0.1778)
		)
		(pad "B29" thru_hole circle
			(at 18.35023 1.24968)
			(size 1.0668 1.0668)
			(drill 0.7112)
			(layers "*.Cu" "*.Mask")
			(remove_unused_layers no)
			(net "GND")
			(clearance 0.1778)
			(thermal_gap 0.1778)
		)
		(pad "B30" thru_hole circle
			(at 19.34972 3.24993)
			(size 1.0668 1.0668)
			(drill 0.7112)
			(layers "*.Cu" "*.Mask")
			(remove_unused_layers no)
			(net "FM_PWRBRK_SLOT_N")
			(clearance 0.1778)
			(thermal_gap 0.1778)
		)
		(pad "B31" thru_hole circle
			(at 20.35048 1.24968)
			(size 1.0668 1.0668)
			(drill 0.7112)
			(layers "*.Cu" "*.Mask")
			(remove_unused_layers no)
			(net "PCIE_SLOT2_PRSNT2_2_N")
			(clearance 0.1778)
			(thermal_gap 0.1778)
		)
		(pad "B32" thru_hole circle
			(at 21.34997 3.24993)
			(size 1.0668 1.0668)
			(drill 0.7112)
			(layers "*.Cu" "*.Mask")
			(remove_unused_layers no)
			(net "GND")
			(clearance 0.1778)
			(thermal_gap 0.1778)
		)
		(pad "B33" thru_hole circle
			(at 22.34946 1.24968)
			(size 1.0668 1.0668)
			(drill 0.7112)
			(layers "*.Cu" "*.Mask")
			(remove_unused_layers no)
			(net "P3E_CPU0_PE1_PCH_CON_TXP<11>")
			(clearance 0.1778)
			(thermal_gap 0.1778)
		)
		(pad "B34" thru_hole circle
			(at 23.35022 3.24993)
			(size 1.0668 1.0668)
			(drill 0.7112)
			(layers "*.Cu" "*.Mask")
			(remove_unused_layers no)
			(net "P3E_CPU0_PE1_PCH_CON_TXN<11>")
			(clearance 0.1778)
			(thermal_gap 0.1778)
		)
		(pad "B35" thru_hole circle
			(at 24.34971 1.24968)
			(size 1.0668 1.0668)
			(drill 0.7112)
			(layers "*.Cu" "*.Mask")
			(remove_unused_layers no)
			(net "GND")
			(clearance 0.1778)
			(thermal_gap 0.1778)
		)
		(pad "B36" thru_hole circle
			(at 25.35047 3.24993)
			(size 1.0668 1.0668)
			(drill 0.7112)
			(layers "*.Cu" "*.Mask")
			(remove_unused_layers no)
			(net "GND")
			(clearance 0.1778)
			(thermal_gap 0.1778)
		)
		(pad "B37" thru_hole circle
			(at 26.34996 1.24968)
			(size 1.0668 1.0668)
			(drill 0.7112)
			(layers "*.Cu" "*.Mask")
			(remove_unused_layers no)
			(net "P3E_CPU0_PE1_PCH_CON_TXP<10>")
			(clearance 0.1778)
			(thermal_gap 0.1778)
		)
		(pad "B38" thru_hole circle
			(at 27.34945 3.24993)
			(size 1.0668 1.0668)
			(drill 0.7112)
			(layers "*.Cu" "*.Mask")
			(remove_unused_layers no)
			(net "P3E_CPU0_PE1_PCH_CON_TXN<10>")
			(clearance 0.1778)
			(thermal_gap 0.1778)
		)
		(pad "B39" thru_hole circle
			(at 28.35021 1.24968)
			(size 1.0668 1.0668)
			(drill 0.7112)
			(layers "*.Cu" "*.Mask")
			(remove_unused_layers no)
			(net "GND")
			(clearance 0.1778)
			(thermal_gap 0.1778)
		)
		(pad "B40" thru_hole circle
			(at 29.3497 3.24993)
			(size 1.0668 1.0668)
			(drill 0.7112)
			(layers "*.Cu" "*.Mask")
			(remove_unused_layers no)
			(net "GND")
			(clearance 0.1778)
			(thermal_gap 0.1778)
		)
		(pad "B41" thru_hole circle
			(at 30.35046 1.24968)
			(size 1.0668 1.0668)
			(drill 0.7112)
			(layers "*.Cu" "*.Mask")
			(remove_unused_layers no)
			(net "P3E_CPU0_PE1_PCH_CON_TXP<9>")
			(clearance 0.1778)
			(thermal_gap 0.1778)
		)
		(pad "B42" thru_hole circle
			(at 31.34995 3.24993)
			(size 1.0668 1.0668)
			(drill 0.7112)
			(layers "*.Cu" "*.Mask")
			(remove_unused_layers no)
			(net "P3E_CPU0_PE1_PCH_CON_TXN<9>")
			(clearance 0.1778)
			(thermal_gap 0.1778)
		)
		(pad "B43" thru_hole circle
			(at 32.34944 1.24968)
			(size 1.0668 1.0668)
			(drill 0.7112)
			(layers "*.Cu" "*.Mask")
			(remove_unused_layers no)
			(net "GND")
			(clearance 0.1778)
			(thermal_gap 0.1778)
		)
		(pad "B44" thru_hole circle
			(at 33.3502 3.24993)
			(size 1.0668 1.0668)
			(drill 0.7112)
			(layers "*.Cu" "*.Mask")
			(remove_unused_layers no)
			(net "GND")
			(clearance 0.1778)
			(thermal_gap 0.1778)
		)
		(pad "B45" thru_hole circle
			(at 34.34969 1.24968)
			(size 1.0668 1.0668)
			(drill 0.7112)
			(layers "*.Cu" "*.Mask")
			(remove_unused_layers no)
			(net "P3E_CPU0_PE1_PCH_CON_TXP<8>")
			(clearance 0.1778)
			(thermal_gap 0.1778)
		)
		(pad "B46" thru_hole circle
			(at 35.35045 3.24993)
			(size 1.0668 1.0668)
			(drill 0.7112)
			(layers "*.Cu" "*.Mask")
			(remove_unused_layers no)
			(net "P3E_CPU0_PE1_PCH_CON_TXN<8>")
			(clearance 0.1778)
			(thermal_gap 0.1778)
		)
		(pad "B47" thru_hole circle
			(at 36.34994 1.24968)
			(size 1.0668 1.0668)
			(drill 0.7112)
			(layers "*.Cu" "*.Mask")
			(remove_unused_layers no)
			(net "GND")
			(clearance 0.1778)
			(thermal_gap 0.1778)
		)
		(pad "B48" thru_hole circle
			(at 37.34943 3.24993)
			(size 1.0668 1.0668)
			(drill 0.7112)
			(layers "*.Cu" "*.Mask")
			(remove_unused_layers no)
			(net "PCIE_SLOT2_PRSNT2_3_N")
			(clearance 0.1778)
			(thermal_gap 0.1778)
		)
		(pad "B49" thru_hole circle
			(at 38.35019 1.24968)
			(size 1.0668 1.0668)
			(drill 0.7112)
			(layers "*.Cu" "*.Mask")
			(remove_unused_layers no)
			(net "GND")
			(clearance 0.1778)
			(thermal_gap 0.1778)
		)
		(pad "B50" thru_hole circle
			(at 39.34968 3.24993)
			(size 1.0668 1.0668)
			(drill 0.7112)
			(layers "*.Cu" "*.Mask")
			(remove_unused_layers no)
			(net "P3E_CPU0_PE1_SS_C_TXP<7>")
			(clearance 0.1778)
			(thermal_gap 0.1778)
		)
		(pad "B51" thru_hole circle
			(at 40.35044 1.24968)
			(size 1.0668 1.0668)
			(drill 0.7112)
			(layers "*.Cu" "*.Mask")
			(remove_unused_layers no)
			(net "P3E_CPU0_PE1_SS_C_TXN<7>")
			(clearance 0.1778)
			(thermal_gap 0.1778)
		)
		(pad "B52" thru_hole circle
			(at 41.34993 3.24993)
			(size 1.0668 1.0668)
			(drill 0.7112)
			(layers "*.Cu" "*.Mask")
			(remove_unused_layers no)
			(net "GND")
			(clearance 0.1778)
			(thermal_gap 0.1778)
		)
		(pad "B53" thru_hole circle
			(at 42.34942 1.24968)
			(size 1.0668 1.0668)
			(drill 0.7112)
			(layers "*.Cu" "*.Mask")
			(remove_unused_layers no)
			(net "GND")
			(clearance 0.1778)
			(thermal_gap 0.1778)
		)
		(pad "B54" thru_hole circle
			(at 43.35018 3.24993)
			(size 1.0668 1.0668)
			(drill 0.7112)
			(layers "*.Cu" "*.Mask")
			(remove_unused_layers no)
			(net "P3E_CPU0_PE1_SS_C_TXP<6>")
			(clearance 0.1778)
			(thermal_gap 0.1778)
		)
		(pad "B55" thru_hole circle
			(at 44.34967 1.24968)
			(size 1.0668 1.0668)
			(drill 0.7112)
			(layers "*.Cu" "*.Mask")
			(remove_unused_layers no)
			(net "P3E_CPU0_PE1_SS_C_TXN<6>")
			(clearance 0.1778)
			(thermal_gap 0.1778)
		)
		(pad "B56" thru_hole circle
			(at 45.35043 3.24993)
			(size 1.0668 1.0668)
			(drill 0.7112)
			(layers "*.Cu" "*.Mask")
			(remove_unused_layers no)
			(net "GND")
			(clearance 0.1778)
			(thermal_gap 0.1778)
		)
		(pad "B57" thru_hole circle
			(at 46.34992 1.24968)
			(size 1.0668 1.0668)
			(drill 0.7112)
			(layers "*.Cu" "*.Mask")
			(remove_unused_layers no)
			(net "GND")
			(clearance 0.1778)
			(thermal_gap 0.1778)
		)
		(pad "B58" thru_hole circle
			(at 47.34941 3.24993)
			(size 1.0668 1.0668)
			(drill 0.7112)
			(layers "*.Cu" "*.Mask")
			(remove_unused_layers no)
			(net "P3E_CPU0_PE1_SS_C_TXP<5>")
			(clearance 0.1778)
			(thermal_gap 0.1778)
		)
		(pad "B59" thru_hole circle
			(at 48.35017 1.24968)
			(size 1.0668 1.0668)
			(drill 0.7112)
			(layers "*.Cu" "*.Mask")
			(remove_unused_layers no)
			(net "P3E_CPU0_PE1_SS_C_TXN<5>")
			(clearance 0.1778)
			(thermal_gap 0.1778)
		)
		(pad "B60" thru_hole circle
			(at 49.34966 3.24993)
			(size 1.0668 1.0668)
			(drill 0.7112)
			(layers "*.Cu" "*.Mask")
			(remove_unused_layers no)
			(net "GND")
			(clearance 0.1778)
			(thermal_gap 0.1778)
		)
		(pad "B61" thru_hole circle
			(at 50.35042 1.24968)
			(size 1.0668 1.0668)
			(drill 0.7112)
			(layers "*.Cu" "*.Mask")
			(remove_unused_layers no)
			(net "GND")
			(clearance 0.1778)
			(thermal_gap 0.1778)
		)
		(pad "B62" thru_hole circle
			(at 51.34991 3.24993)
			(size 1.0668 1.0668)
			(drill 0.7112)
			(layers "*.Cu" "*.Mask")
			(remove_unused_layers no)
			(net "P3E_CPU0_PE1_SS_C_TXP<4>")
			(clearance 0.1778)
			(thermal_gap 0.1778)
		)
		(pad "B63" thru_hole circle
			(at 52.3494 1.24968)
			(size 1.0668 1.0668)
			(drill 0.7112)
			(layers "*.Cu" "*.Mask")
			(remove_unused_layers no)
			(net "P3E_CPU0_PE1_SS_C_TXN<4>")
			(clearance 0.1778)
			(thermal_gap 0.1778)
		)
		(pad "B64" thru_hole circle
			(at 53.35016 3.24993)
			(size 1.0668 1.0668)
			(drill 0.7112)
			(layers "*.Cu" "*.Mask")
			(remove_unused_layers no)
			(net "GND")
			(clearance 0.1778)
			(thermal_gap 0.1778)
		)
		(pad "B65" thru_hole circle
			(at 54.34965 1.24968)
			(size 1.0668 1.0668)
			(drill 0.7112)
			(layers "*.Cu" "*.Mask")
			(remove_unused_layers no)
			(net "GND")
			(clearance 0.1778)
			(thermal_gap 0.1778)
		)
		(pad "B66" thru_hole circle
			(at 55.35041 3.24993)
			(size 1.0668 1.0668)
			(drill 0.7112)
			(layers "*.Cu" "*.Mask")
			(remove_unused_layers no)
			(net "P3E_CPU0_PE1_SS_C_TXP<3>")
			(clearance 0.1778)
			(thermal_gap 0.1778)
		)
		(pad "B67" thru_hole circle
			(at 56.3499 1.24968)
			(size 1.0668 1.0668)
			(drill 0.7112)
			(layers "*.Cu" "*.Mask")
			(remove_unused_layers no)
			(net "P3E_CPU0_PE1_SS_C_TXN<3>")
			(clearance 0.1778)
			(thermal_gap 0.1778)
		)
		(pad "B68" thru_hole circle
			(at 57.34939 3.24993)
			(size 1.0668 1.0668)
			(drill 0.7112)
			(layers "*.Cu" "*.Mask")
			(remove_unused_layers no)
			(net "GND")
			(clearance 0.1778)
			(thermal_gap 0.1778)
		)
		(pad "B69" thru_hole circle
			(at 58.35015 1.24968)
			(size 1.0668 1.0668)
			(drill 0.7112)
			(layers "*.Cu" "*.Mask")
			(remove_unused_layers no)
			(net "GND")
			(clearance 0.1778)
			(thermal_gap 0.1778)
		)
		(pad "B70" thru_hole circle
			(at 59.34964 3.24993)
			(size 1.0668 1.0668)
			(drill 0.7112)
			(layers "*.Cu" "*.Mask")
			(remove_unused_layers no)
			(net "P3E_CPU0_PE1_SS_C_TXP<2>")
			(clearance 0.1778)
			(thermal_gap 0.1778)
		)
		(pad "B71" thru_hole circle
			(at 60.3504 1.24968)
			(size 1.0668 1.0668)
			(drill 0.7112)
			(layers "*.Cu" "*.Mask")
			(remove_unused_layers no)
			(net "P3E_CPU0_PE1_SS_C_TXN<2>")
			(clearance 0.1778)
			(thermal_gap 0.1778)
		)
		(pad "B72" thru_hole circle
			(at 61.34989 3.24993)
			(size 1.0668 1.0668)
			(drill 0.7112)
			(layers "*.Cu" "*.Mask")
			(remove_unused_layers no)
			(net "GND")
			(clearance 0.1778)
			(thermal_gap 0.1778)
		)
		(pad "B73" thru_hole circle
			(at 62.34938 1.24968)
			(size 1.0668 1.0668)
			(drill 0.7112)
			(layers "*.Cu" "*.Mask")
			(remove_unused_layers no)
			(net "GND")
			(clearance 0.1778)
			(thermal_gap 0.1778)
		)
		(pad "B74" thru_hole circle
			(at 63.35014 3.24993)
			(size 1.0668 1.0668)
			(drill 0.7112)
			(layers "*.Cu" "*.Mask")
			(remove_unused_layers no)
			(net "P3E_CPU0_PE1_SS_C_TXP<1>")
			(clearance 0.1778)
			(thermal_gap 0.1778)
		)
		(pad "B75" thru_hole circle
			(at 64.34963 1.24968)
			(size 1.0668 1.0668)
			(drill 0.7112)
			(layers "*.Cu" "*.Mask")
			(remove_unused_layers no)
			(net "P3E_CPU0_PE1_SS_C_TXN<1>")
			(clearance 0.1778)
			(thermal_gap 0.1778)
		)
		(pad "B76" thru_hole circle
			(at 65.35039 3.24993)
			(size 1.0668 1.0668)
			(drill 0.7112)
			(layers "*.Cu" "*.Mask")
			(remove_unused_layers no)
			(net "GND")
			(clearance 0.1778)
			(thermal_gap 0.1778)
		)
		(pad "B77" thru_hole circle
			(at 66.34988 1.24968)
			(size 1.0668 1.0668)
			(drill 0.7112)
			(layers "*.Cu" "*.Mask")
			(remove_unused_layers no)
			(net "GND")
			(clearance 0.1778)
			(thermal_gap 0.1778)
		)
		(pad "B78" thru_hole circle
			(at 67.34937 3.24993)
			(size 1.0668 1.0668)
			(drill 0.7112)
			(layers "*.Cu" "*.Mask")
			(remove_unused_layers no)
			(net "P3E_CPU0_PE1_SS_C_TXP<0>")
			(clearance 0.1778)
			(thermal_gap 0.1778)
		)
		(pad "B79" thru_hole circle
			(at 68.35013 1.24968)
			(size 1.0668 1.0668)
			(drill 0.7112)
			(layers "*.Cu" "*.Mask")
			(remove_unused_layers no)
			(net "P3E_CPU0_PE1_SS_C_TXN<0>")
			(clearance 0.1778)
			(thermal_gap 0.1778)
		)
		(pad "B80" thru_hole circle
			(at 69.34962 3.24993)
			(size 1.0668 1.0668)
			(drill 0.7112)
			(layers "*.Cu" "*.Mask")
			(remove_unused_layers no)
			(net "GND")
			(clearance 0.1778)
			(thermal_gap 0.1778)
		)
		(pad "B81" thru_hole circle
			(at 70.35038 1.24968)
			(size 1.0668 1.0668)
			(drill 0.7112)
			(layers "*.Cu" "*.Mask")
			(remove_unused_layers no)
			(net "PCIE_SLOT2_PRSNT2_4_N")
			(clearance 0.1778)
			(thermal_gap 0.1778)
		)
		(pad "B82" thru_hole circle
			(at 71.34987 3.24993)
			(size 1.0668 1.0668)
			(drill 0.7112)
			(layers "*.Cu" "*.Mask")
			(remove_unused_layers no)
			(net "TP_RSVD_SLOT2_PIN82")
			(clearance 0.1778)
			(thermal_gap 0.1778)
		)
		(zone
			(layers "F.Cu" "B.Cu" "In1.Cu" "In2.Cu" "In3.Cu" "In4.Cu")
			(hatch none 0.5)
			(connect_pads
				(clearance 0)
			)
			(min_thickness 0.25)
			(keepout
				(tracks not_allowed)
				(vias allowed)
				(pads allowed)
				(copperpour not_allowed)
				(footprints allowed)
			)
			(placement
				(enabled no)
				(sheetname "")
			)
			(fill
				(thermal_gap 0.5)
				(thermal_bridge_width 0.5)
				(island_removal_mode 0)
			)
			(polygon
				(pts
					(arc
						(start 44.215812 -10.500106)
						(mid 41.244012 -10.500106)
						(end 44.215812 -10.500106)
					)
				)
			)
		)
		(zone
			(layers "F.Cu" "B.Cu" "In1.Cu" "In2.Cu" "In3.Cu" "In4.Cu")
			(hatch none 0.5)
			(connect_pads
				(clearance 0)
			)
			(min_thickness 0.25)
			(keepout
				(tracks not_allowed)
				(vias allowed)
				(pads allowed)
				(copperpour not_allowed)
				(footprints allowed)
			)
			(placement
				(enabled no)
				(sheetname "")
			)
			(fill
				(thermal_gap 0.5)
				(thermal_bridge_width 0.5)
				(island_removal_mode 0)
			)
			(polygon
				(pts
					(arc
						(start 117.365272 -10.500106)
						(mid 114.393472 -10.500106)
						(end 117.365272 -10.500106)
					)
				)
			)
		)
	)
	(footprint ""
		(layer "F.Cu")
		(at 131.2418 -29.5148 -90)
		(property "Reference" "CU11"
			(at 0 0 270)
			(layer "F.SilkS")
			(hide yes)
			(effects
				(font
					(size 1.27 1.27)
				)
			)
		)
		(property "Value" "SC18P50V2JN-1-GP"
			(at 1.1811 -2.7051 270)
			(unlocked yes)
			(layer "F.Fab")
			(hide yes)
			(effects
				(font
					(size 1.016 1.016)
					(thickness 0.1524)
				)
			)
		)
		(property "Device Type" "C402H22"
			(at 1.1811 -4.2291 270)
			(unlocked yes)
			(layer "F.Fab")
			(hide yes)
			(effects
				(font
					(size 1.016 1.016)
					(thickness 0.1524)
				)
			)
		)
		(duplicate_pad_numbers_are_jumpers no)
		(fp_rect
			(start -0.4318 0.9525)
			(end 0.4318 -0.9525)
			(stroke
				(width 0)
				(type default)
			)
			(fill no)
			(layer "F.CrtYd")
		)
		(fp_rect
			(start -0.4318 0.9525)
			(end 0.4318 -0.9525)
			(stroke
				(width 0)
				(type default)
			)
			(fill no)
			(layer "F.Fab")
		)
		(pad "1" smd custom
			(at 0 -0.4445 270)
			(size 0.1524 0.1524)
			(layers "F.Cu" "F.Mask" "F.Paste")
			(net "USB_HUB_XTAL_IN")
			(options
				(clearance outline)
				(anchor circle)
			)
			(primitives
				(gr_poly
					(pts
						(arc
							(start 0.3048 -0.2032)
							(mid 0.275042 -0.275042)
							(end 0.2032 -0.3048)
						)
						(arc
							(start -0.2032 -0.3048)
							(mid -0.275042 -0.275042)
							(end -0.3048 -0.2032)
						)
						(arc
							(start -0.3048 0.2032)
							(mid -0.275042 0.275042)
							(end -0.2032 0.3048)
						)
						(arc
							(start 0.2032 0.3048)
							(mid 0.275042 0.275042)
							(end 0.3048 0.2032)
						)
					)
					(width 0)
					(fill yes)
				)
			)
		)
		(pad "2" smd custom
			(at 0 0.4445 270)
			(size 0.1524 0.1524)
			(layers "F.Cu" "F.Mask" "F.Paste")
			(net "GND")
			(options
				(clearance outline)
				(anchor circle)
			)
			(primitives
				(gr_poly
					(pts
						(arc
							(start 0.3048 -0.2032)
							(mid 0.275042 -0.275042)
							(end 0.2032 -0.3048)
						)
						(arc
							(start -0.2032 -0.3048)
							(mid -0.275042 -0.275042)
							(end -0.3048 -0.2032)
						)
						(arc
							(start -0.3048 0.2032)
							(mid -0.275042 0.275042)
							(end -0.2032 0.3048)
						)
						(arc
							(start 0.2032 0.3048)
							(mid 0.275042 0.275042)
							(end 0.3048 0.2032)
						)
					)
					(width 0)
					(fill yes)
				)
			)
		)
	)
	(footprint ""
		(layer "F.Cu")
		(at 19.2278 -31.9532 180)
		(property "Reference" "C93"
			(at 0 0 180)
			(layer "F.SilkS")
			(hide yes)
			(effects
				(font
					(size 1.27 1.27)
				)
			)
		)
		(property "Value" "SC22U16V5MX-4-GP"
			(at -0.0762 -6.1214 180)
			(unlocked yes)
			(layer "F.Fab")
			(hide yes)
			(effects
				(font
					(size 1.016 1.016)
					(thickness 0.1524)
				)
			)
		)
		(property "Device Type" "C805H58"
			(at -0.0762 -8.1534 180)
			(unlocked yes)
			(layer "F.Fab")
			(hide yes)
			(effects
				(font
					(size 1.016 1.016)
					(thickness 0.1524)
				)
			)
		)
		(duplicate_pad_numbers_are_jumpers no)
		(fp_line
			(start 0.635 0)
			(end -0.635 0)
			(stroke
				(width 0.508)
				(type default)
			)
			(layer "F.SilkS")
		)
		(fp_rect
			(start -0.9652 1.778)
			(end 0.9652 -1.778)
			(stroke
				(width 0)
				(type default)
			)
			(fill no)
			(layer "F.CrtYd")
		)
		(fp_poly
			(pts
				(xy -0.9652 -1.778) (xy 0.9652 -1.778) (xy 0.9652 1.778) (xy -0.9652 1.778)
			)
			(stroke
				(width 0)
				(type default)
			)
			(fill no)
			(layer "F.Fab")
		)
		(pad "1" smd rect
			(at 0 -0.9652 180)
			(size 1.397 1.143)
			(layers "F.Cu" "F.Mask" "F.Paste")
			(net "P12V_SLOT3")
		)
		(pad "2" smd rect
			(at 0 0.9652 180)
			(size 1.397 1.143)
			(layers "F.Cu" "F.Mask" "F.Paste")
			(net "GND")
		)
	)
	(footprint ""
		(layer "F.Cu")
		(at 43.7261 -4.0259 90)
		(property "Reference" "C26"
			(at 0 0 90)
			(layer "F.SilkS")
			(hide yes)
			(effects
				(font
					(size 1.27 1.27)
				)
			)
		)
		(property "Value" "SCD1U16V2KX-3GP"
			(at 1.1811 -2.7051 90)
			(unlocked yes)
			(layer "F.Fab")
			(hide yes)
			(effects
				(font
					(size 1.016 1.016)
					(thickness 0.1524)
				)
			)
		)
		(property "Device Type" "C402H22"
			(at 1.1811 -4.2291 90)
			(unlocked yes)
			(layer "F.Fab")
			(hide yes)
			(effects
				(font
					(size 1.016 1.016)
					(thickness 0.1524)
				)
			)
		)
		(duplicate_pad_numbers_are_jumpers no)
		(fp_rect
			(start -0.4318 0.9525)
			(end 0.4318 -0.9525)
			(stroke
				(width 0)
				(type default)
			)
			(fill no)
			(layer "F.CrtYd")
		)
		(fp_rect
			(start -0.4318 0.9525)
			(end 0.4318 -0.9525)
			(stroke
				(width 0)
				(type default)
			)
			(fill no)
			(layer "F.Fab")
		)
		(pad "1" smd custom
			(at 0 -0.4445 90)
			(size 0.1524 0.1524)
			(layers "F.Cu" "F.Mask" "F.Paste")
			(net "P3V3_STBY")
			(options
				(clearance outline)
				(anchor circle)
			)
			(primitives
				(gr_poly
					(pts
						(arc
							(start 0.3048 -0.2032)
							(mid 0.275042 -0.275042)
							(end 0.2032 -0.3048)
						)
						(arc
							(start -0.2032 -0.3048)
							(mid -0.275042 -0.275042)
							(end -0.3048 -0.2032)
						)
						(arc
							(start -0.3048 0.2032)
							(mid -0.275042 0.275042)
							(end -0.2032 0.3048)
						)
						(arc
							(start 0.2032 0.3048)
							(mid 0.275042 0.275042)
							(end 0.3048 0.2032)
						)
					)
					(width 0)
					(fill yes)
				)
			)
		)
		(pad "2" smd custom
			(at 0 0.4445 90)
			(size 0.1524 0.1524)
			(layers "F.Cu" "F.Mask" "F.Paste")
			(net "GND")
			(options
				(clearance outline)
				(anchor circle)
			)
			(primitives
				(gr_poly
					(pts
						(arc
							(start 0.3048 -0.2032)
							(mid 0.275042 -0.275042)
							(end 0.2032 -0.3048)
						)
						(arc
							(start -0.2032 -0.3048)
							(mid -0.275042 -0.275042)
							(end -0.3048 -0.2032)
						)
						(arc
							(start -0.3048 0.2032)
							(mid -0.275042 0.275042)
							(end -0.2032 0.3048)
						)
						(arc
							(start 0.2032 0.3048)
							(mid 0.275042 0.275042)
							(end 0.3048 0.2032)
						)
					)
					(width 0)
					(fill yes)
				)
			)
		)
	)
	(footprint ""
		(layer "F.Cu")
		(at 26.2128 -18.6563 180)
		(property "Reference" "R63"
			(at 0 0 180)
			(layer "F.SilkS")
			(hide yes)
			(effects
				(font
					(size 1.27 1.27)
				)
			)
		)
		(property "Value" "0R2F-1-GP"
			(at 0.064008 -3.993896 180)
			(unlocked yes)
			(layer "F.Fab")
			(hide yes)
			(effects
				(font
					(size 1.016 1.016)
					(thickness 0.1524)
				)
			)
		)
		(property "Device Type" "R402H16"
			(at 0.064008 -5.517896 180)
			(unlocked yes)
			(layer "F.Fab")
			(hide yes)
			(effects
				(font
					(size 1.016 1.016)
					(thickness 0.1524)
				)
			)
		)
		(duplicate_pad_numbers_are_jumpers no)
		(fp_line
			(start 0.508 -0.9398)
			(end -0.508 -0.9398)
			(stroke
				(width 0.1524)
				(type default)
			)
			(layer "F.SilkS")
		)
		(fp_line
			(start -0.508 -0.9398)
			(end -0.508 0.9398)
			(stroke
				(width 0.1524)
				(type default)
			)
			(layer "F.SilkS")
		)
		(fp_rect
			(start -0.508 0.9398)
			(end 0.508 -0.9398)
			(stroke
				(width 0)
				(type default)
			)
			(fill no)
			(layer "F.CrtYd")
		)
		(fp_rect
			(start -0.508 0.9398)
			(end 0.508 -0.9398)
			(stroke
				(width 0)
				(type default)
			)
			(fill no)
			(layer "F.Fab")
		)
		(pad "1" smd custom
			(at 0 -0.4445 180)
			(size 0.1397 0.1397)
			(layers "F.Cu" "F.Mask" "F.Paste")
			(net "SMB_VMONITOR_SLOT2_MUX_SDA")
			(options
				(clearance outline)
				(anchor circle)
			)
			(primitives
				(gr_poly
					(pts
						(arc
							(start -0.1778 -0.2794)
							(mid -0.249642 -0.249642)
							(end -0.2794 -0.1778)
						)
						(arc
							(start -0.2794 0.1778)
							(mid -0.249642 0.249642)
							(end -0.1778 0.2794)
						)
						(arc
							(start 0.1778 0.2794)
							(mid 0.249642 0.249642)
							(end 0.2794 0.1778)
						)
						(arc
							(start 0.2794 -0.1778)
							(mid 0.249642 -0.249642)
							(end 0.1778 -0.2794)
						)
					)
					(width 0)
					(fill yes)
				)
			)
		)
		(pad "2" smd custom
			(at 0 0.4445 180)
			(size 0.1397 0.1397)
			(layers "F.Cu" "F.Mask" "F.Paste")
			(net "SMDAT_BMC_DEVICE")
			(options
				(clearance outline)
				(anchor circle)
			)
			(primitives
				(gr_poly
					(pts
						(arc
							(start -0.1778 -0.2794)
							(mid -0.249642 -0.249642)
							(end -0.2794 -0.1778)
						)
						(arc
							(start -0.2794 0.1778)
							(mid -0.249642 0.249642)
							(end -0.1778 0.2794)
						)
						(arc
							(start 0.1778 0.2794)
							(mid 0.249642 0.249642)
							(end 0.2794 0.1778)
						)
						(arc
							(start 0.2794 -0.1778)
							(mid 0.249642 -0.249642)
							(end 0.1778 -0.2794)
						)
					)
					(width 0)
					(fill yes)
				)
			)
		)
	)
	(footprint ""
		(layer "F.Cu")
		(at 104.648 -22.1996 -90)
		(property "Reference" "C33"
			(at 0 0 270)
			(layer "F.SilkS")
			(hide yes)
			(effects
				(font
					(size 1.27 1.27)
				)
			)
		)
		(property "Value" "SCD1U16V2KX-3GP"
			(at 1.1811 -2.7051 270)
			(unlocked yes)
			(layer "F.Fab")
			(hide yes)
			(effects
				(font
					(size 1.016 1.016)
					(thickness 0.1524)
				)
			)
		)
		(property "Device Type" "C402H22"
			(at 1.1811 -4.2291 270)
			(unlocked yes)
			(layer "F.Fab")
			(hide yes)
			(effects
				(font
					(size 1.016 1.016)
					(thickness 0.1524)
				)
			)
		)
		(duplicate_pad_numbers_are_jumpers no)
		(fp_rect
			(start -0.4318 0.9525)
			(end 0.4318 -0.9525)
			(stroke
				(width 0)
				(type default)
			)
			(fill no)
			(layer "F.CrtYd")
		)
		(fp_rect
			(start -0.4318 0.9525)
			(end 0.4318 -0.9525)
			(stroke
				(width 0)
				(type default)
			)
			(fill no)
			(layer "F.Fab")
		)
		(pad "1" smd custom
			(at 0 -0.4445 270)
			(size 0.1524 0.1524)
			(layers "F.Cu" "F.Mask" "F.Paste")
			(net "P3V3_STBY")
			(options
				(clearance outline)
				(anchor circle)
			)
			(primitives
				(gr_poly
					(pts
						(arc
							(start 0.3048 -0.2032)
							(mid 0.275042 -0.275042)
							(end 0.2032 -0.3048)
						)
						(arc
							(start -0.2032 -0.3048)
							(mid -0.275042 -0.275042)
							(end -0.3048 -0.2032)
						)
						(arc
							(start -0.3048 0.2032)
							(mid -0.275042 0.275042)
							(end -0.2032 0.3048)
						)
						(arc
							(start 0.2032 0.3048)
							(mid 0.275042 0.275042)
							(end 0.3048 0.2032)
						)
					)
					(width 0)
					(fill yes)
				)
			)
		)
		(pad "2" smd custom
			(at 0 0.4445 270)
			(size 0.1524 0.1524)
			(layers "F.Cu" "F.Mask" "F.Paste")
			(net "GND")
			(options
				(clearance outline)
				(anchor circle)
			)
			(primitives
				(gr_poly
					(pts
						(arc
							(start 0.3048 -0.2032)
							(mid 0.275042 -0.275042)
							(end 0.2032 -0.3048)
						)
						(arc
							(start -0.2032 -0.3048)
							(mid -0.275042 -0.275042)
							(end -0.3048 -0.2032)
						)
						(arc
							(start -0.3048 0.2032)
							(mid -0.275042 0.275042)
							(end -0.2032 0.3048)
						)
						(arc
							(start 0.2032 0.3048)
							(mid 0.275042 0.275042)
							(end 0.3048 0.2032)
						)
					)
					(width 0)
					(fill yes)
				)
			)
		)
	)
	(footprint ""
		(layer "F.Cu")
		(at 133.1722 -29.5148 90)
		(property "Reference" "CU12"
			(at 0 0 90)
			(layer "F.SilkS")
			(hide yes)
			(effects
				(font
					(size 1.27 1.27)
				)
			)
		)
		(property "Value" "SC18P50V2JN-1-GP"
			(at 1.1811 -2.7051 90)
			(unlocked yes)
			(layer "F.Fab")
			(hide yes)
			(effects
				(font
					(size 1.016 1.016)
					(thickness 0.1524)
				)
			)
		)
		(property "Device Type" "C402H22"
			(at 1.1811 -4.2291 90)
			(unlocked yes)
			(layer "F.Fab")
			(hide yes)
			(effects
				(font
					(size 1.016 1.016)
					(thickness 0.1524)
				)
			)
		)
		(duplicate_pad_numbers_are_jumpers no)
		(fp_rect
			(start -0.4318 0.9525)
			(end 0.4318 -0.9525)
			(stroke
				(width 0)
				(type default)
			)
			(fill no)
			(layer "F.CrtYd")
		)
		(fp_rect
			(start -0.4318 0.9525)
			(end 0.4318 -0.9525)
			(stroke
				(width 0)
				(type default)
			)
			(fill no)
			(layer "F.Fab")
		)
		(pad "1" smd custom
			(at 0 -0.4445 90)
			(size 0.1524 0.1524)
			(layers "F.Cu" "F.Mask" "F.Paste")
			(net "USB_HUB_XTAL_OUT")
			(options
				(clearance outline)
				(anchor circle)
			)
			(primitives
				(gr_poly
					(pts
						(arc
							(start 0.3048 -0.2032)
							(mid 0.275042 -0.275042)
							(end 0.2032 -0.3048)
						)
						(arc
							(start -0.2032 -0.3048)
							(mid -0.275042 -0.275042)
							(end -0.3048 -0.2032)
						)
						(arc
							(start -0.3048 0.2032)
							(mid -0.275042 0.275042)
							(end -0.2032 0.3048)
						)
						(arc
							(start 0.2032 0.3048)
							(mid 0.275042 0.275042)
							(end 0.3048 0.2032)
						)
					)
					(width 0)
					(fill yes)
				)
			)
		)
		(pad "2" smd custom
			(at 0 0.4445 90)
			(size 0.1524 0.1524)
			(layers "F.Cu" "F.Mask" "F.Paste")
			(net "GND")
			(options
				(clearance outline)
				(anchor circle)
			)
			(primitives
				(gr_poly
					(pts
						(arc
							(start 0.3048 -0.2032)
							(mid 0.275042 -0.275042)
							(end 0.2032 -0.3048)
						)
						(arc
							(start -0.2032 -0.3048)
							(mid -0.275042 -0.275042)
							(end -0.3048 -0.2032)
						)
						(arc
							(start -0.3048 0.2032)
							(mid -0.275042 0.275042)
							(end -0.2032 0.3048)
						)
						(arc
							(start 0.2032 0.3048)
							(mid 0.275042 0.275042)
							(end 0.3048 0.2032)
						)
					)
					(width 0)
					(fill yes)
				)
			)
		)
	)
	(footprint ""
		(layer "F.Cu")
		(at 82.9564 -19.1516 90)
		(property "Reference" "C36"
			(at 0 0 90)
			(layer "F.SilkS")
			(hide yes)
			(effects
				(font
					(size 1.27 1.27)
				)
			)
		)
		(property "Value" "SCD1U25V3KX-GP"
			(at 0 -2.8194 90)
			(unlocked yes)
			(layer "F.Fab")
			(hide yes)
			(effects
				(font
					(size 1.016 1.016)
					(thickness 0.1524)
				)
			)
		)
		(property "Device Type" "C603H36"
			(at 0 -4.3434 90)
			(unlocked yes)
			(layer "F.Fab")
			(hide yes)
			(effects
				(font
					(size 1.016 1.016)
					(thickness 0.1524)
				)
			)
		)
		(duplicate_pad_numbers_are_jumpers no)
		(fp_line
			(start 0.508 0)
			(end -0.508 0)
			(stroke
				(width 0.2032)
				(type default)
			)
			(layer "F.SilkS")
		)
		(fp_rect
			(start -0.5842 1.3335)
			(end 0.5842 -1.3335)
			(stroke
				(width 0)
				(type default)
			)
			(fill no)
			(layer "F.CrtYd")
		)
		(fp_rect
			(start -0.5842 1.3335)
			(end 0.5842 -1.3335)
			(stroke
				(width 0)
				(type default)
			)
			(fill no)
			(layer "F.Fab")
		)
		(pad "1" smd custom
			(at 0 -0.762 90)
			(size 0.2159 0.2159)
			(layers "F.Cu" "F.Mask" "F.Paste")
			(net "P12V")
			(options
				(clearance outline)
				(anchor circle)
			)
			(primitives
				(gr_poly
					(pts
						(arc
							(start -0.3302 -0.4318)
							(mid -0.402042 -0.402042)
							(end -0.4318 -0.3302)
						)
						(arc
							(start -0.4318 0.3302)
							(mid -0.402042 0.402042)
							(end -0.3302 0.4318)
						)
						(arc
							(start 0.3302 0.4318)
							(mid 0.402042 0.402042)
							(end 0.4318 0.3302)
						)
						(arc
							(start 0.4318 -0.3302)
							(mid 0.402042 -0.402042)
							(end 0.3302 -0.4318)
						)
					)
					(width 0)
					(fill yes)
				)
			)
		)
		(pad "2" smd custom
			(at 0 0.762 90)
			(size 0.2159 0.2159)
			(layers "F.Cu" "F.Mask" "F.Paste")
			(net "GND")
			(options
				(clearance outline)
				(anchor circle)
			)
			(primitives
				(gr_poly
					(pts
						(arc
							(start -0.3302 -0.4318)
							(mid -0.402042 -0.402042)
							(end -0.4318 -0.3302)
						)
						(arc
							(start -0.4318 0.3302)
							(mid -0.402042 0.402042)
							(end -0.3302 0.4318)
						)
						(arc
							(start 0.3302 0.4318)
							(mid 0.402042 0.402042)
							(end 0.4318 0.3302)
						)
						(arc
							(start 0.4318 -0.3302)
							(mid 0.402042 -0.402042)
							(end 0.3302 -0.4318)
						)
					)
					(width 0)
					(fill yes)
				)
			)
		)
	)
	(footprint ""
		(layer "F.Cu")
		(at 53.7464 -22.1996 180)
		(property "Reference" "R35"
			(at 0 0 180)
			(layer "F.SilkS")
			(hide yes)
			(effects
				(font
					(size 1.27 1.27)
				)
			)
		)
		(property "Value" "0R2F-1-GP"
			(at 0.064008 -3.993896 180)
			(unlocked yes)
			(layer "F.Fab")
			(hide yes)
			(effects
				(font
					(size 1.016 1.016)
					(thickness 0.1524)
				)
			)
		)
		(property "Device Type" "R402H16"
			(at 0.064008 -5.517896 180)
			(unlocked yes)
			(layer "F.Fab")
			(hide yes)
			(effects
				(font
					(size 1.016 1.016)
					(thickness 0.1524)
				)
			)
		)
		(duplicate_pad_numbers_are_jumpers no)
		(fp_line
			(start 0.508 -0.9398)
			(end -0.508 -0.9398)
			(stroke
				(width 0.1524)
				(type default)
			)
			(layer "F.SilkS")
		)
		(fp_line
			(start -0.508 -0.9398)
			(end -0.508 0.9398)
			(stroke
				(width 0.1524)
				(type default)
			)
			(layer "F.SilkS")
		)
		(fp_rect
			(start -0.508 0.9398)
			(end 0.508 -0.9398)
			(stroke
				(width 0)
				(type default)
			)
			(fill no)
			(layer "F.CrtYd")
		)
		(fp_rect
			(start -0.508 0.9398)
			(end 0.508 -0.9398)
			(stroke
				(width 0)
				(type default)
			)
			(fill no)
			(layer "F.Fab")
		)
		(pad "1" smd custom
			(at 0 -0.4445 180)
			(size 0.1397 0.1397)
			(layers "F.Cu" "F.Mask" "F.Paste")
			(net "SMB_PCIE_SLOT3_ALERT_N")
			(options
				(clearance outline)
				(anchor circle)
			)
			(primitives
				(gr_poly
					(pts
						(arc
							(start -0.1778 -0.2794)
							(mid -0.249642 -0.249642)
							(end -0.2794 -0.1778)
						)
						(arc
							(start -0.2794 0.1778)
							(mid -0.249642 0.249642)
							(end -0.1778 0.2794)
						)
						(arc
							(start 0.1778 0.2794)
							(mid 0.249642 0.249642)
							(end 0.2794 0.1778)
						)
						(arc
							(start 0.2794 -0.1778)
							(mid 0.249642 -0.249642)
							(end 0.1778 -0.2794)
						)
					)
					(width 0)
					(fill yes)
				)
			)
		)
		(pad "2" smd custom
			(at 0 0.4445 180)
			(size 0.1397 0.1397)
			(layers "F.Cu" "F.Mask" "F.Paste")
			(net "SMB_ALERT_S3_B12_N")
			(options
				(clearance outline)
				(anchor circle)
			)
			(primitives
				(gr_poly
					(pts
						(arc
							(start -0.1778 -0.2794)
							(mid -0.249642 -0.249642)
							(end -0.2794 -0.1778)
						)
						(arc
							(start -0.2794 0.1778)
							(mid -0.249642 0.249642)
							(end -0.1778 0.2794)
						)
						(arc
							(start 0.1778 0.2794)
							(mid 0.249642 0.249642)
							(end 0.2794 0.1778)
						)
						(arc
							(start 0.2794 -0.1778)
							(mid 0.249642 -0.249642)
							(end 0.1778 -0.2794)
						)
					)
					(width 0)
					(fill yes)
				)
			)
		)
	)
	(footprint ""
		(layer "F.Cu")
		(at 128.8796 -30.861 180)
		(property "Reference" "RU24"
			(at 0 0 180)
			(layer "F.SilkS")
			(hide yes)
			(effects
				(font
					(size 1.27 1.27)
				)
			)
		)
		(property "Value" "12KR2F-L-GP"
			(at 0.064008 -3.993896 180)
			(unlocked yes)
			(layer "F.Fab")
			(hide yes)
			(effects
				(font
					(size 1.016 1.016)
					(thickness 0.1524)
				)
			)
		)
		(property "Device Type" "R402H16"
			(at 0.064008 -5.517896 180)
			(unlocked yes)
			(layer "F.Fab")
			(hide yes)
			(effects
				(font
					(size 1.016 1.016)
					(thickness 0.1524)
				)
			)
		)
		(duplicate_pad_numbers_are_jumpers no)
		(fp_line
			(start 0.508 -0.9398)
			(end -0.508 -0.9398)
			(stroke
				(width 0.1524)
				(type default)
			)
			(layer "F.SilkS")
		)
		(fp_line
			(start -0.508 -0.9398)
			(end -0.508 0.9398)
			(stroke
				(width 0.1524)
				(type default)
			)
			(layer "F.SilkS")
		)
		(fp_rect
			(start -0.508 0.9398)
			(end 0.508 -0.9398)
			(stroke
				(width 0)
				(type default)
			)
			(fill no)
			(layer "F.CrtYd")
		)
		(fp_rect
			(start -0.508 0.9398)
			(end 0.508 -0.9398)
			(stroke
				(width 0)
				(type default)
			)
			(fill no)
			(layer "F.Fab")
		)
		(pad "1" smd custom
			(at 0 -0.4445 180)
			(size 0.1397 0.1397)
			(layers "F.Cu" "F.Mask" "F.Paste")
			(net "RBIAS")
			(options
				(clearance outline)
				(anchor circle)
			)
			(primitives
				(gr_poly
					(pts
						(arc
							(start -0.1778 -0.2794)
							(mid -0.249642 -0.249642)
							(end -0.2794 -0.1778)
						)
						(arc
							(start -0.2794 0.1778)
							(mid -0.249642 0.249642)
							(end -0.1778 0.2794)
						)
						(arc
							(start 0.1778 0.2794)
							(mid 0.249642 0.249642)
							(end 0.2794 0.1778)
						)
						(arc
							(start 0.2794 -0.1778)
							(mid 0.249642 -0.249642)
							(end 0.1778 -0.2794)
						)
					)
					(width 0)
					(fill yes)
				)
			)
		)
		(pad "2" smd custom
			(at 0 0.4445 180)
			(size 0.1397 0.1397)
			(layers "F.Cu" "F.Mask" "F.Paste")
			(net "GND")
			(options
				(clearance outline)
				(anchor circle)
			)
			(primitives
				(gr_poly
					(pts
						(arc
							(start -0.1778 -0.2794)
							(mid -0.249642 -0.249642)
							(end -0.2794 -0.1778)
						)
						(arc
							(start -0.2794 0.1778)
							(mid -0.249642 0.249642)
							(end -0.1778 0.2794)
						)
						(arc
							(start 0.1778 0.2794)
							(mid 0.249642 0.249642)
							(end 0.2794 0.1778)
						)
						(arc
							(start 0.2794 -0.1778)
							(mid 0.249642 -0.249642)
							(end 0.1778 -0.2794)
						)
					)
					(width 0)
					(fill yes)
				)
			)
		)
	)
	(footprint ""
		(layer "F.Cu")
		(at 23.7998 4.1783 90)
		(property "Reference" "R56"
			(at 0 0 90)
			(layer "F.SilkS")
			(hide yes)
			(effects
				(font
					(size 1.27 1.27)
				)
			)
		)
		(property "Value" "4K7R2F-GP"
			(at 0.064008 -3.993896 90)
			(unlocked yes)
			(layer "F.Fab")
			(hide yes)
			(effects
				(font
					(size 1.016 1.016)
					(thickness 0.1524)
				)
			)
		)
		(property "Device Type" "R402H16"
			(at 0.064008 -5.517896 90)
			(unlocked yes)
			(layer "F.Fab")
			(hide yes)
			(effects
				(font
					(size 1.016 1.016)
					(thickness 0.1524)
				)
			)
		)
		(duplicate_pad_numbers_are_jumpers no)
		(fp_line
			(start 0.508 -0.9398)
			(end -0.508 -0.9398)
			(stroke
				(width 0.1524)
				(type default)
			)
			(layer "F.SilkS")
		)
		(fp_line
			(start -0.508 -0.9398)
			(end -0.508 0.9398)
			(stroke
				(width 0.1524)
				(type default)
			)
			(layer "F.SilkS")
		)
		(fp_rect
			(start -0.508 0.9398)
			(end 0.508 -0.9398)
			(stroke
				(width 0)
				(type default)
			)
			(fill no)
			(layer "F.CrtYd")
		)
		(fp_rect
			(start -0.508 0.9398)
			(end 0.508 -0.9398)
			(stroke
				(width 0)
				(type default)
			)
			(fill no)
			(layer "F.Fab")
		)
		(pad "1" smd custom
			(at 0 -0.4445 90)
			(size 0.1397 0.1397)
			(layers "F.Cu" "F.Mask" "F.Paste")
			(net "P3V3_STBY")
			(options
				(clearance outline)
				(anchor circle)
			)
			(primitives
				(gr_poly
					(pts
						(arc
							(start -0.1778 -0.2794)
							(mid -0.249642 -0.249642)
							(end -0.2794 -0.1778)
						)
						(arc
							(start -0.2794 0.1778)
							(mid -0.249642 0.249642)
							(end -0.1778 0.2794)
						)
						(arc
							(start 0.1778 0.2794)
							(mid 0.249642 0.249642)
							(end 0.2794 0.1778)
						)
						(arc
							(start 0.2794 -0.1778)
							(mid 0.249642 -0.249642)
							(end 0.1778 -0.2794)
						)
					)
					(width 0)
					(fill yes)
				)
			)
		)
		(pad "2" smd custom
			(at 0 0.4445 90)
			(size 0.1397 0.1397)
			(layers "F.Cu" "F.Mask" "F.Paste")
			(net "FM_SLT_CFG0")
			(options
				(clearance outline)
				(anchor circle)
			)
			(primitives
				(gr_poly
					(pts
						(arc
							(start -0.1778 -0.2794)
							(mid -0.249642 -0.249642)
							(end -0.2794 -0.1778)
						)
						(arc
							(start -0.2794 0.1778)
							(mid -0.249642 0.249642)
							(end -0.1778 0.2794)
						)
						(arc
							(start 0.1778 0.2794)
							(mid 0.249642 0.249642)
							(end 0.2794 0.1778)
						)
						(arc
							(start 0.2794 -0.1778)
							(mid 0.249642 -0.249642)
							(end 0.1778 -0.2794)
						)
					)
					(width 0)
					(fill yes)
				)
			)
		)
	)
	(footprint ""
		(layer "F.Cu")
		(at 95.5802 -16.8656)
		(property "Reference" "R69"
			(at 0 0 0)
			(layer "F.SilkS")
			(hide yes)
			(effects
				(font
					(size 1.27 1.27)
				)
			)
		)
		(property "Value" "0R2F-1-GP"
			(at 0.064008 -3.993896 0)
			(unlocked yes)
			(layer "F.Fab")
			(hide yes)
			(effects
				(font
					(size 1.016 1.016)
					(thickness 0.1524)
				)
			)
		)
		(property "Device Type" "R402H16"
			(at 0.064008 -5.517896 0)
			(unlocked yes)
			(layer "F.Fab")
			(hide yes)
			(effects
				(font
					(size 1.016 1.016)
					(thickness 0.1524)
				)
			)
		)
		(duplicate_pad_numbers_are_jumpers no)
		(fp_line
			(start -0.508 -0.9398)
			(end -0.508 0.9398)
			(stroke
				(width 0.1524)
				(type default)
			)
			(layer "F.SilkS")
		)
		(fp_line
			(start 0.508 -0.9398)
			(end -0.508 -0.9398)
			(stroke
				(width 0.1524)
				(type default)
			)
			(layer "F.SilkS")
		)
		(fp_rect
			(start -0.508 0.9398)
			(end 0.508 -0.9398)
			(stroke
				(width 0)
				(type default)
			)
			(fill no)
			(layer "F.CrtYd")
		)
		(fp_rect
			(start -0.508 0.9398)
			(end 0.508 -0.9398)
			(stroke
				(width 0)
				(type default)
			)
			(fill no)
			(layer "F.Fab")
		)
		(pad "1" smd custom
			(at 0 -0.4445)
			(size 0.1397 0.1397)
			(layers "F.Cu" "F.Mask" "F.Paste")
			(net "PERST_SLOT_N")
			(options
				(clearance outline)
				(anchor circle)
			)
			(primitives
				(gr_poly
					(pts
						(arc
							(start -0.1778 -0.2794)
							(mid -0.249642 -0.249642)
							(end -0.2794 -0.1778)
						)
						(arc
							(start -0.2794 0.1778)
							(mid -0.249642 0.249642)
							(end -0.1778 0.2794)
						)
						(arc
							(start 0.1778 0.2794)
							(mid 0.249642 0.249642)
							(end 0.2794 0.1778)
						)
						(arc
							(start 0.2794 -0.1778)
							(mid 0.249642 -0.249642)
							(end 0.1778 -0.2794)
						)
					)
					(width 0)
					(fill yes)
				)
			)
		)
		(pad "2" smd custom
			(at 0 0.4445)
			(size 0.1397 0.1397)
			(layers "F.Cu" "F.Mask" "F.Paste")
			(net "RESET_BUF_N_SLOT2")
			(options
				(clearance outline)
				(anchor circle)
			)
			(primitives
				(gr_poly
					(pts
						(arc
							(start -0.1778 -0.2794)
							(mid -0.249642 -0.249642)
							(end -0.2794 -0.1778)
						)
						(arc
							(start -0.2794 0.1778)
							(mid -0.249642 0.249642)
							(end -0.1778 0.2794)
						)
						(arc
							(start 0.1778 0.2794)
							(mid 0.249642 0.249642)
							(end 0.2794 0.1778)
						)
						(arc
							(start 0.2794 -0.1778)
							(mid 0.249642 -0.249642)
							(end 0.1778 -0.2794)
						)
					)
					(width 0)
					(fill yes)
				)
			)
		)
	)
	(footprint ""
		(layer "F.Cu")
		(at 26.2382 -23.749 180)
		(property "Reference" "R91"
			(at 0 0 180)
			(layer "F.SilkS")
			(hide yes)
			(effects
				(font
					(size 1.27 1.27)
				)
			)
		)
		(property "Value" "10KR2F-2-GP"
			(at 0.064008 -3.993896 180)
			(unlocked yes)
			(layer "F.Fab")
			(hide yes)
			(effects
				(font
					(size 1.016 1.016)
					(thickness 0.1524)
				)
			)
		)
		(property "Device Type" "R402H16"
			(at 0.064008 -5.517896 180)
			(unlocked yes)
			(layer "F.Fab")
			(hide yes)
			(effects
				(font
					(size 1.016 1.016)
					(thickness 0.1524)
				)
			)
		)
		(duplicate_pad_numbers_are_jumpers no)
		(fp_line
			(start 0.508 -0.9398)
			(end -0.508 -0.9398)
			(stroke
				(width 0.1524)
				(type default)
			)
			(layer "F.SilkS")
		)
		(fp_line
			(start -0.508 -0.9398)
			(end -0.508 0.9398)
			(stroke
				(width 0.1524)
				(type default)
			)
			(layer "F.SilkS")
		)
		(fp_rect
			(start -0.508 0.9398)
			(end 0.508 -0.9398)
			(stroke
				(width 0)
				(type default)
			)
			(fill no)
			(layer "F.CrtYd")
		)
		(fp_rect
			(start -0.508 0.9398)
			(end 0.508 -0.9398)
			(stroke
				(width 0)
				(type default)
			)
			(fill no)
			(layer "F.Fab")
		)
		(pad "1" smd custom
			(at 0 -0.4445 180)
			(size 0.1397 0.1397)
			(layers "F.Cu" "F.Mask" "F.Paste")
			(net "P3V3_STBY")
			(options
				(clearance outline)
				(anchor circle)
			)
			(primitives
				(gr_poly
					(pts
						(arc
							(start -0.1778 -0.2794)
							(mid -0.249642 -0.249642)
							(end -0.2794 -0.1778)
						)
						(arc
							(start -0.2794 0.1778)
							(mid -0.249642 0.249642)
							(end -0.1778 0.2794)
						)
						(arc
							(start 0.1778 0.2794)
							(mid 0.249642 0.249642)
							(end 0.2794 0.1778)
						)
						(arc
							(start 0.2794 -0.1778)
							(mid 0.249642 -0.249642)
							(end 0.1778 -0.2794)
						)
					)
					(width 0)
					(fill yes)
				)
			)
		)
		(pad "2" smd custom
			(at 0 0.4445 180)
			(size 0.1397 0.1397)
			(layers "F.Cu" "F.Mask" "F.Paste")
			(net "SLOT3_VMONITOR_A1")
			(options
				(clearance outline)
				(anchor circle)
			)
			(primitives
				(gr_poly
					(pts
						(arc
							(start -0.1778 -0.2794)
							(mid -0.249642 -0.249642)
							(end -0.2794 -0.1778)
						)
						(arc
							(start -0.2794 0.1778)
							(mid -0.249642 0.249642)
							(end -0.1778 0.2794)
						)
						(arc
							(start 0.1778 0.2794)
							(mid 0.249642 0.249642)
							(end 0.2794 0.1778)
						)
						(arc
							(start 0.2794 -0.1778)
							(mid 0.249642 -0.249642)
							(end 0.1778 -0.2794)
						)
					)
					(width 0)
					(fill yes)
				)
			)
		)
	)
	(footprint ""
		(layer "F.Cu")
		(at 115.5446 -3.7592)
		(property "Reference" "TP16"
			(at 0 0 0)
			(layer "F.SilkS")
			(hide yes)
			(effects
				(font
					(size 1.27 1.27)
				)
			)
		)
		(property "Value" "TPAD24"
			(at 0 -1.6129 0)
			(unlocked yes)
			(layer "F.Fab")
			(hide yes)
			(effects
				(font
					(size 1.016 1.016)
					(thickness 0.1524)
				)
			)
		)
		(property "Device Type" "TPAD24"
			(at 0 -3.1369 0)
			(unlocked yes)
			(layer "F.Fab")
			(hide yes)
			(effects
				(font
					(size 1.016 1.016)
					(thickness 0.1524)
				)
			)
		)
		(duplicate_pad_numbers_are_jumpers no)
		(fp_poly
			(pts
				(arc
					(start 0.3048 0)
					(mid -0.3048 0)
					(end 0.3048 0)
				)
			)
			(stroke
				(width 0)
				(type default)
			)
			(fill no)
			(layer "F.CrtYd")
		)
		(fp_poly
			(pts
				(arc
					(start 0.6096 0)
					(mid -0.6096 0)
					(end 0.6096 0)
				)
			)
			(stroke
				(width 0)
				(type default)
			)
			(fill no)
			(layer "F.Fab")
		)
		(pad "1" smd circle
			(at 0 0)
			(size 0.6096 0.6096)
			(layers "F.Cu" "F.Mask" "F.Paste")
			(net "TP_RSVD_SLOT2_PIN82")
		)
	)
	(footprint ""
		(layer "F.Cu")
		(at 130.4036 -25.527 90)
		(property "Reference" "RU50"
			(at 0 0 90)
			(layer "F.SilkS")
			(hide yes)
			(effects
				(font
					(size 1.27 1.27)
				)
			)
		)
		(property "Value" "100KR2F-L1-GP"
			(at 0.064008 -3.993896 90)
			(unlocked yes)
			(layer "F.Fab")
			(hide yes)
			(effects
				(font
					(size 1.016 1.016)
					(thickness 0.1524)
				)
			)
		)
		(property "Device Type" "R402H16"
			(at 0.064008 -5.517896 90)
			(unlocked yes)
			(layer "F.Fab")
			(hide yes)
			(effects
				(font
					(size 1.016 1.016)
					(thickness 0.1524)
				)
			)
		)
		(duplicate_pad_numbers_are_jumpers no)
		(fp_line
			(start 0.508 -0.9398)
			(end -0.508 -0.9398)
			(stroke
				(width 0.1524)
				(type default)
			)
			(layer "F.SilkS")
		)
		(fp_line
			(start -0.508 -0.9398)
			(end -0.508 0.9398)
			(stroke
				(width 0.1524)
				(type default)
			)
			(layer "F.SilkS")
		)
		(fp_rect
			(start -0.508 0.9398)
			(end 0.508 -0.9398)
			(stroke
				(width 0)
				(type default)
			)
			(fill no)
			(layer "F.CrtYd")
		)
		(fp_rect
			(start -0.508 0.9398)
			(end 0.508 -0.9398)
			(stroke
				(width 0)
				(type default)
			)
			(fill no)
			(layer "F.Fab")
		)
		(pad "1" smd custom
			(at 0 -0.4445 90)
			(size 0.1397 0.1397)
			(layers "F.Cu" "F.Mask" "F.Paste")
			(net "NON_REM0")
			(options
				(clearance outline)
				(anchor circle)
			)
			(primitives
				(gr_poly
					(pts
						(arc
							(start -0.1778 -0.2794)
							(mid -0.249642 -0.249642)
							(end -0.2794 -0.1778)
						)
						(arc
							(start -0.2794 0.1778)
							(mid -0.249642 0.249642)
							(end -0.1778 0.2794)
						)
						(arc
							(start 0.1778 0.2794)
							(mid 0.249642 0.249642)
							(end 0.2794 0.1778)
						)
						(arc
							(start 0.2794 -0.1778)
							(mid 0.249642 -0.249642)
							(end 0.1778 -0.2794)
						)
					)
					(width 0)
					(fill yes)
				)
			)
		)
		(pad "2" smd custom
			(at 0 0.4445 90)
			(size 0.1397 0.1397)
			(layers "F.Cu" "F.Mask" "F.Paste")
			(net "P3V3_USB_HUB")
			(options
				(clearance outline)
				(anchor circle)
			)
			(primitives
				(gr_poly
					(pts
						(arc
							(start -0.1778 -0.2794)
							(mid -0.249642 -0.249642)
							(end -0.2794 -0.1778)
						)
						(arc
							(start -0.2794 0.1778)
							(mid -0.249642 0.249642)
							(end -0.1778 0.2794)
						)
						(arc
							(start 0.1778 0.2794)
							(mid 0.249642 0.249642)
							(end 0.2794 0.1778)
						)
						(arc
							(start 0.2794 -0.1778)
							(mid 0.249642 -0.249642)
							(end 0.1778 -0.2794)
						)
					)
					(width 0)
					(fill yes)
				)
			)
		)
	)
	(footprint ""
		(layer "F.Cu")
		(at 117.6528 -19.0246 180)
		(property "Reference" "R115"
			(at 0 0 180)
			(layer "F.SilkS")
			(hide yes)
			(effects
				(font
					(size 1.27 1.27)
				)
			)
		)
		(property "Value" "10KR2F-2-GP"
			(at 0.064008 -3.993896 180)
			(unlocked yes)
			(layer "F.Fab")
			(hide yes)
			(effects
				(font
					(size 1.016 1.016)
					(thickness 0.1524)
				)
			)
		)
		(property "Device Type" "R402H16"
			(at 0.064008 -5.517896 180)
			(unlocked yes)
			(layer "F.Fab")
			(hide yes)
			(effects
				(font
					(size 1.016 1.016)
					(thickness 0.1524)
				)
			)
		)
		(duplicate_pad_numbers_are_jumpers no)
		(fp_line
			(start 0.508 -0.9398)
			(end -0.508 -0.9398)
			(stroke
				(width 0.1524)
				(type default)
			)
			(layer "F.SilkS")
		)
		(fp_line
			(start -0.508 -0.9398)
			(end -0.508 0.9398)
			(stroke
				(width 0.1524)
				(type default)
			)
			(layer "F.SilkS")
		)
		(fp_rect
			(start -0.508 0.9398)
			(end 0.508 -0.9398)
			(stroke
				(width 0)
				(type default)
			)
			(fill no)
			(layer "F.CrtYd")
		)
		(fp_rect
			(start -0.508 0.9398)
			(end 0.508 -0.9398)
			(stroke
				(width 0)
				(type default)
			)
			(fill no)
			(layer "F.Fab")
		)
		(pad "1" smd custom
			(at 0 -0.4445 180)
			(size 0.1397 0.1397)
			(layers "F.Cu" "F.Mask" "F.Paste")
			(net "GPIO_B_EXP_A2")
			(options
				(clearance outline)
				(anchor circle)
			)
			(primitives
				(gr_poly
					(pts
						(arc
							(start -0.1778 -0.2794)
							(mid -0.249642 -0.249642)
							(end -0.2794 -0.1778)
						)
						(arc
							(start -0.2794 0.1778)
							(mid -0.249642 0.249642)
							(end -0.1778 0.2794)
						)
						(arc
							(start 0.1778 0.2794)
							(mid 0.249642 0.249642)
							(end 0.2794 0.1778)
						)
						(arc
							(start 0.2794 -0.1778)
							(mid 0.249642 -0.249642)
							(end 0.1778 -0.2794)
						)
					)
					(width 0)
					(fill yes)
				)
			)
		)
		(pad "2" smd custom
			(at 0 0.4445 180)
			(size 0.1397 0.1397)
			(layers "F.Cu" "F.Mask" "F.Paste")
			(net "GND")
			(options
				(clearance outline)
				(anchor circle)
			)
			(primitives
				(gr_poly
					(pts
						(arc
							(start -0.1778 -0.2794)
							(mid -0.249642 -0.249642)
							(end -0.2794 -0.1778)
						)
						(arc
							(start -0.2794 0.1778)
							(mid -0.249642 0.249642)
							(end -0.1778 0.2794)
						)
						(arc
							(start 0.1778 0.2794)
							(mid 0.249642 0.249642)
							(end 0.2794 0.1778)
						)
						(arc
							(start 0.2794 -0.1778)
							(mid 0.249642 -0.249642)
							(end 0.1778 -0.2794)
						)
					)
					(width 0)
					(fill yes)
				)
			)
		)
	)
	(footprint ""
		(layer "F.Cu")
		(at 131.7244 -13.589 -90)
		(property "Reference" "R124"
			(at 0 0 270)
			(layer "F.SilkS")
			(hide yes)
			(effects
				(font
					(size 1.27 1.27)
				)
			)
		)
		(property "Value" "10KR2F-2-GP"
			(at 0.064008 -3.993896 270)
			(unlocked yes)
			(layer "F.Fab")
			(hide yes)
			(effects
				(font
					(size 1.016 1.016)
					(thickness 0.1524)
				)
			)
		)
		(property "Device Type" "R402H16"
			(at 0.064008 -5.517896 270)
			(unlocked yes)
			(layer "F.Fab")
			(hide yes)
			(effects
				(font
					(size 1.016 1.016)
					(thickness 0.1524)
				)
			)
		)
		(duplicate_pad_numbers_are_jumpers no)
		(fp_line
			(start -0.508 -0.9398)
			(end -0.508 0.9398)
			(stroke
				(width 0.1524)
				(type default)
			)
			(layer "F.SilkS")
		)
		(fp_line
			(start 0.508 -0.9398)
			(end -0.508 -0.9398)
			(stroke
				(width 0.1524)
				(type default)
			)
			(layer "F.SilkS")
		)
		(fp_rect
			(start -0.508 0.9398)
			(end 0.508 -0.9398)
			(stroke
				(width 0)
				(type default)
			)
			(fill no)
			(layer "F.CrtYd")
		)
		(fp_rect
			(start -0.508 0.9398)
			(end 0.508 -0.9398)
			(stroke
				(width 0)
				(type default)
			)
			(fill no)
			(layer "F.Fab")
		)
		(pad "1" smd custom
			(at 0 -0.4445 270)
			(size 0.1397 0.1397)
			(layers "F.Cu" "F.Mask" "F.Paste")
			(net "P3V3_STBY")
			(options
				(clearance outline)
				(anchor circle)
			)
			(primitives
				(gr_poly
					(pts
						(arc
							(start -0.1778 -0.2794)
							(mid -0.249642 -0.249642)
							(end -0.2794 -0.1778)
						)
						(arc
							(start -0.2794 0.1778)
							(mid -0.249642 0.249642)
							(end -0.1778 0.2794)
						)
						(arc
							(start 0.1778 0.2794)
							(mid 0.249642 0.249642)
							(end 0.2794 0.1778)
						)
						(arc
							(start 0.2794 -0.1778)
							(mid 0.249642 -0.249642)
							(end 0.1778 -0.2794)
						)
					)
					(width 0)
					(fill yes)
				)
			)
		)
		(pad "2" smd custom
			(at 0 0.4445 270)
			(size 0.1397 0.1397)
			(layers "F.Cu" "F.Mask" "F.Paste")
			(net "GPIO_B_IO1_4")
			(options
				(clearance outline)
				(anchor circle)
			)
			(primitives
				(gr_poly
					(pts
						(arc
							(start -0.1778 -0.2794)
							(mid -0.249642 -0.249642)
							(end -0.2794 -0.1778)
						)
						(arc
							(start -0.2794 0.1778)
							(mid -0.249642 0.249642)
							(end -0.1778 0.2794)
						)
						(arc
							(start 0.1778 0.2794)
							(mid 0.249642 0.249642)
							(end 0.2794 0.1778)
						)
						(arc
							(start 0.2794 -0.1778)
							(mid 0.249642 -0.249642)
							(end 0.1778 -0.2794)
						)
					)
					(width 0)
					(fill yes)
				)
			)
		)
	)
	(footprint ""
		(layer "F.Cu")
		(at 80.772 -24.4602 -90)
		(property "Reference" "R114"
			(at 0 0 270)
			(layer "F.SilkS")
			(hide yes)
			(effects
				(font
					(size 1.27 1.27)
				)
			)
		)
		(property "Value" "4K7R2F-GP"
			(at 0.064008 -3.993896 270)
			(unlocked yes)
			(layer "F.Fab")
			(hide yes)
			(effects
				(font
					(size 1.016 1.016)
					(thickness 0.1524)
				)
			)
		)
		(property "Device Type" "R402H16"
			(at 0.064008 -5.517896 270)
			(unlocked yes)
			(layer "F.Fab")
			(hide yes)
			(effects
				(font
					(size 1.016 1.016)
					(thickness 0.1524)
				)
			)
		)
		(duplicate_pad_numbers_are_jumpers no)
		(fp_line
			(start -0.508 -0.9398)
			(end -0.508 0.9398)
			(stroke
				(width 0.1524)
				(type default)
			)
			(layer "F.SilkS")
		)
		(fp_line
			(start 0.508 -0.9398)
			(end -0.508 -0.9398)
			(stroke
				(width 0.1524)
				(type default)
			)
			(layer "F.SilkS")
		)
		(fp_rect
			(start -0.508 0.9398)
			(end 0.508 -0.9398)
			(stroke
				(width 0)
				(type default)
			)
			(fill no)
			(layer "F.CrtYd")
		)
		(fp_rect
			(start -0.508 0.9398)
			(end 0.508 -0.9398)
			(stroke
				(width 0)
				(type default)
			)
			(fill no)
			(layer "F.Fab")
		)
		(pad "1" smd custom
			(at 0 -0.4445 270)
			(size 0.1397 0.1397)
			(layers "F.Cu" "F.Mask" "F.Paste")
			(net "P3V3_STBY")
			(options
				(clearance outline)
				(anchor circle)
			)
			(primitives
				(gr_poly
					(pts
						(arc
							(start -0.1778 -0.2794)
							(mid -0.249642 -0.249642)
							(end -0.2794 -0.1778)
						)
						(arc
							(start -0.2794 0.1778)
							(mid -0.249642 0.249642)
							(end -0.1778 0.2794)
						)
						(arc
							(start 0.1778 0.2794)
							(mid 0.249642 0.249642)
							(end 0.2794 0.1778)
						)
						(arc
							(start 0.2794 -0.1778)
							(mid 0.249642 -0.249642)
							(end 0.1778 -0.2794)
						)
					)
					(width 0)
					(fill yes)
				)
			)
		)
		(pad "2" smd custom
			(at 0 0.4445 270)
			(size 0.1397 0.1397)
			(layers "F.Cu" "F.Mask" "F.Paste")
			(net "PCIE_SLOT3_PRSNT2_3_N")
			(options
				(clearance outline)
				(anchor circle)
			)
			(primitives
				(gr_poly
					(pts
						(arc
							(start -0.1778 -0.2794)
							(mid -0.249642 -0.249642)
							(end -0.2794 -0.1778)
						)
						(arc
							(start -0.2794 0.1778)
							(mid -0.249642 0.249642)
							(end -0.1778 0.2794)
						)
						(arc
							(start 0.1778 0.2794)
							(mid 0.249642 0.249642)
							(end 0.2794 0.1778)
						)
						(arc
							(start 0.2794 -0.1778)
							(mid 0.249642 -0.249642)
							(end 0.1778 -0.2794)
						)
					)
					(width 0)
					(fill yes)
				)
			)
		)
	)
	(footprint ""
		(layer "F.Cu")
		(at 119.9388 -16.637 90)
		(property "Reference" "R47"
			(at 0 0 90)
			(layer "F.SilkS")
			(hide yes)
			(effects
				(font
					(size 1.27 1.27)
				)
			)
		)
		(property "Value" "4K7R2F-GP"
			(at 0.064008 -3.993896 90)
			(unlocked yes)
			(layer "F.Fab")
			(hide yes)
			(effects
				(font
					(size 1.016 1.016)
					(thickness 0.1524)
				)
			)
		)
		(property "Device Type" "R402H16"
			(at 0.064008 -5.517896 90)
			(unlocked yes)
			(layer "F.Fab")
			(hide yes)
			(effects
				(font
					(size 1.016 1.016)
					(thickness 0.1524)
				)
			)
		)
		(duplicate_pad_numbers_are_jumpers no)
		(fp_line
			(start 0.508 -0.9398)
			(end -0.508 -0.9398)
			(stroke
				(width 0.1524)
				(type default)
			)
			(layer "F.SilkS")
		)
		(fp_line
			(start -0.508 -0.9398)
			(end -0.508 0.9398)
			(stroke
				(width 0.1524)
				(type default)
			)
			(layer "F.SilkS")
		)
		(fp_rect
			(start -0.508 0.9398)
			(end 0.508 -0.9398)
			(stroke
				(width 0)
				(type default)
			)
			(fill no)
			(layer "F.CrtYd")
		)
		(fp_rect
			(start -0.508 0.9398)
			(end 0.508 -0.9398)
			(stroke
				(width 0)
				(type default)
			)
			(fill no)
			(layer "F.Fab")
		)
		(pad "1" smd custom
			(at 0 -0.4445 90)
			(size 0.1397 0.1397)
			(layers "F.Cu" "F.Mask" "F.Paste")
			(net "P3V3_STBY")
			(options
				(clearance outline)
				(anchor circle)
			)
			(primitives
				(gr_poly
					(pts
						(arc
							(start -0.1778 -0.2794)
							(mid -0.249642 -0.249642)
							(end -0.2794 -0.1778)
						)
						(arc
							(start -0.2794 0.1778)
							(mid -0.249642 0.249642)
							(end -0.1778 0.2794)
						)
						(arc
							(start 0.1778 0.2794)
							(mid 0.249642 0.249642)
							(end 0.2794 0.1778)
						)
						(arc
							(start 0.2794 -0.1778)
							(mid 0.249642 -0.249642)
							(end 0.1778 -0.2794)
						)
					)
					(width 0)
					(fill yes)
				)
			)
		)
		(pad "2" smd custom
			(at 0 0.4445 90)
			(size 0.1397 0.1397)
			(layers "F.Cu" "F.Mask" "F.Paste")
			(net "PCIE_SLOT2_PRSNT2_3_N")
			(options
				(clearance outline)
				(anchor circle)
			)
			(primitives
				(gr_poly
					(pts
						(arc
							(start -0.1778 -0.2794)
							(mid -0.249642 -0.249642)
							(end -0.2794 -0.1778)
						)
						(arc
							(start -0.2794 0.1778)
							(mid -0.249642 0.249642)
							(end -0.1778 0.2794)
						)
						(arc
							(start 0.1778 0.2794)
							(mid 0.249642 0.249642)
							(end 0.2794 0.1778)
						)
						(arc
							(start 0.2794 -0.1778)
							(mid 0.249642 -0.249642)
							(end 0.1778 -0.2794)
						)
					)
					(width 0)
					(fill yes)
				)
			)
		)
	)
	(footprint ""
		(layer "F.Cu")
		(at 112.7252 0.4064 180)
		(property "Reference" "R10"
			(at 0 0 180)
			(layer "F.SilkS")
			(hide yes)
			(effects
				(font
					(size 1.27 1.27)
				)
			)
		)
		(property "Value" "4K7R2F-GP"
			(at 0.064008 -3.993896 180)
			(unlocked yes)
			(layer "F.Fab")
			(hide yes)
			(effects
				(font
					(size 1.016 1.016)
					(thickness 0.1524)
				)
			)
		)
		(property "Device Type" "R402H16"
			(at 0.064008 -5.517896 180)
			(unlocked yes)
			(layer "F.Fab")
			(hide yes)
			(effects
				(font
					(size 1.016 1.016)
					(thickness 0.1524)
				)
			)
		)
		(duplicate_pad_numbers_are_jumpers no)
		(fp_line
			(start 0.508 -0.9398)
			(end -0.508 -0.9398)
			(stroke
				(width 0.1524)
				(type default)
			)
			(layer "F.SilkS")
		)
		(fp_line
			(start -0.508 -0.9398)
			(end -0.508 0.9398)
			(stroke
				(width 0.1524)
				(type default)
			)
			(layer "F.SilkS")
		)
		(fp_rect
			(start -0.508 0.9398)
			(end 0.508 -0.9398)
			(stroke
				(width 0)
				(type default)
			)
			(fill no)
			(layer "F.CrtYd")
		)
		(fp_rect
			(start -0.508 0.9398)
			(end 0.508 -0.9398)
			(stroke
				(width 0)
				(type default)
			)
			(fill no)
			(layer "F.Fab")
		)
		(pad "1" smd custom
			(at 0 -0.4445 180)
			(size 0.1397 0.1397)
			(layers "F.Cu" "F.Mask" "F.Paste")
			(net "P3V3_STBY")
			(options
				(clearance outline)
				(anchor circle)
			)
			(primitives
				(gr_poly
					(pts
						(arc
							(start -0.1778 -0.2794)
							(mid -0.249642 -0.249642)
							(end -0.2794 -0.1778)
						)
						(arc
							(start -0.2794 0.1778)
							(mid -0.249642 0.249642)
							(end -0.1778 0.2794)
						)
						(arc
							(start 0.1778 0.2794)
							(mid 0.249642 0.249642)
							(end 0.2794 0.1778)
						)
						(arc
							(start 0.2794 -0.1778)
							(mid 0.249642 -0.249642)
							(end 0.1778 -0.2794)
						)
					)
					(width 0)
					(fill yes)
				)
			)
		)
		(pad "2" smd custom
			(at 0 0.4445 180)
			(size 0.1397 0.1397)
			(layers "F.Cu" "F.Mask" "F.Paste")
			(net "PU_B_MUX_SDA2")
			(options
				(clearance outline)
				(anchor circle)
			)
			(primitives
				(gr_poly
					(pts
						(arc
							(start -0.1778 -0.2794)
							(mid -0.249642 -0.249642)
							(end -0.2794 -0.1778)
						)
						(arc
							(start -0.2794 0.1778)
							(mid -0.249642 0.249642)
							(end -0.1778 0.2794)
						)
						(arc
							(start 0.1778 0.2794)
							(mid 0.249642 0.249642)
							(end 0.2794 0.1778)
						)
						(arc
							(start 0.2794 -0.1778)
							(mid 0.249642 -0.249642)
							(end 0.1778 -0.2794)
						)
					)
					(width 0)
					(fill yes)
				)
			)
		)
	)
	(footprint ""
		(layer "F.Cu")
		(at 118.7958 -32.3596 90)
		(property "Reference" "RU29"
			(at 0 0 90)
			(layer "F.SilkS")
			(hide yes)
			(effects
				(font
					(size 1.27 1.27)
				)
			)
		)
		(property "Value" "10KR2F-2-GP"
			(at 0.064008 -3.993896 90)
			(unlocked yes)
			(layer "F.Fab")
			(hide yes)
			(effects
				(font
					(size 1.016 1.016)
					(thickness 0.1524)
				)
			)
		)
		(property "Device Type" "R402H16"
			(at 0.064008 -5.517896 90)
			(unlocked yes)
			(layer "F.Fab")
			(hide yes)
			(effects
				(font
					(size 1.016 1.016)
					(thickness 0.1524)
				)
			)
		)
		(duplicate_pad_numbers_are_jumpers no)
		(fp_line
			(start 0.508 -0.9398)
			(end -0.508 -0.9398)
			(stroke
				(width 0.1524)
				(type default)
			)
			(layer "F.SilkS")
		)
		(fp_line
			(start -0.508 -0.9398)
			(end -0.508 0.9398)
			(stroke
				(width 0.1524)
				(type default)
			)
			(layer "F.SilkS")
		)
		(fp_rect
			(start -0.508 0.9398)
			(end 0.508 -0.9398)
			(stroke
				(width 0)
				(type default)
			)
			(fill no)
			(layer "F.CrtYd")
		)
		(fp_rect
			(start -0.508 0.9398)
			(end 0.508 -0.9398)
			(stroke
				(width 0)
				(type default)
			)
			(fill no)
			(layer "F.Fab")
		)
		(pad "1" smd custom
			(at 0 -0.4445 90)
			(size 0.1397 0.1397)
			(layers "F.Cu" "F.Mask" "F.Paste")
			(net "P3V3_USB_HUB")
			(options
				(clearance outline)
				(anchor circle)
			)
			(primitives
				(gr_poly
					(pts
						(arc
							(start -0.1778 -0.2794)
							(mid -0.249642 -0.249642)
							(end -0.2794 -0.1778)
						)
						(arc
							(start -0.2794 0.1778)
							(mid -0.249642 0.249642)
							(end -0.1778 0.2794)
						)
						(arc
							(start 0.1778 0.2794)
							(mid 0.249642 0.249642)
							(end 0.2794 0.1778)
						)
						(arc
							(start 0.2794 -0.1778)
							(mid 0.249642 -0.249642)
							(end 0.1778 -0.2794)
						)
					)
					(width 0)
					(fill yes)
				)
			)
		)
		(pad "2" smd custom
			(at 0 0.4445 90)
			(size 0.1397 0.1397)
			(layers "F.Cu" "F.Mask" "F.Paste")
			(net "USB_DP2")
			(options
				(clearance outline)
				(anchor circle)
			)
			(primitives
				(gr_poly
					(pts
						(arc
							(start -0.1778 -0.2794)
							(mid -0.249642 -0.249642)
							(end -0.2794 -0.1778)
						)
						(arc
							(start -0.2794 0.1778)
							(mid -0.249642 0.249642)
							(end -0.1778 0.2794)
						)
						(arc
							(start 0.1778 0.2794)
							(mid 0.249642 0.249642)
							(end 0.2794 0.1778)
						)
						(arc
							(start 0.2794 -0.1778)
							(mid 0.249642 -0.249642)
							(end 0.1778 -0.2794)
						)
					)
					(width 0)
					(fill yes)
				)
			)
		)
	)
	(footprint ""
		(layer "F.Cu")
		(at 140.5001 -25.584912 -90)
		(property "Reference" "H2"
			(at 0 0 270)
			(layer "F.SilkS")
			(hide yes)
			(effects
				(font
					(size 1.27 1.27)
				)
			)
		)
		(property "Value" "STFT363B238R224H453-GP"
			(at 7.0612 1.4605 270)
			(unlocked yes)
			(layer "F.Fab")
			(hide yes)
			(effects
				(font
					(size 1.016 1.016)
					(thickness 0.1524)
				)
			)
		)
		(property "Device Type" "STFT363B238R224H453"
			(at 7.0612 -0.0635 270)
			(unlocked yes)
			(layer "F.Fab")
			(hide yes)
			(effects
				(font
					(size 1.016 1.016)
					(thickness 0.1524)
				)
			)
		)
		(duplicate_pad_numbers_are_jumpers no)
		(fp_circle
			(center 0 0)
			(end 0 -5.3594)
			(stroke
				(width 0.3048)
				(type default)
			)
			(fill no)
			(layer "F.SilkS")
		)
		(fp_poly
			(pts
				(arc
					(start 0 -3.5306)
					(mid 0 3.5306)
					(end 0 -3.5306)
				)
			)
			(stroke
				(width 0)
				(type default)
			)
			(fill no)
			(layer "B.CrtYd")
		)
		(fp_poly
			(pts
				(arc
					(start 0 -5.0038)
					(mid 0 5.0038)
					(end 0 -5.0038)
				)
			)
			(stroke
				(width 0)
				(type default)
			)
			(fill no)
			(layer "F.CrtYd")
		)
		(fp_poly
			(pts
				(arc
					(start 5.5118 0.00635)
					(mid -5.511804 0)
					(end 5.5118 -0.00635)
				)
				(arc
					(start 5.0038 -0.00635)
					(mid -5.003804 0)
					(end 5.0038 0.00635)
				)
			)
			(stroke
				(width 0)
				(type default)
			)
			(fill no)
			(layer "F.CrtYd")
		)
		(fp_poly
			(pts
				(arc
					(start 0 -3.5306)
					(mid 0 3.5306)
					(end 0 -3.5306)
				)
			)
			(stroke
				(width 0)
				(type default)
			)
			(fill no)
			(layer "B.Fab")
		)
		(fp_poly
			(pts
				(arc
					(start 0 -5.5118)
					(mid 0 5.5118)
					(end 0 -5.5118)
				)
			)
			(stroke
				(width 0)
				(type default)
			)
			(fill no)
			(layer "F.Fab")
		)
		(pad "1" thru_hole circle
			(at 0 0 270)
			(size 9.2202 9.2202)
			(drill 5.6896)
			(layers "*.Cu" "*.Mask")
			(remove_unused_layers no)
			(net "GND")
			(clearance -1.2573)
			(thermal_gap 0.3302)
			(padstack
				(mode front_inner_back)
				(layer "Inner"
					(shape circle)
					(size 6.0452 6.0452)
					(clearance 0.3302)
				)
				(layer "B.Cu"
					(shape circle)
					(size 6.0452 6.0452)
					(clearance 0.3302)
				)
			)
		)
	)
	(footprint ""
		(layer "F.Cu")
		(at 132.207 -4.6736 90)
		(property "Reference" "R143"
			(at 0 0 90)
			(layer "F.SilkS")
			(hide yes)
			(effects
				(font
					(size 1.27 1.27)
				)
			)
		)
		(property "Value" "10KR2F-2-GP"
			(at 0.064008 -3.993896 90)
			(unlocked yes)
			(layer "F.Fab")
			(hide yes)
			(effects
				(font
					(size 1.016 1.016)
					(thickness 0.1524)
				)
			)
		)
		(property "Device Type" "R402H16"
			(at 0.064008 -5.517896 90)
			(unlocked yes)
			(layer "F.Fab")
			(hide yes)
			(effects
				(font
					(size 1.016 1.016)
					(thickness 0.1524)
				)
			)
		)
		(duplicate_pad_numbers_are_jumpers no)
		(fp_line
			(start 0.508 -0.9398)
			(end -0.508 -0.9398)
			(stroke
				(width 0.1524)
				(type default)
			)
			(layer "F.SilkS")
		)
		(fp_line
			(start -0.508 -0.9398)
			(end -0.508 0.9398)
			(stroke
				(width 0.1524)
				(type default)
			)
			(layer "F.SilkS")
		)
		(fp_rect
			(start -0.508 0.9398)
			(end 0.508 -0.9398)
			(stroke
				(width 0)
				(type default)
			)
			(fill no)
			(layer "F.CrtYd")
		)
		(fp_rect
			(start -0.508 0.9398)
			(end 0.508 -0.9398)
			(stroke
				(width 0)
				(type default)
			)
			(fill no)
			(layer "F.Fab")
		)
		(pad "1" smd custom
			(at 0 -0.4445 90)
			(size 0.1397 0.1397)
			(layers "F.Cu" "F.Mask" "F.Paste")
			(net "GPIO_P_EXP_A2")
			(options
				(clearance outline)
				(anchor circle)
			)
			(primitives
				(gr_poly
					(pts
						(arc
							(start -0.1778 -0.2794)
							(mid -0.249642 -0.249642)
							(end -0.2794 -0.1778)
						)
						(arc
							(start -0.2794 0.1778)
							(mid -0.249642 0.249642)
							(end -0.1778 0.2794)
						)
						(arc
							(start 0.1778 0.2794)
							(mid 0.249642 0.249642)
							(end 0.2794 0.1778)
						)
						(arc
							(start 0.2794 -0.1778)
							(mid 0.249642 -0.249642)
							(end 0.1778 -0.2794)
						)
					)
					(width 0)
					(fill yes)
				)
			)
		)
		(pad "2" smd custom
			(at 0 0.4445 90)
			(size 0.1397 0.1397)
			(layers "F.Cu" "F.Mask" "F.Paste")
			(net "GND")
			(options
				(clearance outline)
				(anchor circle)
			)
			(primitives
				(gr_poly
					(pts
						(arc
							(start -0.1778 -0.2794)
							(mid -0.249642 -0.249642)
							(end -0.2794 -0.1778)
						)
						(arc
							(start -0.2794 0.1778)
							(mid -0.249642 0.249642)
							(end -0.1778 0.2794)
						)
						(arc
							(start 0.1778 0.2794)
							(mid 0.249642 0.249642)
							(end 0.2794 0.1778)
						)
						(arc
							(start 0.2794 -0.1778)
							(mid 0.249642 -0.249642)
							(end 0.1778 -0.2794)
						)
					)
					(width 0)
					(fill yes)
				)
			)
		)
	)
	(footprint ""
		(layer "F.Cu")
		(at 132.334 -31.7754 180)
		(property "Reference" "XU1"
			(at 0 0 180)
			(layer "F.SilkS")
			(hide yes)
			(effects
				(font
					(size 1.27 1.27)
				)
			)
		)
		(property "Value" "XTAL-24MHZ-87-GP"
			(at -0.0889 -3.0988 180)
			(unlocked yes)
			(layer "F.Fab")
			(hide yes)
			(effects
				(font
					(size 1.016 1.016)
					(thickness 0.1524)
				)
			)
		)
		(property "Device Type" "OSC-3225-4P-4H30"
			(at -0.0889 -4.6228 180)
			(unlocked yes)
			(layer "F.Fab")
			(hide yes)
			(effects
				(font
					(size 1.016 1.016)
					(thickness 0.1524)
				)
			)
		)
		(duplicate_pad_numbers_are_jumpers no)
		(fp_line
			(start 2.1209 1.5494)
			(end 2.1209 -1.5494)
			(stroke
				(width 0.1524)
				(type default)
			)
			(layer "F.SilkS")
		)
		(fp_line
			(start 2.1209 -1.5494)
			(end -2.1209 -1.5494)
			(stroke
				(width 0.1524)
				(type default)
			)
			(layer "F.SilkS")
		)
		(fp_line
			(start -1.143 1.651)
			(end -2.2098 1.651)
			(stroke
				(width 0.3302)
				(type default)
			)
			(layer "F.SilkS")
		)
		(fp_line
			(start -2.1209 1.5494)
			(end 2.1209 1.5494)
			(stroke
				(width 0.1524)
				(type default)
			)
			(layer "F.SilkS")
		)
		(fp_line
			(start -2.1209 -1.5494)
			(end -2.1209 1.5494)
			(stroke
				(width 0.1524)
				(type default)
			)
			(layer "F.SilkS")
		)
		(fp_line
			(start -2.2098 1.651)
			(end -2.2098 0.6604)
			(stroke
				(width 0.3302)
				(type default)
			)
			(layer "F.SilkS")
		)
		(fp_poly
			(pts
				(xy -2.6289 1.1938) (xy -2.6289 0.3302) (xy -2.1971 0.762)
			)
			(stroke
				(width 0)
				(type default)
			)
			(fill yes)
			(layer "F.SilkS")
		)
		(fp_rect
			(start -1.6002 1.2446)
			(end 1.6002 -1.2446)
			(stroke
				(width 0)
				(type default)
			)
			(fill no)
			(layer "F.CrtYd")
		)
		(fp_poly
			(pts
				(xy -2.3749 1.8034) (xy -2.3749 -1.8034) (xy 2.3749 -1.8034) (xy 2.3749 1.8034) (xy 0.00254 1.8034)
				(xy 0.00254 1.2446) (xy 1.6002 1.2446) (xy 1.6002 -1.2446) (xy -1.6002 -1.2446) (xy -1.6002 1.2446)
				(xy -0.00254 1.2446) (xy -0.00254 1.8034)
			)
			(stroke
				(width 0)
				(type default)
			)
			(fill no)
			(layer "F.CrtYd")
		)
		(fp_rect
			(start -2.3749 1.8034)
			(end 2.3749 -1.8034)
			(stroke
				(width 0)
				(type default)
			)
			(fill no)
			(layer "F.Fab")
		)
		(pad "1" smd rect
			(at -1.171448 0.756412 180)
			(size 1.397 1.0668)
			(layers "F.Cu" "F.Mask" "F.Paste")
			(net "USB_HUB_XTAL_OUT")
		)
		(pad "2" smd rect
			(at 1.171448 0.756412 180)
			(size 1.397 1.0668)
			(layers "F.Cu" "F.Mask" "F.Paste")
			(net "GND")
		)
		(pad "3" smd rect
			(at 1.171448 -0.756412 180)
			(size 1.397 1.0668)
			(layers "F.Cu" "F.Mask" "F.Paste")
			(net "USB_HUB_XTAL_IN")
		)
		(pad "4" smd rect
			(at -1.171448 -0.756412 180)
			(size 1.397 1.0668)
			(layers "F.Cu" "F.Mask" "F.Paste")
			(net "GND")
		)
		(zone
			(layer "F.Cu")
			(hatch none 0.5)
			(connect_pads
				(clearance 0)
			)
			(min_thickness 0.25)
			(keepout
				(tracks not_allowed)
				(vias allowed)
				(pads allowed)
				(copperpour not_allowed)
				(footprints allowed)
			)
			(placement
				(enabled no)
				(sheetname "")
			)
			(fill
				(thermal_gap 0.5)
				(thermal_bridge_width 0.5)
				(island_removal_mode 0)
			)
			(polygon
				(pts
					(xy 132.3848 -31.8262) (xy 132.2832 -31.8262) (xy 132.2832 -31.7246) (xy 132.3848 -31.7246)
				)
			)
		)
		(zone
			(layer "F.Cu")
			(hatch none 0.5)
			(connect_pads
				(clearance 0)
			)
			(min_thickness 0.25)
			(keepout
				(tracks allowed)
				(vias not_allowed)
				(pads allowed)
				(copperpour not_allowed)
				(footprints allowed)
			)
			(placement
				(enabled no)
				(sheetname "")
			)
			(fill
				(thermal_gap 0.5)
				(thermal_bridge_width 0.5)
				(island_removal_mode 0)
			)
			(polygon
				(pts
					(xy 132.806948 -30.485588) (xy 131.861052 -30.485588) (xy 131.861052 -31.552388) (xy 130.464052 -31.552388)
					(xy 130.464052 -31.998412) (xy 131.861052 -31.998412) (xy 131.861052 -33.065212) (xy 132.806948 -33.065212)
					(xy 132.806948 -31.998412) (xy 134.203948 -31.998412) (xy 134.203948 -31.552388) (xy 132.806948 -31.552388)
				)
			)
		)
	)
	(footprint ""
		(layer "F.Cu")
		(at 26.035 -12.0142 -90)
		(property "Reference" "C15"
			(at 0 0 270)
			(layer "F.SilkS")
			(hide yes)
			(effects
				(font
					(size 1.27 1.27)
				)
			)
		)
		(property "Value" "SCD1U25V3KX-GP"
			(at 0 -2.8194 270)
			(unlocked yes)
			(layer "F.Fab")
			(hide yes)
			(effects
				(font
					(size 1.016 1.016)
					(thickness 0.1524)
				)
			)
		)
		(property "Device Type" "C603H36"
			(at 0 -4.3434 270)
			(unlocked yes)
			(layer "F.Fab")
			(hide yes)
			(effects
				(font
					(size 1.016 1.016)
					(thickness 0.1524)
				)
			)
		)
		(duplicate_pad_numbers_are_jumpers no)
		(fp_line
			(start 0.508 0)
			(end -0.508 0)
			(stroke
				(width 0.2032)
				(type default)
			)
			(layer "F.SilkS")
		)
		(fp_rect
			(start -0.5842 1.3335)
			(end 0.5842 -1.3335)
			(stroke
				(width 0)
				(type default)
			)
			(fill no)
			(layer "F.CrtYd")
		)
		(fp_rect
			(start -0.5842 1.3335)
			(end 0.5842 -1.3335)
			(stroke
				(width 0)
				(type default)
			)
			(fill no)
			(layer "F.Fab")
		)
		(pad "1" smd custom
			(at 0 -0.762 270)
			(size 0.2159 0.2159)
			(layers "F.Cu" "F.Mask" "F.Paste")
			(net "P12V_SLOT2")
			(options
				(clearance outline)
				(anchor circle)
			)
			(primitives
				(gr_poly
					(pts
						(arc
							(start -0.3302 -0.4318)
							(mid -0.402042 -0.402042)
							(end -0.4318 -0.3302)
						)
						(arc
							(start -0.4318 0.3302)
							(mid -0.402042 0.402042)
							(end -0.3302 0.4318)
						)
						(arc
							(start 0.3302 0.4318)
							(mid 0.402042 0.402042)
							(end 0.4318 0.3302)
						)
						(arc
							(start 0.4318 -0.3302)
							(mid 0.402042 -0.402042)
							(end 0.3302 -0.4318)
						)
					)
					(width 0)
					(fill yes)
				)
			)
		)
		(pad "2" smd custom
			(at 0 0.762 270)
			(size 0.2159 0.2159)
			(layers "F.Cu" "F.Mask" "F.Paste")
			(net "GND")
			(options
				(clearance outline)
				(anchor circle)
			)
			(primitives
				(gr_poly
					(pts
						(arc
							(start -0.3302 -0.4318)
							(mid -0.402042 -0.402042)
							(end -0.4318 -0.3302)
						)
						(arc
							(start -0.4318 0.3302)
							(mid -0.402042 0.402042)
							(end -0.3302 0.4318)
						)
						(arc
							(start 0.3302 0.4318)
							(mid 0.402042 0.402042)
							(end 0.4318 0.3302)
						)
						(arc
							(start 0.4318 -0.3302)
							(mid 0.402042 -0.402042)
							(end 0.3302 -0.4318)
						)
					)
					(width 0)
					(fill yes)
				)
			)
		)
	)
	(footprint ""
		(layer "F.Cu")
		(at 131.7244 -12.5476 90)
		(property "Reference" "R125"
			(at 0 0 90)
			(layer "F.SilkS")
			(hide yes)
			(effects
				(font
					(size 1.27 1.27)
				)
			)
		)
		(property "Value" "10KR2F-2-GP"
			(at 0.064008 -3.993896 90)
			(unlocked yes)
			(layer "F.Fab")
			(hide yes)
			(effects
				(font
					(size 1.016 1.016)
					(thickness 0.1524)
				)
			)
		)
		(property "Device Type" "R402H16"
			(at 0.064008 -5.517896 90)
			(unlocked yes)
			(layer "F.Fab")
			(hide yes)
			(effects
				(font
					(size 1.016 1.016)
					(thickness 0.1524)
				)
			)
		)
		(duplicate_pad_numbers_are_jumpers no)
		(fp_line
			(start 0.508 -0.9398)
			(end -0.508 -0.9398)
			(stroke
				(width 0.1524)
				(type default)
			)
			(layer "F.SilkS")
		)
		(fp_line
			(start -0.508 -0.9398)
			(end -0.508 0.9398)
			(stroke
				(width 0.1524)
				(type default)
			)
			(layer "F.SilkS")
		)
		(fp_rect
			(start -0.508 0.9398)
			(end 0.508 -0.9398)
			(stroke
				(width 0)
				(type default)
			)
			(fill no)
			(layer "F.CrtYd")
		)
		(fp_rect
			(start -0.508 0.9398)
			(end 0.508 -0.9398)
			(stroke
				(width 0)
				(type default)
			)
			(fill no)
			(layer "F.Fab")
		)
		(pad "1" smd custom
			(at 0 -0.4445 90)
			(size 0.1397 0.1397)
			(layers "F.Cu" "F.Mask" "F.Paste")
			(net "GPIO_B_IO1_4")
			(options
				(clearance outline)
				(anchor circle)
			)
			(primitives
				(gr_poly
					(pts
						(arc
							(start -0.1778 -0.2794)
							(mid -0.249642 -0.249642)
							(end -0.2794 -0.1778)
						)
						(arc
							(start -0.2794 0.1778)
							(mid -0.249642 0.249642)
							(end -0.1778 0.2794)
						)
						(arc
							(start 0.1778 0.2794)
							(mid 0.249642 0.249642)
							(end 0.2794 0.1778)
						)
						(arc
							(start 0.2794 -0.1778)
							(mid 0.249642 -0.249642)
							(end 0.1778 -0.2794)
						)
					)
					(width 0)
					(fill yes)
				)
			)
		)
		(pad "2" smd custom
			(at 0 0.4445 90)
			(size 0.1397 0.1397)
			(layers "F.Cu" "F.Mask" "F.Paste")
			(net "GND")
			(options
				(clearance outline)
				(anchor circle)
			)
			(primitives
				(gr_poly
					(pts
						(arc
							(start -0.1778 -0.2794)
							(mid -0.249642 -0.249642)
							(end -0.2794 -0.1778)
						)
						(arc
							(start -0.2794 0.1778)
							(mid -0.249642 0.249642)
							(end -0.1778 0.2794)
						)
						(arc
							(start 0.1778 0.2794)
							(mid 0.249642 0.249642)
							(end 0.2794 0.1778)
						)
						(arc
							(start 0.2794 -0.1778)
							(mid 0.249642 -0.249642)
							(end 0.1778 -0.2794)
						)
					)
					(width 0)
					(fill yes)
				)
			)
		)
	)
	(footprint ""
		(layer "F.Cu")
		(at 15.145512 -17.724882 -135)
		(property "Reference" "R83"
			(at 0 0 225)
			(layer "F.SilkS")
			(hide yes)
			(effects
				(font
					(size 1.27 1.27)
				)
			)
		)
		(property "Value" "D001R6F-L-GP"
			(at -0.126981 -3.733736 225)
			(unlocked yes)
			(layer "F.Fab")
			(hide yes)
			(effects
				(font
					(size 1.016 1.016)
					(thickness 0.1524)
				)
			)
		)
		(property "Device Type" "R1206H36"
			(at -0.12716 -5.257685 225)
			(unlocked yes)
			(layer "F.Fab")
			(hide yes)
			(effects
				(font
					(size 1.016 1.016)
					(thickness 0.1524)
				)
			)
		)
		(duplicate_pad_numbers_are_jumpers no)
		(fp_line
			(start 1.016026 2.235186)
			(end -1.016026 2.235186)
			(stroke
				(width 0.1524)
				(type default)
			)
			(layer "F.SilkS")
		)
		(fp_line
			(start -1.016026 2.235186)
			(end -1.016026 -2.235186)
			(stroke
				(width 0.1524)
				(type default)
			)
			(layer "F.SilkS")
		)
		(fp_line
			(start 1.016026 -2.235186)
			(end 1.016026 2.235186)
			(stroke
				(width 0.1524)
				(type default)
			)
			(layer "F.SilkS")
		)
		(fp_line
			(start -1.016026 -2.235186)
			(end 1.016026 -2.235186)
			(stroke
				(width 0.1524)
				(type default)
			)
			(layer "F.SilkS")
		)
		(fp_poly
			(pts
				(xy -0.800141 -1.599939) (xy 0.80006 -1.599939) (xy 0.800059 1.600461) (xy -0.800141 1.600461)
			)
			(stroke
				(width 0)
				(type default)
			)
			(fill no)
			(layer "F.CrtYd")
		)
		(fp_poly
			(pts
				(xy -1.092358 2.311518) (xy -1.092179 -2.311338) (xy 1.092179 -2.311338) (xy 1.092179 1.58753) (xy 0.800141 1.58753)
				(xy 0.800141 -1.600102) (xy -0.800141 -1.600102) (xy -0.800141 1.600461) (xy 1.092179 1.600461)
				(xy 1.092358 2.311518)
			)
			(stroke
				(width 0)
				(type default)
			)
			(fill no)
			(layer "F.CrtYd")
		)
		(fp_poly
			(pts
				(xy -1.092358 -2.311282) (xy 1.092042 -2.311282) (xy 1.092042 2.311518) (xy -1.092358 2.311518)
			)
			(stroke
				(width 0)
				(type default)
			)
			(fill no)
			(layer "F.Fab")
		)
		(pad "1" smd rect
			(at 0 -1.397 225)
			(size 1.651 1.27)
			(layers "F.Cu" "F.Mask" "F.Paste")
			(net "P12V")
		)
		(pad "2" smd rect
			(at 0 1.397 225)
			(size 1.651 1.27)
			(layers "F.Cu" "F.Mask" "F.Paste")
			(net "P12V_SLOT2")
		)
	)
	(footprint ""
		(layer "F.Cu")
		(at 21.5138 -15.748)
		(property "Reference" "R84"
			(at 0 0 0)
			(layer "F.SilkS")
			(hide yes)
			(effects
				(font
					(size 1.27 1.27)
				)
			)
		)
		(property "Value" "10KR2F-2-GP"
			(at 0.064008 -3.993896 0)
			(unlocked yes)
			(layer "F.Fab")
			(hide yes)
			(effects
				(font
					(size 1.016 1.016)
					(thickness 0.1524)
				)
			)
		)
		(property "Device Type" "R402H16"
			(at 0.064008 -5.517896 0)
			(unlocked yes)
			(layer "F.Fab")
			(hide yes)
			(effects
				(font
					(size 1.016 1.016)
					(thickness 0.1524)
				)
			)
		)
		(duplicate_pad_numbers_are_jumpers no)
		(fp_line
			(start -0.508 -0.9398)
			(end -0.508 0.9398)
			(stroke
				(width 0.1524)
				(type default)
			)
			(layer "F.SilkS")
		)
		(fp_line
			(start 0.508 -0.9398)
			(end -0.508 -0.9398)
			(stroke
				(width 0.1524)
				(type default)
			)
			(layer "F.SilkS")
		)
		(fp_rect
			(start -0.508 0.9398)
			(end 0.508 -0.9398)
			(stroke
				(width 0)
				(type default)
			)
			(fill no)
			(layer "F.CrtYd")
		)
		(fp_rect
			(start -0.508 0.9398)
			(end 0.508 -0.9398)
			(stroke
				(width 0)
				(type default)
			)
			(fill no)
			(layer "F.Fab")
		)
		(pad "1" smd custom
			(at 0 -0.4445)
			(size 0.1397 0.1397)
			(layers "F.Cu" "F.Mask" "F.Paste")
			(net "SLOT2_VMONITOR_A0")
			(options
				(clearance outline)
				(anchor circle)
			)
			(primitives
				(gr_poly
					(pts
						(arc
							(start -0.1778 -0.2794)
							(mid -0.249642 -0.249642)
							(end -0.2794 -0.1778)
						)
						(arc
							(start -0.2794 0.1778)
							(mid -0.249642 0.249642)
							(end -0.1778 0.2794)
						)
						(arc
							(start 0.1778 0.2794)
							(mid 0.249642 0.249642)
							(end 0.2794 0.1778)
						)
						(arc
							(start 0.2794 -0.1778)
							(mid 0.249642 -0.249642)
							(end 0.1778 -0.2794)
						)
					)
					(width 0)
					(fill yes)
				)
			)
		)
		(pad "2" smd custom
			(at 0 0.4445)
			(size 0.1397 0.1397)
			(layers "F.Cu" "F.Mask" "F.Paste")
			(net "GND")
			(options
				(clearance outline)
				(anchor circle)
			)
			(primitives
				(gr_poly
					(pts
						(arc
							(start -0.1778 -0.2794)
							(mid -0.249642 -0.249642)
							(end -0.2794 -0.1778)
						)
						(arc
							(start -0.2794 0.1778)
							(mid -0.249642 0.249642)
							(end -0.1778 0.2794)
						)
						(arc
							(start 0.1778 0.2794)
							(mid 0.249642 0.249642)
							(end 0.2794 0.1778)
						)
						(arc
							(start 0.2794 -0.1778)
							(mid 0.249642 -0.249642)
							(end 0.1778 -0.2794)
						)
					)
					(width 0)
					(fill yes)
				)
			)
		)
	)
	(footprint ""
		(layer "F.Cu")
		(at 88.138 -23.9014)
		(property "Reference" "R74"
			(at 0 0 0)
			(layer "F.SilkS")
			(hide yes)
			(effects
				(font
					(size 1.27 1.27)
				)
			)
		)
		(property "Value" "4K7R2F-GP"
			(at 0.064008 -3.993896 0)
			(unlocked yes)
			(layer "F.Fab")
			(hide yes)
			(effects
				(font
					(size 1.016 1.016)
					(thickness 0.1524)
				)
			)
		)
		(property "Device Type" "R402H16"
			(at 0.064008 -5.517896 0)
			(unlocked yes)
			(layer "F.Fab")
			(hide yes)
			(effects
				(font
					(size 1.016 1.016)
					(thickness 0.1524)
				)
			)
		)
		(duplicate_pad_numbers_are_jumpers no)
		(fp_line
			(start -0.508 -0.9398)
			(end -0.508 0.9398)
			(stroke
				(width 0.1524)
				(type default)
			)
			(layer "F.SilkS")
		)
		(fp_line
			(start 0.508 -0.9398)
			(end -0.508 -0.9398)
			(stroke
				(width 0.1524)
				(type default)
			)
			(layer "F.SilkS")
		)
		(fp_rect
			(start -0.508 0.9398)
			(end 0.508 -0.9398)
			(stroke
				(width 0)
				(type default)
			)
			(fill no)
			(layer "F.CrtYd")
		)
		(fp_rect
			(start -0.508 0.9398)
			(end 0.508 -0.9398)
			(stroke
				(width 0)
				(type default)
			)
			(fill no)
			(layer "F.Fab")
		)
		(pad "1" smd custom
			(at 0 -0.4445)
			(size 0.1397 0.1397)
			(layers "F.Cu" "F.Mask" "F.Paste")
			(net "P3V3_STBY")
			(options
				(clearance outline)
				(anchor circle)
			)
			(primitives
				(gr_poly
					(pts
						(arc
							(start -0.1778 -0.2794)
							(mid -0.249642 -0.249642)
							(end -0.2794 -0.1778)
						)
						(arc
							(start -0.2794 0.1778)
							(mid -0.249642 0.249642)
							(end -0.1778 0.2794)
						)
						(arc
							(start 0.1778 0.2794)
							(mid 0.249642 0.249642)
							(end 0.2794 0.1778)
						)
						(arc
							(start 0.2794 -0.1778)
							(mid 0.249642 -0.249642)
							(end 0.1778 -0.2794)
						)
					)
					(width 0)
					(fill yes)
				)
			)
		)
		(pad "2" smd custom
			(at 0 0.4445)
			(size 0.1397 0.1397)
			(layers "F.Cu" "F.Mask" "F.Paste")
			(net "RESET_O_1")
			(options
				(clearance outline)
				(anchor circle)
			)
			(primitives
				(gr_poly
					(pts
						(arc
							(start -0.1778 -0.2794)
							(mid -0.249642 -0.249642)
							(end -0.2794 -0.1778)
						)
						(arc
							(start -0.2794 0.1778)
							(mid -0.249642 0.249642)
							(end -0.1778 0.2794)
						)
						(arc
							(start 0.1778 0.2794)
							(mid 0.249642 0.249642)
							(end 0.2794 0.1778)
						)
						(arc
							(start 0.2794 -0.1778)
							(mid 0.249642 -0.249642)
							(end 0.1778 -0.2794)
						)
					)
					(width 0)
					(fill yes)
				)
			)
		)
	)
	(footprint ""
		(layer "F.Cu")
		(at 129.2098 -10.7696 180)
		(property "Reference" "R118"
			(at 0 0 180)
			(layer "F.SilkS")
			(hide yes)
			(effects
				(font
					(size 1.27 1.27)
				)
			)
		)
		(property "Value" "10KR2F-2-GP"
			(at 0.064008 -3.993896 180)
			(unlocked yes)
			(layer "F.Fab")
			(hide yes)
			(effects
				(font
					(size 1.016 1.016)
					(thickness 0.1524)
				)
			)
		)
		(property "Device Type" "R402H16"
			(at 0.064008 -5.517896 180)
			(unlocked yes)
			(layer "F.Fab")
			(hide yes)
			(effects
				(font
					(size 1.016 1.016)
					(thickness 0.1524)
				)
			)
		)
		(duplicate_pad_numbers_are_jumpers no)
		(fp_line
			(start 0.508 -0.9398)
			(end -0.508 -0.9398)
			(stroke
				(width 0.1524)
				(type default)
			)
			(layer "F.SilkS")
		)
		(fp_line
			(start -0.508 -0.9398)
			(end -0.508 0.9398)
			(stroke
				(width 0.1524)
				(type default)
			)
			(layer "F.SilkS")
		)
		(fp_rect
			(start -0.508 0.9398)
			(end 0.508 -0.9398)
			(stroke
				(width 0)
				(type default)
			)
			(fill no)
			(layer "F.CrtYd")
		)
		(fp_rect
			(start -0.508 0.9398)
			(end 0.508 -0.9398)
			(stroke
				(width 0)
				(type default)
			)
			(fill no)
			(layer "F.Fab")
		)
		(pad "1" smd custom
			(at 0 -0.4445 180)
			(size 0.1397 0.1397)
			(layers "F.Cu" "F.Mask" "F.Paste")
			(net "P3V3_STBY")
			(options
				(clearance outline)
				(anchor circle)
			)
			(primitives
				(gr_poly
					(pts
						(arc
							(start -0.1778 -0.2794)
							(mid -0.249642 -0.249642)
							(end -0.2794 -0.1778)
						)
						(arc
							(start -0.2794 0.1778)
							(mid -0.249642 0.249642)
							(end -0.1778 0.2794)
						)
						(arc
							(start 0.1778 0.2794)
							(mid 0.249642 0.249642)
							(end 0.2794 0.1778)
						)
						(arc
							(start 0.2794 -0.1778)
							(mid 0.249642 -0.249642)
							(end 0.1778 -0.2794)
						)
					)
					(width 0)
					(fill yes)
				)
			)
		)
		(pad "2" smd custom
			(at 0 0.4445 180)
			(size 0.1397 0.1397)
			(layers "F.Cu" "F.Mask" "F.Paste")
			(net "GPIO_B_IO1_0")
			(options
				(clearance outline)
				(anchor circle)
			)
			(primitives
				(gr_poly
					(pts
						(arc
							(start -0.1778 -0.2794)
							(mid -0.249642 -0.249642)
							(end -0.2794 -0.1778)
						)
						(arc
							(start -0.2794 0.1778)
							(mid -0.249642 0.249642)
							(end -0.1778 0.2794)
						)
						(arc
							(start 0.1778 0.2794)
							(mid 0.249642 0.249642)
							(end 0.2794 0.1778)
						)
						(arc
							(start 0.2794 -0.1778)
							(mid 0.249642 -0.249642)
							(end 0.1778 -0.2794)
						)
					)
					(width 0)
					(fill yes)
				)
			)
		)
	)
	(footprint ""
		(layer "F.Cu")
		(at 30.21584 -24.06142 180)
		(property "Reference" "R34"
			(at 0 0 180)
			(layer "F.SilkS")
			(hide yes)
			(effects
				(font
					(size 1.27 1.27)
				)
			)
		)
		(property "Value" "0R2F-1-GP"
			(at 0.064008 -3.993896 180)
			(unlocked yes)
			(layer "F.Fab")
			(hide yes)
			(effects
				(font
					(size 1.016 1.016)
					(thickness 0.1524)
				)
			)
		)
		(property "Device Type" "R402H16"
			(at 0.064008 -5.517896 180)
			(unlocked yes)
			(layer "F.Fab")
			(hide yes)
			(effects
				(font
					(size 1.016 1.016)
					(thickness 0.1524)
				)
			)
		)
		(duplicate_pad_numbers_are_jumpers no)
		(fp_line
			(start 0.508 -0.9398)
			(end -0.508 -0.9398)
			(stroke
				(width 0.1524)
				(type default)
			)
			(layer "F.SilkS")
		)
		(fp_line
			(start -0.508 -0.9398)
			(end -0.508 0.9398)
			(stroke
				(width 0.1524)
				(type default)
			)
			(layer "F.SilkS")
		)
		(fp_rect
			(start -0.508 0.9398)
			(end 0.508 -0.9398)
			(stroke
				(width 0)
				(type default)
			)
			(fill no)
			(layer "F.CrtYd")
		)
		(fp_rect
			(start -0.508 0.9398)
			(end 0.508 -0.9398)
			(stroke
				(width 0)
				(type default)
			)
			(fill no)
			(layer "F.Fab")
		)
		(pad "1" smd custom
			(at 0 -0.4445 180)
			(size 0.1397 0.1397)
			(layers "F.Cu" "F.Mask" "F.Paste")
			(net "SMCLK_BMC_SLOT3")
			(options
				(clearance outline)
				(anchor circle)
			)
			(primitives
				(gr_poly
					(pts
						(arc
							(start -0.1778 -0.2794)
							(mid -0.249642 -0.249642)
							(end -0.2794 -0.1778)
						)
						(arc
							(start -0.2794 0.1778)
							(mid -0.249642 0.249642)
							(end -0.1778 0.2794)
						)
						(arc
							(start 0.1778 0.2794)
							(mid 0.249642 0.249642)
							(end 0.2794 0.1778)
						)
						(arc
							(start 0.2794 -0.1778)
							(mid 0.249642 -0.249642)
							(end 0.1778 -0.2794)
						)
					)
					(width 0)
					(fill yes)
				)
			)
		)
		(pad "2" smd custom
			(at 0 0.4445 180)
			(size 0.1397 0.1397)
			(layers "F.Cu" "F.Mask" "F.Paste")
			(net "SMCLK_BMC_SLOT3_R")
			(options
				(clearance outline)
				(anchor circle)
			)
			(primitives
				(gr_poly
					(pts
						(arc
							(start -0.1778 -0.2794)
							(mid -0.249642 -0.249642)
							(end -0.2794 -0.1778)
						)
						(arc
							(start -0.2794 0.1778)
							(mid -0.249642 0.249642)
							(end -0.1778 0.2794)
						)
						(arc
							(start 0.1778 0.2794)
							(mid 0.249642 0.249642)
							(end 0.2794 0.1778)
						)
						(arc
							(start 0.2794 -0.1778)
							(mid 0.249642 -0.249642)
							(end 0.1778 -0.2794)
						)
					)
					(width 0)
					(fill yes)
				)
			)
		)
	)
	(footprint ""
		(layer "F.Cu")
		(at 37.9222 -23.6728 -90)
		(property "Reference" "C20"
			(at 0 0 270)
			(layer "F.SilkS")
			(hide yes)
			(effects
				(font
					(size 1.27 1.27)
				)
			)
		)
		(property "Value" "SC10U6D3V3MX-7-GP-U"
			(at 0 -2.8194 270)
			(unlocked yes)
			(layer "F.Fab")
			(hide yes)
			(effects
				(font
					(size 1.016 1.016)
					(thickness 0.1524)
				)
			)
		)
		(property "Device Type" "C603H40"
			(at 0 -4.3434 270)
			(unlocked yes)
			(layer "F.Fab")
			(hide yes)
			(effects
				(font
					(size 1.016 1.016)
					(thickness 0.1524)
				)
			)
		)
		(duplicate_pad_numbers_are_jumpers no)
		(fp_line
			(start 0.508 0)
			(end -0.508 0)
			(stroke
				(width 0.2032)
				(type default)
			)
			(layer "F.SilkS")
		)
		(fp_rect
			(start -0.5842 1.3335)
			(end 0.5842 -1.3335)
			(stroke
				(width 0)
				(type default)
			)
			(fill no)
			(layer "F.CrtYd")
		)
		(fp_rect
			(start -0.5842 1.3335)
			(end 0.5842 -1.3335)
			(stroke
				(width 0)
				(type default)
			)
			(fill no)
			(layer "F.Fab")
		)
		(pad "1" smd custom
			(at 0 -0.762 270)
			(size 0.2159 0.2159)
			(layers "F.Cu" "F.Mask" "F.Paste")
			(net "P3V3_STBY")
			(options
				(clearance outline)
				(anchor circle)
			)
			(primitives
				(gr_poly
					(pts
						(arc
							(start -0.3302 -0.4318)
							(mid -0.402042 -0.402042)
							(end -0.4318 -0.3302)
						)
						(arc
							(start -0.4318 0.3302)
							(mid -0.402042 0.402042)
							(end -0.3302 0.4318)
						)
						(arc
							(start 0.3302 0.4318)
							(mid 0.402042 0.402042)
							(end 0.4318 0.3302)
						)
						(arc
							(start 0.4318 -0.3302)
							(mid 0.402042 -0.402042)
							(end 0.3302 -0.4318)
						)
					)
					(width 0)
					(fill yes)
				)
			)
		)
		(pad "2" smd custom
			(at 0 0.762 270)
			(size 0.2159 0.2159)
			(layers "F.Cu" "F.Mask" "F.Paste")
			(net "GND")
			(options
				(clearance outline)
				(anchor circle)
			)
			(primitives
				(gr_poly
					(pts
						(arc
							(start -0.3302 -0.4318)
							(mid -0.402042 -0.402042)
							(end -0.4318 -0.3302)
						)
						(arc
							(start -0.4318 0.3302)
							(mid -0.402042 0.402042)
							(end -0.3302 0.4318)
						)
						(arc
							(start 0.3302 0.4318)
							(mid 0.402042 0.402042)
							(end 0.4318 0.3302)
						)
						(arc
							(start 0.4318 -0.3302)
							(mid 0.402042 -0.402042)
							(end 0.3302 -0.4318)
						)
					)
					(width 0)
					(fill yes)
				)
			)
		)
	)
	(footprint ""
		(layer "F.Cu")
		(at 119.5324 -15.5956 90)
		(property "Reference" "R108"
			(at 0 0 90)
			(layer "F.SilkS")
			(hide yes)
			(effects
				(font
					(size 1.27 1.27)
				)
			)
		)
		(property "Value" "4K7R2F-GP"
			(at 0.064008 -3.993896 90)
			(unlocked yes)
			(layer "F.Fab")
			(hide yes)
			(effects
				(font
					(size 1.016 1.016)
					(thickness 0.1524)
				)
			)
		)
		(property "Device Type" "R402H16"
			(at 0.064008 -5.517896 90)
			(unlocked yes)
			(layer "F.Fab")
			(hide yes)
			(effects
				(font
					(size 1.016 1.016)
					(thickness 0.1524)
				)
			)
		)
		(duplicate_pad_numbers_are_jumpers no)
		(fp_line
			(start 0.508 -0.9398)
			(end -0.508 -0.9398)
			(stroke
				(width 0.1524)
				(type default)
			)
			(layer "F.SilkS")
		)
		(fp_line
			(start -0.508 -0.9398)
			(end -0.508 0.9398)
			(stroke
				(width 0.1524)
				(type default)
			)
			(layer "F.SilkS")
		)
		(fp_rect
			(start -0.508 0.9398)
			(end 0.508 -0.9398)
			(stroke
				(width 0)
				(type default)
			)
			(fill no)
			(layer "F.CrtYd")
		)
		(fp_rect
			(start -0.508 0.9398)
			(end 0.508 -0.9398)
			(stroke
				(width 0)
				(type default)
			)
			(fill no)
			(layer "F.Fab")
		)
		(pad "1" smd custom
			(at 0 -0.4445 90)
			(size 0.1397 0.1397)
			(layers "F.Cu" "F.Mask" "F.Paste")
			(net "P3V3_STBY")
			(options
				(clearance outline)
				(anchor circle)
			)
			(primitives
				(gr_poly
					(pts
						(arc
							(start -0.1778 -0.2794)
							(mid -0.249642 -0.249642)
							(end -0.2794 -0.1778)
						)
						(arc
							(start -0.2794 0.1778)
							(mid -0.249642 0.249642)
							(end -0.1778 0.2794)
						)
						(arc
							(start 0.1778 0.2794)
							(mid 0.249642 0.249642)
							(end 0.2794 0.1778)
						)
						(arc
							(start 0.2794 -0.1778)
							(mid 0.249642 -0.249642)
							(end 0.1778 -0.2794)
						)
					)
					(width 0)
					(fill yes)
				)
			)
		)
		(pad "2" smd custom
			(at 0 0.4445 90)
			(size 0.1397 0.1397)
			(layers "F.Cu" "F.Mask" "F.Paste")
			(net "PCIE_SLOT2_PRSNT2_4_N")
			(options
				(clearance outline)
				(anchor circle)
			)
			(primitives
				(gr_poly
					(pts
						(arc
							(start -0.1778 -0.2794)
							(mid -0.249642 -0.249642)
							(end -0.2794 -0.1778)
						)
						(arc
							(start -0.2794 0.1778)
							(mid -0.249642 0.249642)
							(end -0.1778 0.2794)
						)
						(arc
							(start 0.1778 0.2794)
							(mid 0.249642 0.249642)
							(end 0.2794 0.1778)
						)
						(arc
							(start 0.2794 -0.1778)
							(mid 0.249642 -0.249642)
							(end 0.1778 -0.2794)
						)
					)
					(width 0)
					(fill yes)
				)
			)
		)
	)
	(footprint ""
		(layer "F.Cu")
		(at 37.719 -24.7396 -90)
		(property "Reference" "C21"
			(at 0 0 270)
			(layer "F.SilkS")
			(hide yes)
			(effects
				(font
					(size 1.27 1.27)
				)
			)
		)
		(property "Value" "SCD1U16V2KX-3GP"
			(at 1.1811 -2.7051 270)
			(unlocked yes)
			(layer "F.Fab")
			(hide yes)
			(effects
				(font
					(size 1.016 1.016)
					(thickness 0.1524)
				)
			)
		)
		(property "Device Type" "C402H22"
			(at 1.1811 -4.2291 270)
			(unlocked yes)
			(layer "F.Fab")
			(hide yes)
			(effects
				(font
					(size 1.016 1.016)
					(thickness 0.1524)
				)
			)
		)
		(duplicate_pad_numbers_are_jumpers no)
		(fp_rect
			(start -0.4318 0.9525)
			(end 0.4318 -0.9525)
			(stroke
				(width 0)
				(type default)
			)
			(fill no)
			(layer "F.CrtYd")
		)
		(fp_rect
			(start -0.4318 0.9525)
			(end 0.4318 -0.9525)
			(stroke
				(width 0)
				(type default)
			)
			(fill no)
			(layer "F.Fab")
		)
		(pad "1" smd custom
			(at 0 -0.4445 270)
			(size 0.1524 0.1524)
			(layers "F.Cu" "F.Mask" "F.Paste")
			(net "P3V3_STBY")
			(options
				(clearance outline)
				(anchor circle)
			)
			(primitives
				(gr_poly
					(pts
						(arc
							(start 0.3048 -0.2032)
							(mid 0.275042 -0.275042)
							(end 0.2032 -0.3048)
						)
						(arc
							(start -0.2032 -0.3048)
							(mid -0.275042 -0.275042)
							(end -0.3048 -0.2032)
						)
						(arc
							(start -0.3048 0.2032)
							(mid -0.275042 0.275042)
							(end -0.2032 0.3048)
						)
						(arc
							(start 0.2032 0.3048)
							(mid 0.275042 0.275042)
							(end 0.3048 0.2032)
						)
					)
					(width 0)
					(fill yes)
				)
			)
		)
		(pad "2" smd custom
			(at 0 0.4445 270)
			(size 0.1524 0.1524)
			(layers "F.Cu" "F.Mask" "F.Paste")
			(net "GND")
			(options
				(clearance outline)
				(anchor circle)
			)
			(primitives
				(gr_poly
					(pts
						(arc
							(start 0.3048 -0.2032)
							(mid 0.275042 -0.275042)
							(end 0.2032 -0.3048)
						)
						(arc
							(start -0.2032 -0.3048)
							(mid -0.275042 -0.275042)
							(end -0.3048 -0.2032)
						)
						(arc
							(start -0.3048 0.2032)
							(mid -0.275042 0.275042)
							(end -0.2032 0.3048)
						)
						(arc
							(start 0.2032 0.3048)
							(mid 0.275042 0.275042)
							(end 0.3048 0.2032)
						)
					)
					(width 0)
					(fill yes)
				)
			)
		)
	)
	(footprint ""
		(layer "F.Cu")
		(at 17.6022 -32.0548 180)
		(property "Reference" "C25"
			(at 0 0 180)
			(layer "F.SilkS")
			(hide yes)
			(effects
				(font
					(size 1.27 1.27)
				)
			)
		)
		(property "Value" "SCD1U25V3KX-GP"
			(at 0 -2.8194 180)
			(unlocked yes)
			(layer "F.Fab")
			(hide yes)
			(effects
				(font
					(size 1.016 1.016)
					(thickness 0.1524)
				)
			)
		)
		(property "Device Type" "C603H36"
			(at 0 -4.3434 180)
			(unlocked yes)
			(layer "F.Fab")
			(hide yes)
			(effects
				(font
					(size 1.016 1.016)
					(thickness 0.1524)
				)
			)
		)
		(duplicate_pad_numbers_are_jumpers no)
		(fp_line
			(start 0.508 0)
			(end -0.508 0)
			(stroke
				(width 0.2032)
				(type default)
			)
			(layer "F.SilkS")
		)
		(fp_rect
			(start -0.5842 1.3335)
			(end 0.5842 -1.3335)
			(stroke
				(width 0)
				(type default)
			)
			(fill no)
			(layer "F.CrtYd")
		)
		(fp_rect
			(start -0.5842 1.3335)
			(end 0.5842 -1.3335)
			(stroke
				(width 0)
				(type default)
			)
			(fill no)
			(layer "F.Fab")
		)
		(pad "1" smd custom
			(at 0 -0.762 180)
			(size 0.2159 0.2159)
			(layers "F.Cu" "F.Mask" "F.Paste")
			(net "P12V_SLOT3")
			(options
				(clearance outline)
				(anchor circle)
			)
			(primitives
				(gr_poly
					(pts
						(arc
							(start -0.3302 -0.4318)
							(mid -0.402042 -0.402042)
							(end -0.4318 -0.3302)
						)
						(arc
							(start -0.4318 0.3302)
							(mid -0.402042 0.402042)
							(end -0.3302 0.4318)
						)
						(arc
							(start 0.3302 0.4318)
							(mid 0.402042 0.402042)
							(end 0.4318 0.3302)
						)
						(arc
							(start 0.4318 -0.3302)
							(mid 0.402042 -0.402042)
							(end 0.3302 -0.4318)
						)
					)
					(width 0)
					(fill yes)
				)
			)
		)
		(pad "2" smd custom
			(at 0 0.762 180)
			(size 0.2159 0.2159)
			(layers "F.Cu" "F.Mask" "F.Paste")
			(net "GND")
			(options
				(clearance outline)
				(anchor circle)
			)
			(primitives
				(gr_poly
					(pts
						(arc
							(start -0.3302 -0.4318)
							(mid -0.402042 -0.402042)
							(end -0.4318 -0.3302)
						)
						(arc
							(start -0.4318 0.3302)
							(mid -0.402042 0.402042)
							(end -0.3302 0.4318)
						)
						(arc
							(start 0.3302 0.4318)
							(mid 0.402042 0.402042)
							(end 0.4318 0.3302)
						)
						(arc
							(start 0.4318 -0.3302)
							(mid 0.402042 -0.402042)
							(end 0.3302 -0.4318)
						)
					)
					(width 0)
					(fill yes)
				)
			)
		)
	)
	(footprint ""
		(layer "F.Cu")
		(at 89.5858 -21.1074)
		(property "Reference" "R78"
			(at 0 0 0)
			(layer "F.SilkS")
			(hide yes)
			(effects
				(font
					(size 1.27 1.27)
				)
			)
		)
		(property "Value" "0R2F-1-GP"
			(at 0.064008 -3.993896 0)
			(unlocked yes)
			(layer "F.Fab")
			(hide yes)
			(effects
				(font
					(size 1.016 1.016)
					(thickness 0.1524)
				)
			)
		)
		(property "Device Type" "R402H16"
			(at 0.064008 -5.517896 0)
			(unlocked yes)
			(layer "F.Fab")
			(hide yes)
			(effects
				(font
					(size 1.016 1.016)
					(thickness 0.1524)
				)
			)
		)
		(duplicate_pad_numbers_are_jumpers no)
		(fp_line
			(start -0.508 -0.9398)
			(end -0.508 0.9398)
			(stroke
				(width 0.1524)
				(type default)
			)
			(layer "F.SilkS")
		)
		(fp_line
			(start 0.508 -0.9398)
			(end -0.508 -0.9398)
			(stroke
				(width 0.1524)
				(type default)
			)
			(layer "F.SilkS")
		)
		(fp_rect
			(start -0.508 0.9398)
			(end 0.508 -0.9398)
			(stroke
				(width 0)
				(type default)
			)
			(fill no)
			(layer "F.CrtYd")
		)
		(fp_rect
			(start -0.508 0.9398)
			(end 0.508 -0.9398)
			(stroke
				(width 0)
				(type default)
			)
			(fill no)
			(layer "F.Fab")
		)
		(pad "1" smd custom
			(at 0 -0.4445)
			(size 0.1397 0.1397)
			(layers "F.Cu" "F.Mask" "F.Paste")
			(net "PERST_N_1")
			(options
				(clearance outline)
				(anchor circle)
			)
			(primitives
				(gr_poly
					(pts
						(arc
							(start -0.1778 -0.2794)
							(mid -0.249642 -0.249642)
							(end -0.2794 -0.1778)
						)
						(arc
							(start -0.2794 0.1778)
							(mid -0.249642 0.249642)
							(end -0.1778 0.2794)
						)
						(arc
							(start 0.1778 0.2794)
							(mid 0.249642 0.249642)
							(end 0.2794 0.1778)
						)
						(arc
							(start 0.2794 -0.1778)
							(mid 0.249642 -0.249642)
							(end 0.1778 -0.2794)
						)
					)
					(width 0)
					(fill yes)
				)
			)
		)
		(pad "2" smd custom
			(at 0 0.4445)
			(size 0.1397 0.1397)
			(layers "F.Cu" "F.Mask" "F.Paste")
			(net "PERST_N_1_R")
			(options
				(clearance outline)
				(anchor circle)
			)
			(primitives
				(gr_poly
					(pts
						(arc
							(start -0.1778 -0.2794)
							(mid -0.249642 -0.249642)
							(end -0.2794 -0.1778)
						)
						(arc
							(start -0.2794 0.1778)
							(mid -0.249642 0.249642)
							(end -0.1778 0.2794)
						)
						(arc
							(start 0.1778 0.2794)
							(mid 0.249642 0.249642)
							(end 0.2794 0.1778)
						)
						(arc
							(start 0.2794 -0.1778)
							(mid 0.249642 -0.249642)
							(end 0.1778 -0.2794)
						)
					)
					(width 0)
					(fill yes)
				)
			)
		)
	)
	(footprint ""
		(layer "F.Cu")
		(at 131.6736 -18.8214 -90)
		(property "Reference" "R132"
			(at 0 0 270)
			(layer "F.SilkS")
			(hide yes)
			(effects
				(font
					(size 1.27 1.27)
				)
			)
		)
		(property "Value" "10KR2F-2-GP"
			(at 0.064008 -3.993896 270)
			(unlocked yes)
			(layer "F.Fab")
			(hide yes)
			(effects
				(font
					(size 1.016 1.016)
					(thickness 0.1524)
				)
			)
		)
		(property "Device Type" "R402H16"
			(at 0.064008 -5.517896 270)
			(unlocked yes)
			(layer "F.Fab")
			(hide yes)
			(effects
				(font
					(size 1.016 1.016)
					(thickness 0.1524)
				)
			)
		)
		(duplicate_pad_numbers_are_jumpers no)
		(fp_line
			(start -0.508 -0.9398)
			(end -0.508 0.9398)
			(stroke
				(width 0.1524)
				(type default)
			)
			(layer "F.SilkS")
		)
		(fp_line
			(start 0.508 -0.9398)
			(end -0.508 -0.9398)
			(stroke
				(width 0.1524)
				(type default)
			)
			(layer "F.SilkS")
		)
		(fp_rect
			(start -0.508 0.9398)
			(end 0.508 -0.9398)
			(stroke
				(width 0)
				(type default)
			)
			(fill no)
			(layer "F.CrtYd")
		)
		(fp_rect
			(start -0.508 0.9398)
			(end 0.508 -0.9398)
			(stroke
				(width 0)
				(type default)
			)
			(fill no)
			(layer "F.Fab")
		)
		(pad "1" smd custom
			(at 0 -0.4445 270)
			(size 0.1397 0.1397)
			(layers "F.Cu" "F.Mask" "F.Paste")
			(net "P3V3_STBY")
			(options
				(clearance outline)
				(anchor circle)
			)
			(primitives
				(gr_poly
					(pts
						(arc
							(start -0.1778 -0.2794)
							(mid -0.249642 -0.249642)
							(end -0.2794 -0.1778)
						)
						(arc
							(start -0.2794 0.1778)
							(mid -0.249642 0.249642)
							(end -0.1778 0.2794)
						)
						(arc
							(start 0.1778 0.2794)
							(mid 0.249642 0.249642)
							(end 0.2794 0.1778)
						)
						(arc
							(start 0.2794 -0.1778)
							(mid 0.249642 -0.249642)
							(end 0.1778 -0.2794)
						)
					)
					(width 0)
					(fill yes)
				)
			)
		)
		(pad "2" smd custom
			(at 0 0.4445 270)
			(size 0.1397 0.1397)
			(layers "F.Cu" "F.Mask" "F.Paste")
			(net "GPIO_B_IO1_7")
			(options
				(clearance outline)
				(anchor circle)
			)
			(primitives
				(gr_poly
					(pts
						(arc
							(start -0.1778 -0.2794)
							(mid -0.249642 -0.249642)
							(end -0.2794 -0.1778)
						)
						(arc
							(start -0.2794 0.1778)
							(mid -0.249642 0.249642)
							(end -0.1778 0.2794)
						)
						(arc
							(start 0.1778 0.2794)
							(mid 0.249642 0.249642)
							(end 0.2794 0.1778)
						)
						(arc
							(start 0.2794 -0.1778)
							(mid 0.249642 -0.249642)
							(end 0.1778 -0.2794)
						)
					)
					(width 0)
					(fill yes)
				)
			)
		)
	)
	(footprint ""
		(layer "F.Cu")
		(at 62.9666 -16.1798 90)
		(property "Reference" "R46"
			(at 0 0 90)
			(layer "F.SilkS")
			(hide yes)
			(effects
				(font
					(size 1.27 1.27)
				)
			)
		)
		(property "Value" "4K7R2F-GP"
			(at 0.064008 -3.993896 90)
			(unlocked yes)
			(layer "F.Fab")
			(hide yes)
			(effects
				(font
					(size 1.016 1.016)
					(thickness 0.1524)
				)
			)
		)
		(property "Device Type" "R402H16"
			(at 0.064008 -5.517896 90)
			(unlocked yes)
			(layer "F.Fab")
			(hide yes)
			(effects
				(font
					(size 1.016 1.016)
					(thickness 0.1524)
				)
			)
		)
		(duplicate_pad_numbers_are_jumpers no)
		(fp_line
			(start 0.508 -0.9398)
			(end -0.508 -0.9398)
			(stroke
				(width 0.1524)
				(type default)
			)
			(layer "F.SilkS")
		)
		(fp_line
			(start -0.508 -0.9398)
			(end -0.508 0.9398)
			(stroke
				(width 0.1524)
				(type default)
			)
			(layer "F.SilkS")
		)
		(fp_rect
			(start -0.508 0.9398)
			(end 0.508 -0.9398)
			(stroke
				(width 0)
				(type default)
			)
			(fill no)
			(layer "F.CrtYd")
		)
		(fp_rect
			(start -0.508 0.9398)
			(end 0.508 -0.9398)
			(stroke
				(width 0)
				(type default)
			)
			(fill no)
			(layer "F.Fab")
		)
		(pad "1" smd custom
			(at 0 -0.4445 90)
			(size 0.1397 0.1397)
			(layers "F.Cu" "F.Mask" "F.Paste")
			(net "P3V3_STBY")
			(options
				(clearance outline)
				(anchor circle)
			)
			(primitives
				(gr_poly
					(pts
						(arc
							(start -0.1778 -0.2794)
							(mid -0.249642 -0.249642)
							(end -0.2794 -0.1778)
						)
						(arc
							(start -0.2794 0.1778)
							(mid -0.249642 0.249642)
							(end -0.1778 0.2794)
						)
						(arc
							(start 0.1778 0.2794)
							(mid 0.249642 0.249642)
							(end 0.2794 0.1778)
						)
						(arc
							(start 0.2794 -0.1778)
							(mid 0.249642 -0.249642)
							(end 0.1778 -0.2794)
						)
					)
					(width 0)
					(fill yes)
				)
			)
		)
		(pad "2" smd custom
			(at 0 0.4445 90)
			(size 0.1397 0.1397)
			(layers "F.Cu" "F.Mask" "F.Paste")
			(net "PCIE_SLOT2_PRSNT2_2_N")
			(options
				(clearance outline)
				(anchor circle)
			)
			(primitives
				(gr_poly
					(pts
						(arc
							(start -0.1778 -0.2794)
							(mid -0.249642 -0.249642)
							(end -0.2794 -0.1778)
						)
						(arc
							(start -0.2794 0.1778)
							(mid -0.249642 0.249642)
							(end -0.1778 0.2794)
						)
						(arc
							(start 0.1778 0.2794)
							(mid 0.249642 0.249642)
							(end 0.2794 0.1778)
						)
						(arc
							(start 0.2794 -0.1778)
							(mid 0.249642 -0.249642)
							(end 0.1778 -0.2794)
						)
					)
					(width 0)
					(fill yes)
				)
			)
		)
	)
	(footprint ""
		(layer "F.Cu")
		(at 38.2397 1.9177 90)
		(property "Reference" "R167"
			(at 0 0 90)
			(layer "F.SilkS")
			(hide yes)
			(effects
				(font
					(size 1.27 1.27)
				)
			)
		)
		(property "Value" "4K7R2F-GP"
			(at 0.064008 -3.993896 90)
			(unlocked yes)
			(layer "F.Fab")
			(hide yes)
			(effects
				(font
					(size 1.016 1.016)
					(thickness 0.1524)
				)
			)
		)
		(property "Device Type" "R402H16"
			(at 0.064008 -5.517896 90)
			(unlocked yes)
			(layer "F.Fab")
			(hide yes)
			(effects
				(font
					(size 1.016 1.016)
					(thickness 0.1524)
				)
			)
		)
		(duplicate_pad_numbers_are_jumpers no)
		(fp_line
			(start 0.508 -0.9398)
			(end -0.508 -0.9398)
			(stroke
				(width 0.1524)
				(type default)
			)
			(layer "F.SilkS")
		)
		(fp_line
			(start -0.508 -0.9398)
			(end -0.508 0.9398)
			(stroke
				(width 0.1524)
				(type default)
			)
			(layer "F.SilkS")
		)
		(fp_rect
			(start -0.508 0.9398)
			(end 0.508 -0.9398)
			(stroke
				(width 0)
				(type default)
			)
			(fill no)
			(layer "F.CrtYd")
		)
		(fp_rect
			(start -0.508 0.9398)
			(end 0.508 -0.9398)
			(stroke
				(width 0)
				(type default)
			)
			(fill no)
			(layer "F.Fab")
		)
		(pad "1" smd custom
			(at 0 -0.4445 90)
			(size 0.1397 0.1397)
			(layers "F.Cu" "F.Mask" "F.Paste")
			(net "P3V3")
			(options
				(clearance outline)
				(anchor circle)
			)
			(primitives
				(gr_poly
					(pts
						(arc
							(start -0.1778 -0.2794)
							(mid -0.249642 -0.249642)
							(end -0.2794 -0.1778)
						)
						(arc
							(start -0.2794 0.1778)
							(mid -0.249642 0.249642)
							(end -0.1778 0.2794)
						)
						(arc
							(start 0.1778 0.2794)
							(mid 0.249642 0.249642)
							(end 0.2794 0.1778)
						)
						(arc
							(start 0.2794 -0.1778)
							(mid 0.249642 -0.249642)
							(end 0.1778 -0.2794)
						)
					)
					(width 0)
					(fill yes)
				)
			)
		)
		(pad "2" smd custom
			(at 0 0.4445 90)
			(size 0.1397 0.1397)
			(layers "F.Cu" "F.Mask" "F.Paste")
			(net "SMB_PCH_ALERT")
			(options
				(clearance outline)
				(anchor circle)
			)
			(primitives
				(gr_poly
					(pts
						(arc
							(start -0.1778 -0.2794)
							(mid -0.249642 -0.249642)
							(end -0.2794 -0.1778)
						)
						(arc
							(start -0.2794 0.1778)
							(mid -0.249642 0.249642)
							(end -0.1778 0.2794)
						)
						(arc
							(start 0.1778 0.2794)
							(mid 0.249642 0.249642)
							(end 0.2794 0.1778)
						)
						(arc
							(start 0.2794 -0.1778)
							(mid 0.249642 -0.249642)
							(end 0.1778 -0.2794)
						)
					)
					(width 0)
					(fill yes)
				)
			)
		)
	)
	(footprint ""
		(layer "F.Cu")
		(at 20.7772 -23.5204 180)
		(property "Reference" "C52"
			(at 0 0 180)
			(layer "F.SilkS")
			(hide yes)
			(effects
				(font
					(size 1.27 1.27)
				)
			)
		)
		(property "Value" "SCD1U16V2KX-3GP"
			(at 1.1811 -2.7051 180)
			(unlocked yes)
			(layer "F.Fab")
			(hide yes)
			(effects
				(font
					(size 1.016 1.016)
					(thickness 0.1524)
				)
			)
		)
		(property "Device Type" "C402H22"
			(at 1.1811 -4.2291 180)
			(unlocked yes)
			(layer "F.Fab")
			(hide yes)
			(effects
				(font
					(size 1.016 1.016)
					(thickness 0.1524)
				)
			)
		)
		(duplicate_pad_numbers_are_jumpers no)
		(fp_rect
			(start -0.4318 0.9525)
			(end 0.4318 -0.9525)
			(stroke
				(width 0)
				(type default)
			)
			(fill no)
			(layer "F.CrtYd")
		)
		(fp_rect
			(start -0.4318 0.9525)
			(end 0.4318 -0.9525)
			(stroke
				(width 0)
				(type default)
			)
			(fill no)
			(layer "F.Fab")
		)
		(pad "1" smd custom
			(at 0 -0.4445 180)
			(size 0.1524 0.1524)
			(layers "F.Cu" "F.Mask" "F.Paste")
			(net "P3V3_STBY")
			(options
				(clearance outline)
				(anchor circle)
			)
			(primitives
				(gr_poly
					(pts
						(arc
							(start 0.3048 -0.2032)
							(mid 0.275042 -0.275042)
							(end 0.2032 -0.3048)
						)
						(arc
							(start -0.2032 -0.3048)
							(mid -0.275042 -0.275042)
							(end -0.3048 -0.2032)
						)
						(arc
							(start -0.3048 0.2032)
							(mid -0.275042 0.275042)
							(end -0.2032 0.3048)
						)
						(arc
							(start 0.2032 0.3048)
							(mid 0.275042 0.275042)
							(end 0.3048 0.2032)
						)
					)
					(width 0)
					(fill yes)
				)
			)
		)
		(pad "2" smd custom
			(at 0 0.4445 180)
			(size 0.1524 0.1524)
			(layers "F.Cu" "F.Mask" "F.Paste")
			(net "GND")
			(options
				(clearance outline)
				(anchor circle)
			)
			(primitives
				(gr_poly
					(pts
						(arc
							(start 0.3048 -0.2032)
							(mid 0.275042 -0.275042)
							(end 0.2032 -0.3048)
						)
						(arc
							(start -0.2032 -0.3048)
							(mid -0.275042 -0.275042)
							(end -0.3048 -0.2032)
						)
						(arc
							(start -0.3048 0.2032)
							(mid -0.275042 0.275042)
							(end -0.2032 0.3048)
						)
						(arc
							(start 0.2032 0.3048)
							(mid 0.275042 0.275042)
							(end 0.3048 0.2032)
						)
					)
					(width 0)
					(fill yes)
				)
			)
		)
	)
	(footprint ""
		(layer "F.Cu")
		(at 114.6048 0.3048 180)
		(property "Reference" "R11"
			(at 0 0 180)
			(layer "F.SilkS")
			(hide yes)
			(effects
				(font
					(size 1.27 1.27)
				)
			)
		)
		(property "Value" "4K7R2F-GP"
			(at 0.064008 -3.993896 180)
			(unlocked yes)
			(layer "F.Fab")
			(hide yes)
			(effects
				(font
					(size 1.016 1.016)
					(thickness 0.1524)
				)
			)
		)
		(property "Device Type" "R402H16"
			(at 0.064008 -5.517896 180)
			(unlocked yes)
			(layer "F.Fab")
			(hide yes)
			(effects
				(font
					(size 1.016 1.016)
					(thickness 0.1524)
				)
			)
		)
		(duplicate_pad_numbers_are_jumpers no)
		(fp_line
			(start 0.508 -0.9398)
			(end -0.508 -0.9398)
			(stroke
				(width 0.1524)
				(type default)
			)
			(layer "F.SilkS")
		)
		(fp_line
			(start -0.508 -0.9398)
			(end -0.508 0.9398)
			(stroke
				(width 0.1524)
				(type default)
			)
			(layer "F.SilkS")
		)
		(fp_rect
			(start -0.508 0.9398)
			(end 0.508 -0.9398)
			(stroke
				(width 0)
				(type default)
			)
			(fill no)
			(layer "F.CrtYd")
		)
		(fp_rect
			(start -0.508 0.9398)
			(end 0.508 -0.9398)
			(stroke
				(width 0)
				(type default)
			)
			(fill no)
			(layer "F.Fab")
		)
		(pad "1" smd custom
			(at 0 -0.4445 180)
			(size 0.1397 0.1397)
			(layers "F.Cu" "F.Mask" "F.Paste")
			(net "P3V3_STBY")
			(options
				(clearance outline)
				(anchor circle)
			)
			(primitives
				(gr_poly
					(pts
						(arc
							(start -0.1778 -0.2794)
							(mid -0.249642 -0.249642)
							(end -0.2794 -0.1778)
						)
						(arc
							(start -0.2794 0.1778)
							(mid -0.249642 0.249642)
							(end -0.1778 0.2794)
						)
						(arc
							(start 0.1778 0.2794)
							(mid 0.249642 0.249642)
							(end 0.2794 0.1778)
						)
						(arc
							(start 0.2794 -0.1778)
							(mid 0.249642 -0.249642)
							(end 0.1778 -0.2794)
						)
					)
					(width 0)
					(fill yes)
				)
			)
		)
		(pad "2" smd custom
			(at 0 0.4445 180)
			(size 0.1397 0.1397)
			(layers "F.Cu" "F.Mask" "F.Paste")
			(net "PU_B_MUX_SCL2")
			(options
				(clearance outline)
				(anchor circle)
			)
			(primitives
				(gr_poly
					(pts
						(arc
							(start -0.1778 -0.2794)
							(mid -0.249642 -0.249642)
							(end -0.2794 -0.1778)
						)
						(arc
							(start -0.2794 0.1778)
							(mid -0.249642 0.249642)
							(end -0.1778 0.2794)
						)
						(arc
							(start 0.1778 0.2794)
							(mid 0.249642 0.249642)
							(end 0.2794 0.1778)
						)
						(arc
							(start 0.2794 -0.1778)
							(mid 0.249642 -0.249642)
							(end 0.1778 -0.2794)
						)
					)
					(width 0)
					(fill yes)
				)
			)
		)
	)
	(footprint ""
		(layer "F.Cu")
		(at 129.1082 0.4826 180)
		(property "Reference" "R68"
			(at 0 0 180)
			(layer "F.SilkS")
			(hide yes)
			(effects
				(font
					(size 1.27 1.27)
				)
			)
		)
		(property "Value" "0R2F-1-GP"
			(at 0.064008 -3.993896 180)
			(unlocked yes)
			(layer "F.Fab")
			(hide yes)
			(effects
				(font
					(size 1.016 1.016)
					(thickness 0.1524)
				)
			)
		)
		(property "Device Type" "R402H16"
			(at 0.064008 -5.517896 180)
			(unlocked yes)
			(layer "F.Fab")
			(hide yes)
			(effects
				(font
					(size 1.016 1.016)
					(thickness 0.1524)
				)
			)
		)
		(duplicate_pad_numbers_are_jumpers no)
		(fp_line
			(start 0.508 -0.9398)
			(end -0.508 -0.9398)
			(stroke
				(width 0.1524)
				(type default)
			)
			(layer "F.SilkS")
		)
		(fp_line
			(start -0.508 -0.9398)
			(end -0.508 0.9398)
			(stroke
				(width 0.1524)
				(type default)
			)
			(layer "F.SilkS")
		)
		(fp_rect
			(start -0.508 0.9398)
			(end 0.508 -0.9398)
			(stroke
				(width 0)
				(type default)
			)
			(fill no)
			(layer "F.CrtYd")
		)
		(fp_rect
			(start -0.508 0.9398)
			(end 0.508 -0.9398)
			(stroke
				(width 0)
				(type default)
			)
			(fill no)
			(layer "F.Fab")
		)
		(pad "1" smd custom
			(at 0 -0.4445 180)
			(size 0.1397 0.1397)
			(layers "F.Cu" "F.Mask" "F.Paste")
			(net "SMCLK_PCH_DEVICE")
			(options
				(clearance outline)
				(anchor circle)
			)
			(primitives
				(gr_poly
					(pts
						(arc
							(start -0.1778 -0.2794)
							(mid -0.249642 -0.249642)
							(end -0.2794 -0.1778)
						)
						(arc
							(start -0.2794 0.1778)
							(mid -0.249642 0.249642)
							(end -0.1778 0.2794)
						)
						(arc
							(start 0.1778 0.2794)
							(mid 0.249642 0.249642)
							(end 0.2794 0.1778)
						)
						(arc
							(start 0.2794 -0.1778)
							(mid 0.249642 -0.249642)
							(end 0.1778 -0.2794)
						)
					)
					(width 0)
					(fill yes)
				)
			)
		)
		(pad "2" smd custom
			(at 0 0.4445 180)
			(size 0.1397 0.1397)
			(layers "F.Cu" "F.Mask" "F.Paste")
			(net "SMCLK_EXP_R_PCH")
			(options
				(clearance outline)
				(anchor circle)
			)
			(primitives
				(gr_poly
					(pts
						(arc
							(start -0.1778 -0.2794)
							(mid -0.249642 -0.249642)
							(end -0.2794 -0.1778)
						)
						(arc
							(start -0.2794 0.1778)
							(mid -0.249642 0.249642)
							(end -0.1778 0.2794)
						)
						(arc
							(start 0.1778 0.2794)
							(mid 0.249642 0.249642)
							(end 0.2794 0.1778)
						)
						(arc
							(start 0.2794 -0.1778)
							(mid 0.249642 -0.249642)
							(end 0.1778 -0.2794)
						)
					)
					(width 0)
					(fill yes)
				)
			)
		)
	)
	(footprint ""
		(layer "F.Cu")
		(at 84.4804 -21.082)
		(property "Reference" "C37"
			(at 0 0 0)
			(layer "F.SilkS")
			(hide yes)
			(effects
				(font
					(size 1.27 1.27)
				)
			)
		)
		(property "Value" "SCD01U16V2KX-3GP"
			(at 1.1811 -2.7051 0)
			(unlocked yes)
			(layer "F.Fab")
			(hide yes)
			(effects
				(font
					(size 1.016 1.016)
					(thickness 0.1524)
				)
			)
		)
		(property "Device Type" "C402H22"
			(at 1.1811 -4.2291 0)
			(unlocked yes)
			(layer "F.Fab")
			(hide yes)
			(effects
				(font
					(size 1.016 1.016)
					(thickness 0.1524)
				)
			)
		)
		(duplicate_pad_numbers_are_jumpers no)
		(fp_rect
			(start -0.4318 0.9525)
			(end 0.4318 -0.9525)
			(stroke
				(width 0)
				(type default)
			)
			(fill no)
			(layer "F.CrtYd")
		)
		(fp_rect
			(start -0.4318 0.9525)
			(end 0.4318 -0.9525)
			(stroke
				(width 0)
				(type default)
			)
			(fill no)
			(layer "F.Fab")
		)
		(pad "1" smd custom
			(at 0 -0.4445)
			(size 0.1524 0.1524)
			(layers "F.Cu" "F.Mask" "F.Paste")
			(net "RESET_IN")
			(options
				(clearance outline)
				(anchor circle)
			)
			(primitives
				(gr_poly
					(pts
						(arc
							(start 0.3048 -0.2032)
							(mid 0.275042 -0.275042)
							(end 0.2032 -0.3048)
						)
						(arc
							(start -0.2032 -0.3048)
							(mid -0.275042 -0.275042)
							(end -0.3048 -0.2032)
						)
						(arc
							(start -0.3048 0.2032)
							(mid -0.275042 0.275042)
							(end -0.2032 0.3048)
						)
						(arc
							(start 0.2032 0.3048)
							(mid 0.275042 0.275042)
							(end 0.3048 0.2032)
						)
					)
					(width 0)
					(fill yes)
				)
			)
		)
		(pad "2" smd custom
			(at 0 0.4445)
			(size 0.1524 0.1524)
			(layers "F.Cu" "F.Mask" "F.Paste")
			(net "GND")
			(options
				(clearance outline)
				(anchor circle)
			)
			(primitives
				(gr_poly
					(pts
						(arc
							(start 0.3048 -0.2032)
							(mid 0.275042 -0.275042)
							(end 0.2032 -0.3048)
						)
						(arc
							(start -0.2032 -0.3048)
							(mid -0.275042 -0.275042)
							(end -0.3048 -0.2032)
						)
						(arc
							(start -0.3048 0.2032)
							(mid -0.275042 0.275042)
							(end -0.2032 0.3048)
						)
						(arc
							(start 0.2032 0.3048)
							(mid 0.275042 0.275042)
							(end 0.3048 0.2032)
						)
					)
					(width 0)
					(fill yes)
				)
			)
		)
	)
	(footprint ""
		(layer "F.Cu")
		(at 105.3084 2.7686)
		(property "Reference" "R15"
			(at 0 0 0)
			(layer "F.SilkS")
			(hide yes)
			(effects
				(font
					(size 1.27 1.27)
				)
			)
		)
		(property "Value" "10KR2F-2-GP"
			(at 0.064008 -3.993896 0)
			(unlocked yes)
			(layer "F.Fab")
			(hide yes)
			(effects
				(font
					(size 1.016 1.016)
					(thickness 0.1524)
				)
			)
		)
		(property "Device Type" "R402H16"
			(at 0.064008 -5.517896 0)
			(unlocked yes)
			(layer "F.Fab")
			(hide yes)
			(effects
				(font
					(size 1.016 1.016)
					(thickness 0.1524)
				)
			)
		)
		(duplicate_pad_numbers_are_jumpers no)
		(fp_line
			(start -0.508 -0.9398)
			(end -0.508 0.9398)
			(stroke
				(width 0.1524)
				(type default)
			)
			(layer "F.SilkS")
		)
		(fp_line
			(start 0.508 -0.9398)
			(end -0.508 -0.9398)
			(stroke
				(width 0.1524)
				(type default)
			)
			(layer "F.SilkS")
		)
		(fp_rect
			(start -0.508 0.9398)
			(end 0.508 -0.9398)
			(stroke
				(width 0)
				(type default)
			)
			(fill no)
			(layer "F.CrtYd")
		)
		(fp_rect
			(start -0.508 0.9398)
			(end 0.508 -0.9398)
			(stroke
				(width 0)
				(type default)
			)
			(fill no)
			(layer "F.Fab")
		)
		(pad "1" smd custom
			(at 0 -0.4445)
			(size 0.1397 0.1397)
			(layers "F.Cu" "F.Mask" "F.Paste")
			(net "SMB_B_HUB_A2")
			(options
				(clearance outline)
				(anchor circle)
			)
			(primitives
				(gr_poly
					(pts
						(arc
							(start -0.1778 -0.2794)
							(mid -0.249642 -0.249642)
							(end -0.2794 -0.1778)
						)
						(arc
							(start -0.2794 0.1778)
							(mid -0.249642 0.249642)
							(end -0.1778 0.2794)
						)
						(arc
							(start 0.1778 0.2794)
							(mid 0.249642 0.249642)
							(end 0.2794 0.1778)
						)
						(arc
							(start 0.2794 -0.1778)
							(mid 0.249642 -0.249642)
							(end 0.1778 -0.2794)
						)
					)
					(width 0)
					(fill yes)
				)
			)
		)
		(pad "2" smd custom
			(at 0 0.4445)
			(size 0.1397 0.1397)
			(layers "F.Cu" "F.Mask" "F.Paste")
			(net "GND")
			(options
				(clearance outline)
				(anchor circle)
			)
			(primitives
				(gr_poly
					(pts
						(arc
							(start -0.1778 -0.2794)
							(mid -0.249642 -0.249642)
							(end -0.2794 -0.1778)
						)
						(arc
							(start -0.2794 0.1778)
							(mid -0.249642 0.249642)
							(end -0.1778 0.2794)
						)
						(arc
							(start 0.1778 0.2794)
							(mid 0.249642 0.249642)
							(end 0.2794 0.1778)
						)
						(arc
							(start 0.2794 -0.1778)
							(mid 0.249642 -0.249642)
							(end 0.1778 -0.2794)
						)
					)
					(width 0)
					(fill yes)
				)
			)
		)
	)
	(footprint ""
		(layer "F.Cu")
		(at 125.1458 2.6416 90)
		(property "Reference" "R142"
			(at 0 0 90)
			(layer "F.SilkS")
			(hide yes)
			(effects
				(font
					(size 1.27 1.27)
				)
			)
		)
		(property "Value" "10KR2F-2-GP"
			(at 0.064008 -3.993896 90)
			(unlocked yes)
			(layer "F.Fab")
			(hide yes)
			(effects
				(font
					(size 1.016 1.016)
					(thickness 0.1524)
				)
			)
		)
		(property "Device Type" "R402H16"
			(at 0.064008 -5.517896 90)
			(unlocked yes)
			(layer "F.Fab")
			(hide yes)
			(effects
				(font
					(size 1.016 1.016)
					(thickness 0.1524)
				)
			)
		)
		(duplicate_pad_numbers_are_jumpers no)
		(fp_line
			(start 0.508 -0.9398)
			(end -0.508 -0.9398)
			(stroke
				(width 0.1524)
				(type default)
			)
			(layer "F.SilkS")
		)
		(fp_line
			(start -0.508 -0.9398)
			(end -0.508 0.9398)
			(stroke
				(width 0.1524)
				(type default)
			)
			(layer "F.SilkS")
		)
		(fp_rect
			(start -0.508 0.9398)
			(end 0.508 -0.9398)
			(stroke
				(width 0)
				(type default)
			)
			(fill no)
			(layer "F.CrtYd")
		)
		(fp_rect
			(start -0.508 0.9398)
			(end 0.508 -0.9398)
			(stroke
				(width 0)
				(type default)
			)
			(fill no)
			(layer "F.Fab")
		)
		(pad "1" smd custom
			(at 0 -0.4445 90)
			(size 0.1397 0.1397)
			(layers "F.Cu" "F.Mask" "F.Paste")
			(net "P3V3_STBY")
			(options
				(clearance outline)
				(anchor circle)
			)
			(primitives
				(gr_poly
					(pts
						(arc
							(start -0.1778 -0.2794)
							(mid -0.249642 -0.249642)
							(end -0.2794 -0.1778)
						)
						(arc
							(start -0.2794 0.1778)
							(mid -0.249642 0.249642)
							(end -0.1778 0.2794)
						)
						(arc
							(start 0.1778 0.2794)
							(mid 0.249642 0.249642)
							(end 0.2794 0.1778)
						)
						(arc
							(start 0.2794 -0.1778)
							(mid 0.249642 -0.249642)
							(end 0.1778 -0.2794)
						)
					)
					(width 0)
					(fill yes)
				)
			)
		)
		(pad "2" smd custom
			(at 0 0.4445 90)
			(size 0.1397 0.1397)
			(layers "F.Cu" "F.Mask" "F.Paste")
			(net "GPIO_P_IO1_6")
			(options
				(clearance outline)
				(anchor circle)
			)
			(primitives
				(gr_poly
					(pts
						(arc
							(start -0.1778 -0.2794)
							(mid -0.249642 -0.249642)
							(end -0.2794 -0.1778)
						)
						(arc
							(start -0.2794 0.1778)
							(mid -0.249642 0.249642)
							(end -0.1778 0.2794)
						)
						(arc
							(start 0.1778 0.2794)
							(mid 0.249642 0.249642)
							(end 0.2794 0.1778)
						)
						(arc
							(start 0.2794 -0.1778)
							(mid 0.249642 -0.249642)
							(end 0.1778 -0.2794)
						)
					)
					(width 0)
					(fill yes)
				)
			)
		)
	)
	(footprint ""
		(layer "F.Cu")
		(at 17.7292 -13.1572 90)
		(property "Reference" "PL1"
			(at 0 0 90)
			(layer "F.SilkS")
			(hide yes)
			(effects
				(font
					(size 1.27 1.27)
				)
			)
		)
		(property "Value" "BLM21PG220SN1DGP"
			(at 0.0254 -5.6896 90)
			(unlocked yes)
			(layer "F.Fab")
			(hide yes)
			(effects
				(font
					(size 1.016 1.016)
					(thickness 0.1524)
				)
			)
		)
		(property "Device Type" "L20125H42"
			(at 0.0254 -7.5946 90)
			(unlocked yes)
			(layer "F.Fab")
			(hide yes)
			(effects
				(font
					(size 1.016 1.016)
					(thickness 0.1524)
				)
			)
		)
		(duplicate_pad_numbers_are_jumpers no)
		(fp_line
			(start 0.9144 -1.7018)
			(end -0.9144 -1.7018)
			(stroke
				(width 0.1524)
				(type default)
			)
			(layer "F.SilkS")
		)
		(fp_line
			(start -0.9144 -1.7018)
			(end -0.9144 1.7018)
			(stroke
				(width 0.1524)
				(type default)
			)
			(layer "F.SilkS")
		)
		(fp_line
			(start 0.9144 1.7018)
			(end 0.9144 -1.7018)
			(stroke
				(width 0.1524)
				(type default)
			)
			(layer "F.SilkS")
		)
		(fp_line
			(start -0.9144 1.7018)
			(end 0.9144 1.7018)
			(stroke
				(width 0.1524)
				(type default)
			)
			(layer "F.SilkS")
		)
		(fp_rect
			(start -1.0033 1.778)
			(end 1.0033 -1.778)
			(stroke
				(width 0)
				(type default)
			)
			(fill no)
			(layer "F.CrtYd")
		)
		(fp_poly
			(pts
				(xy -1.0033 -1.778) (xy 1.0033 -1.778) (xy 1.0033 1.778) (xy -1.0033 1.778)
			)
			(stroke
				(width 0)
				(type default)
			)
			(fill no)
			(layer "F.Fab")
		)
		(pad "1" smd rect
			(at 0 -0.9652 90)
			(size 1.397 1.143)
			(layers "F.Cu" "F.Mask" "F.Paste")
			(net "P12V")
		)
		(pad "2" smd rect
			(at 0 0.9652 90)
			(size 1.397 1.143)
			(layers "F.Cu" "F.Mask" "F.Paste")
			(net "P3V3_VIN")
		)
	)
	(footprint ""
		(layer "F.Cu")
		(at 82.1436 -20.8788 180)
		(property "Reference" "R65"
			(at 0 0 180)
			(layer "F.SilkS")
			(hide yes)
			(effects
				(font
					(size 1.27 1.27)
				)
			)
		)
		(property "Value" "8K2R2F-1-GP"
			(at 0.064008 -3.993896 180)
			(unlocked yes)
			(layer "F.Fab")
			(hide yes)
			(effects
				(font
					(size 1.016 1.016)
					(thickness 0.1524)
				)
			)
		)
		(property "Device Type" "R402H16"
			(at 0.064008 -5.517896 180)
			(unlocked yes)
			(layer "F.Fab")
			(hide yes)
			(effects
				(font
					(size 1.016 1.016)
					(thickness 0.1524)
				)
			)
		)
		(duplicate_pad_numbers_are_jumpers no)
		(fp_line
			(start 0.508 -0.9398)
			(end -0.508 -0.9398)
			(stroke
				(width 0.1524)
				(type default)
			)
			(layer "F.SilkS")
		)
		(fp_line
			(start -0.508 -0.9398)
			(end -0.508 0.9398)
			(stroke
				(width 0.1524)
				(type default)
			)
			(layer "F.SilkS")
		)
		(fp_rect
			(start -0.508 0.9398)
			(end 0.508 -0.9398)
			(stroke
				(width 0)
				(type default)
			)
			(fill no)
			(layer "F.CrtYd")
		)
		(fp_rect
			(start -0.508 0.9398)
			(end 0.508 -0.9398)
			(stroke
				(width 0)
				(type default)
			)
			(fill no)
			(layer "F.Fab")
		)
		(pad "1" smd custom
			(at 0 -0.4445 180)
			(size 0.1397 0.1397)
			(layers "F.Cu" "F.Mask" "F.Paste")
			(net "P12V")
			(options
				(clearance outline)
				(anchor circle)
			)
			(primitives
				(gr_poly
					(pts
						(arc
							(start -0.1778 -0.2794)
							(mid -0.249642 -0.249642)
							(end -0.2794 -0.1778)
						)
						(arc
							(start -0.2794 0.1778)
							(mid -0.249642 0.249642)
							(end -0.1778 0.2794)
						)
						(arc
							(start 0.1778 0.2794)
							(mid 0.249642 0.249642)
							(end 0.2794 0.1778)
						)
						(arc
							(start 0.2794 -0.1778)
							(mid 0.249642 -0.249642)
							(end 0.1778 -0.2794)
						)
					)
					(width 0)
					(fill yes)
				)
			)
		)
		(pad "2" smd custom
			(at 0 0.4445 180)
			(size 0.1397 0.1397)
			(layers "F.Cu" "F.Mask" "F.Paste")
			(net "RESET_IN")
			(options
				(clearance outline)
				(anchor circle)
			)
			(primitives
				(gr_poly
					(pts
						(arc
							(start -0.1778 -0.2794)
							(mid -0.249642 -0.249642)
							(end -0.2794 -0.1778)
						)
						(arc
							(start -0.2794 0.1778)
							(mid -0.249642 0.249642)
							(end -0.1778 0.2794)
						)
						(arc
							(start 0.1778 0.2794)
							(mid 0.249642 0.249642)
							(end 0.2794 0.1778)
						)
						(arc
							(start 0.2794 -0.1778)
							(mid 0.249642 -0.249642)
							(end 0.1778 -0.2794)
						)
					)
					(width 0)
					(fill yes)
				)
			)
		)
	)
	(footprint ""
		(layer "F.Cu")
		(at 17.675098 -20.287742 -135)
		(property "Reference" "C47"
			(at 0 0 225)
			(layer "F.SilkS")
			(hide yes)
			(effects
				(font
					(size 1.27 1.27)
				)
			)
		)
		(property "Value" "SCD1U25V2KX-2-GP"
			(at 1.181083 -2.705137 225)
			(unlocked yes)
			(layer "F.Fab")
			(hide yes)
			(effects
				(font
					(size 1.016 1.016)
					(thickness 0.1524)
				)
			)
		)
		(property "Device Type" "C402H22"
			(at 1.181083 -4.229266 225)
			(unlocked yes)
			(layer "F.Fab")
			(hide yes)
			(effects
				(font
					(size 1.016 1.016)
					(thickness 0.1524)
				)
			)
		)
		(duplicate_pad_numbers_are_jumpers no)
		(fp_poly
			(pts
				(xy -0.43195 -0.952553) (xy 0.43165 -0.952554) (xy 0.431649 0.952446) (xy -0.43195 0.952446)
			)
			(stroke
				(width 0)
				(type default)
			)
			(fill no)
			(layer "F.CrtYd")
		)
		(fp_poly
			(pts
				(xy -0.43195 -0.952553) (xy 0.43165 -0.952554) (xy 0.431649 0.952446) (xy -0.43195 0.952446)
			)
			(stroke
				(width 0)
				(type default)
			)
			(fill no)
			(layer "F.Fab")
		)
		(pad "1" smd custom
			(at 0 -0.4445 225)
			(size 0.1524 0.1524)
			(layers "F.Cu" "F.Mask" "F.Paste")
			(net "SLOT2_P12V_SENSE_VP_R")
			(options
				(clearance outline)
				(anchor circle)
			)
			(primitives
				(gr_poly
					(pts
						(arc
							(start 0.3048 -0.2032)
							(mid 0.275042 -0.275042)
							(end 0.2032 -0.3048)
						)
						(arc
							(start -0.2032 -0.3048)
							(mid -0.275042 -0.275042)
							(end -0.3048 -0.2032)
						)
						(arc
							(start -0.3048 0.2032)
							(mid -0.275042 0.275042)
							(end -0.2032 0.3048)
						)
						(arc
							(start 0.2032 0.3048)
							(mid 0.275042 0.275042)
							(end 0.3048 0.2032)
						)
					)
					(width 0)
					(fill yes)
				)
			)
		)
		(pad "2" smd custom
			(at 0 0.4445 225)
			(size 0.1524 0.1524)
			(layers "F.Cu" "F.Mask" "F.Paste")
			(net "SLOT2_P12V_SENSE_VN_R")
			(options
				(clearance outline)
				(anchor circle)
			)
			(primitives
				(gr_poly
					(pts
						(arc
							(start 0.3048 -0.2032)
							(mid 0.275042 -0.275042)
							(end 0.2032 -0.3048)
						)
						(arc
							(start -0.2032 -0.3048)
							(mid -0.275042 -0.275042)
							(end -0.3048 -0.2032)
						)
						(arc
							(start -0.3048 0.2032)
							(mid -0.275042 0.275042)
							(end -0.2032 0.3048)
						)
						(arc
							(start 0.2032 0.3048)
							(mid 0.275042 0.275042)
							(end 0.3048 0.2032)
						)
					)
					(width 0)
					(fill yes)
				)
			)
		)
	)
	(footprint ""
		(layer "F.Cu")
		(at 23.1394 -31.9532 180)
		(property "Reference" "C60"
			(at 0 0 180)
			(layer "F.SilkS")
			(hide yes)
			(effects
				(font
					(size 1.27 1.27)
				)
			)
		)
		(property "Value" "SC22U16V5MX-4-GP"
			(at -0.0762 -6.1214 180)
			(unlocked yes)
			(layer "F.Fab")
			(hide yes)
			(effects
				(font
					(size 1.016 1.016)
					(thickness 0.1524)
				)
			)
		)
		(property "Device Type" "C805H58"
			(at -0.0762 -8.1534 180)
			(unlocked yes)
			(layer "F.Fab")
			(hide yes)
			(effects
				(font
					(size 1.016 1.016)
					(thickness 0.1524)
				)
			)
		)
		(duplicate_pad_numbers_are_jumpers no)
		(fp_line
			(start 0.635 0)
			(end -0.635 0)
			(stroke
				(width 0.508)
				(type default)
			)
			(layer "F.SilkS")
		)
		(fp_rect
			(start -0.9652 1.778)
			(end 0.9652 -1.778)
			(stroke
				(width 0)
				(type default)
			)
			(fill no)
			(layer "F.CrtYd")
		)
		(fp_poly
			(pts
				(xy -0.9652 -1.778) (xy 0.9652 -1.778) (xy 0.9652 1.778) (xy -0.9652 1.778)
			)
			(stroke
				(width 0)
				(type default)
			)
			(fill no)
			(layer "F.Fab")
		)
		(pad "1" smd rect
			(at 0 -0.9652 180)
			(size 1.397 1.143)
			(layers "F.Cu" "F.Mask" "F.Paste")
			(net "P12V_SLOT3")
		)
		(pad "2" smd rect
			(at 0 0.9652 180)
			(size 1.397 1.143)
			(layers "F.Cu" "F.Mask" "F.Paste")
			(net "GND")
		)
	)
	(footprint ""
		(layer "F.Cu")
		(at 97.525078 -22.008846 180)
		(property "Reference" "U8"
			(at 0 0 180)
			(layer "F.SilkS")
			(hide yes)
			(effects
				(font
					(size 1.27 1.27)
				)
			)
		)
		(property "Value" "SN74LVC1G08DCKR-GP"
			(at -2.3368 -8.6868 180)
			(unlocked yes)
			(layer "F.Fab")
			(hide yes)
			(effects
				(font
					(size 1.016 1.016)
					(thickness 0.1524)
				)
			)
		)
		(property "Device Type" "SC70-5H44"
			(at -2.3114 -10.414 180)
			(unlocked yes)
			(layer "F.Fab")
			(hide yes)
			(effects
				(font
					(size 1.016 1.016)
					(thickness 0.1524)
				)
			)
		)
		(duplicate_pad_numbers_are_jumpers no)
		(fp_line
			(start 1.3843 -1.8034)
			(end 1.3843 -1.1176)
			(stroke
				(width 0.3302)
				(type default)
			)
			(layer "F.SilkS")
		)
		(fp_line
			(start 1.27 1.7018)
			(end -1.27 1.7018)
			(stroke
				(width 0.1524)
				(type default)
			)
			(layer "F.SilkS")
		)
		(fp_line
			(start 1.27 -1.7018)
			(end 1.27 1.7018)
			(stroke
				(width 0.1524)
				(type default)
			)
			(layer "F.SilkS")
		)
		(fp_line
			(start 0.6604 -1.8034)
			(end 1.3843 -1.8034)
			(stroke
				(width 0.3302)
				(type default)
			)
			(layer "F.SilkS")
		)
		(fp_line
			(start -1.27 1.7018)
			(end -1.27 -1.7018)
			(stroke
				(width 0.1524)
				(type default)
			)
			(layer "F.SilkS")
		)
		(fp_line
			(start -1.27 -1.7018)
			(end 1.27 -1.7018)
			(stroke
				(width 0.1524)
				(type default)
			)
			(layer "F.SilkS")
		)
		(fp_rect
			(start -1.524 1.9558)
			(end 1.524 -1.9558)
			(stroke
				(width 0)
				(type default)
			)
			(fill no)
			(layer "F.CrtYd")
		)
		(fp_poly
			(pts
				(xy -1.524 -1.9558) (xy 1.524 -1.9558) (xy 1.524 1.9558) (xy -1.524 1.9558)
			)
			(stroke
				(width 0)
				(type default)
			)
			(fill no)
			(layer "F.Fab")
		)
		(pad "1" smd rect
			(at 0.65024 -0.8255 180)
			(size 0.4064 1.2192)
			(layers "F.Cu" "F.Mask" "F.Paste")
			(net "PERST_O_1_R")
		)
		(pad "2" smd rect
			(at 0 -0.8255 180)
			(size 0.4064 1.2192)
			(layers "F.Cu" "F.Mask" "F.Paste")
			(net "RESET_O_2_R")
		)
		(pad "3" smd rect
			(at -0.65024 -0.8255 180)
			(size 0.4064 1.2192)
			(layers "F.Cu" "F.Mask" "F.Paste")
			(net "GND")
		)
		(pad "4" smd rect
			(at -0.65024 0.8255 180)
			(size 0.4064 1.2192)
			(layers "F.Cu" "F.Mask" "F.Paste")
			(net "PERST_N_1")
		)
		(pad "5" smd rect
			(at 0.65024 0.8255 180)
			(size 0.4064 1.2192)
			(layers "F.Cu" "F.Mask" "F.Paste")
			(net "P3V3_STBY")
		)
	)
	(footprint ""
		(layer "F.Cu")
		(at 119.5832 -8.0772 90)
		(property "Reference" "R136"
			(at 0 0 90)
			(layer "F.SilkS")
			(hide yes)
			(effects
				(font
					(size 1.27 1.27)
				)
			)
		)
		(property "Value" "10KR2F-2-GP"
			(at 0.064008 -3.993896 90)
			(unlocked yes)
			(layer "F.Fab")
			(hide yes)
			(effects
				(font
					(size 1.016 1.016)
					(thickness 0.1524)
				)
			)
		)
		(property "Device Type" "R402H16"
			(at 0.064008 -5.517896 90)
			(unlocked yes)
			(layer "F.Fab")
			(hide yes)
			(effects
				(font
					(size 1.016 1.016)
					(thickness 0.1524)
				)
			)
		)
		(duplicate_pad_numbers_are_jumpers no)
		(fp_line
			(start 0.508 -0.9398)
			(end -0.508 -0.9398)
			(stroke
				(width 0.1524)
				(type default)
			)
			(layer "F.SilkS")
		)
		(fp_line
			(start -0.508 -0.9398)
			(end -0.508 0.9398)
			(stroke
				(width 0.1524)
				(type default)
			)
			(layer "F.SilkS")
		)
		(fp_rect
			(start -0.508 0.9398)
			(end 0.508 -0.9398)
			(stroke
				(width 0)
				(type default)
			)
			(fill no)
			(layer "F.CrtYd")
		)
		(fp_rect
			(start -0.508 0.9398)
			(end 0.508 -0.9398)
			(stroke
				(width 0)
				(type default)
			)
			(fill no)
			(layer "F.Fab")
		)
		(pad "1" smd custom
			(at 0 -0.4445 90)
			(size 0.1397 0.1397)
			(layers "F.Cu" "F.Mask" "F.Paste")
			(net "P3V3_STBY")
			(options
				(clearance outline)
				(anchor circle)
			)
			(primitives
				(gr_poly
					(pts
						(arc
							(start -0.1778 -0.2794)
							(mid -0.249642 -0.249642)
							(end -0.2794 -0.1778)
						)
						(arc
							(start -0.2794 0.1778)
							(mid -0.249642 0.249642)
							(end -0.1778 0.2794)
						)
						(arc
							(start 0.1778 0.2794)
							(mid 0.249642 0.249642)
							(end 0.2794 0.1778)
						)
						(arc
							(start 0.2794 -0.1778)
							(mid 0.249642 -0.249642)
							(end 0.1778 -0.2794)
						)
					)
					(width 0)
					(fill yes)
				)
			)
		)
		(pad "2" smd custom
			(at 0 0.4445 90)
			(size 0.1397 0.1397)
			(layers "F.Cu" "F.Mask" "F.Paste")
			(net "GPIO_P_IO1_3")
			(options
				(clearance outline)
				(anchor circle)
			)
			(primitives
				(gr_poly
					(pts
						(arc
							(start -0.1778 -0.2794)
							(mid -0.249642 -0.249642)
							(end -0.2794 -0.1778)
						)
						(arc
							(start -0.2794 0.1778)
							(mid -0.249642 0.249642)
							(end -0.1778 0.2794)
						)
						(arc
							(start 0.1778 0.2794)
							(mid 0.249642 0.249642)
							(end 0.2794 0.1778)
						)
						(arc
							(start 0.2794 -0.1778)
							(mid 0.249642 -0.249642)
							(end 0.1778 -0.2794)
						)
					)
					(width 0)
					(fill yes)
				)
			)
		)
	)
	(footprint ""
		(layer "F.Cu")
		(at 15.1384 -23.5458 180)
		(property "Reference" "R90"
			(at 0 0 180)
			(layer "F.SilkS")
			(hide yes)
			(effects
				(font
					(size 1.27 1.27)
				)
			)
		)
		(property "Value" "D001R6F-L-GP"
			(at -0.127 -3.7338 180)
			(unlocked yes)
			(layer "F.Fab")
			(hide yes)
			(effects
				(font
					(size 1.016 1.016)
					(thickness 0.1524)
				)
			)
		)
		(property "Device Type" "R1206H36"
			(at -0.127 -5.2578 180)
			(unlocked yes)
			(layer "F.Fab")
			(hide yes)
			(effects
				(font
					(size 1.016 1.016)
					(thickness 0.1524)
				)
			)
		)
		(duplicate_pad_numbers_are_jumpers no)
		(fp_line
			(start 1.016 2.2352)
			(end -1.016 2.2352)
			(stroke
				(width 0.1524)
				(type default)
			)
			(layer "F.SilkS")
		)
		(fp_line
			(start 1.016 -2.2352)
			(end 1.016 2.2352)
			(stroke
				(width 0.1524)
				(type default)
			)
			(layer "F.SilkS")
		)
		(fp_line
			(start -1.016 2.2352)
			(end -1.016 -2.2352)
			(stroke
				(width 0.1524)
				(type default)
			)
			(layer "F.SilkS")
		)
		(fp_line
			(start -1.016 -2.2352)
			(end 1.016 -2.2352)
			(stroke
				(width 0.1524)
				(type default)
			)
			(layer "F.SilkS")
		)
		(fp_rect
			(start -0.8001 1.6002)
			(end 0.8001 -1.6002)
			(stroke
				(width 0)
				(type default)
			)
			(fill no)
			(layer "F.CrtYd")
		)
		(fp_poly
			(pts
				(xy -1.0922 2.3114) (xy -1.0922 -2.3114) (xy 1.0922 -2.3114) (xy 1.0922 1.5875) (xy 0.8001 1.5875)
				(xy 0.8001 -1.6002) (xy -0.8001 -1.6002) (xy -0.8001 1.6002) (xy 1.0922 1.6002) (xy 1.0922 2.3114)
			)
			(stroke
				(width 0)
				(type default)
			)
			(fill no)
			(layer "F.CrtYd")
		)
		(fp_rect
			(start -1.0922 2.3114)
			(end 1.0922 -2.3114)
			(stroke
				(width 0)
				(type default)
			)
			(fill no)
			(layer "F.Fab")
		)
		(pad "1" smd rect
			(at 0 -1.397 180)
			(size 1.651 1.27)
			(layers "F.Cu" "F.Mask" "F.Paste")
			(net "P12V")
		)
		(pad "2" smd rect
			(at 0 1.397 180)
			(size 1.651 1.27)
			(layers "F.Cu" "F.Mask" "F.Paste")
			(net "P12V_SLOT3")
		)
	)
	(footprint ""
		(layer "F.Cu")
		(at 28.6004 -16.7894 180)
		(property "Reference" "C14"
			(at 0 0 180)
			(layer "F.SilkS")
			(hide yes)
			(effects
				(font
					(size 1.27 1.27)
				)
			)
		)
		(property "Value" "SCD1U25V3KX-GP"
			(at 0 -2.8194 180)
			(unlocked yes)
			(layer "F.Fab")
			(hide yes)
			(effects
				(font
					(size 1.016 1.016)
					(thickness 0.1524)
				)
			)
		)
		(property "Device Type" "C603H36"
			(at 0 -4.3434 180)
			(unlocked yes)
			(layer "F.Fab")
			(hide yes)
			(effects
				(font
					(size 1.016 1.016)
					(thickness 0.1524)
				)
			)
		)
		(duplicate_pad_numbers_are_jumpers no)
		(fp_line
			(start 0.508 0)
			(end -0.508 0)
			(stroke
				(width 0.2032)
				(type default)
			)
			(layer "F.SilkS")
		)
		(fp_rect
			(start -0.5842 1.3335)
			(end 0.5842 -1.3335)
			(stroke
				(width 0)
				(type default)
			)
			(fill no)
			(layer "F.CrtYd")
		)
		(fp_rect
			(start -0.5842 1.3335)
			(end 0.5842 -1.3335)
			(stroke
				(width 0)
				(type default)
			)
			(fill no)
			(layer "F.Fab")
		)
		(pad "1" smd custom
			(at 0 -0.762 180)
			(size 0.2159 0.2159)
			(layers "F.Cu" "F.Mask" "F.Paste")
			(net "P12V_SLOT2")
			(options
				(clearance outline)
				(anchor circle)
			)
			(primitives
				(gr_poly
					(pts
						(arc
							(start -0.3302 -0.4318)
							(mid -0.402042 -0.402042)
							(end -0.4318 -0.3302)
						)
						(arc
							(start -0.4318 0.3302)
							(mid -0.402042 0.402042)
							(end -0.3302 0.4318)
						)
						(arc
							(start 0.3302 0.4318)
							(mid 0.402042 0.402042)
							(end 0.4318 0.3302)
						)
						(arc
							(start 0.4318 -0.3302)
							(mid 0.402042 -0.402042)
							(end 0.3302 -0.4318)
						)
					)
					(width 0)
					(fill yes)
				)
			)
		)
		(pad "2" smd custom
			(at 0 0.762 180)
			(size 0.2159 0.2159)
			(layers "F.Cu" "F.Mask" "F.Paste")
			(net "GND")
			(options
				(clearance outline)
				(anchor circle)
			)
			(primitives
				(gr_poly
					(pts
						(arc
							(start -0.3302 -0.4318)
							(mid -0.402042 -0.402042)
							(end -0.4318 -0.3302)
						)
						(arc
							(start -0.4318 0.3302)
							(mid -0.402042 0.402042)
							(end -0.3302 0.4318)
						)
						(arc
							(start 0.3302 0.4318)
							(mid 0.402042 0.402042)
							(end 0.4318 0.3302)
						)
						(arc
							(start 0.4318 -0.3302)
							(mid 0.402042 -0.402042)
							(end 0.3302 -0.4318)
						)
					)
					(width 0)
					(fill yes)
				)
			)
		)
	)
	(footprint ""
		(layer "F.Cu")
		(at 38.6969 -0.0635 90)
		(property "Reference" "C17"
			(at 0 0 90)
			(layer "F.SilkS")
			(hide yes)
			(effects
				(font
					(size 1.27 1.27)
				)
			)
		)
		(property "Value" "SCD1U16V2KX-3GP"
			(at 1.1811 -2.7051 90)
			(unlocked yes)
			(layer "F.Fab")
			(hide yes)
			(effects
				(font
					(size 1.016 1.016)
					(thickness 0.1524)
				)
			)
		)
		(property "Device Type" "C402H22"
			(at 1.1811 -4.2291 90)
			(unlocked yes)
			(layer "F.Fab")
			(hide yes)
			(effects
				(font
					(size 1.016 1.016)
					(thickness 0.1524)
				)
			)
		)
		(duplicate_pad_numbers_are_jumpers no)
		(fp_rect
			(start -0.4318 0.9525)
			(end 0.4318 -0.9525)
			(stroke
				(width 0)
				(type default)
			)
			(fill no)
			(layer "F.CrtYd")
		)
		(fp_rect
			(start -0.4318 0.9525)
			(end 0.4318 -0.9525)
			(stroke
				(width 0)
				(type default)
			)
			(fill no)
			(layer "F.Fab")
		)
		(pad "1" smd custom
			(at 0 -0.4445 90)
			(size 0.1524 0.1524)
			(layers "F.Cu" "F.Mask" "F.Paste")
			(net "P3V3")
			(options
				(clearance outline)
				(anchor circle)
			)
			(primitives
				(gr_poly
					(pts
						(arc
							(start 0.3048 -0.2032)
							(mid 0.275042 -0.275042)
							(end 0.2032 -0.3048)
						)
						(arc
							(start -0.2032 -0.3048)
							(mid -0.275042 -0.275042)
							(end -0.3048 -0.2032)
						)
						(arc
							(start -0.3048 0.2032)
							(mid -0.275042 0.275042)
							(end -0.2032 0.3048)
						)
						(arc
							(start 0.2032 0.3048)
							(mid 0.275042 0.275042)
							(end 0.3048 0.2032)
						)
					)
					(width 0)
					(fill yes)
				)
			)
		)
		(pad "2" smd custom
			(at 0 0.4445 90)
			(size 0.1524 0.1524)
			(layers "F.Cu" "F.Mask" "F.Paste")
			(net "GND")
			(options
				(clearance outline)
				(anchor circle)
			)
			(primitives
				(gr_poly
					(pts
						(arc
							(start 0.3048 -0.2032)
							(mid 0.275042 -0.275042)
							(end 0.2032 -0.3048)
						)
						(arc
							(start -0.2032 -0.3048)
							(mid -0.275042 -0.275042)
							(end -0.3048 -0.2032)
						)
						(arc
							(start -0.3048 0.2032)
							(mid -0.275042 0.275042)
							(end -0.2032 0.3048)
						)
						(arc
							(start 0.2032 0.3048)
							(mid 0.275042 0.275042)
							(end 0.3048 0.2032)
						)
					)
					(width 0)
					(fill yes)
				)
			)
		)
	)
	(footprint ""
		(layer "F.Cu")
		(at 27.3812 -16.764 180)
		(property "Reference" "C16"
			(at 0 0 180)
			(layer "F.SilkS")
			(hide yes)
			(effects
				(font
					(size 1.27 1.27)
				)
			)
		)
		(property "Value" "SCD1U25V3KX-GP"
			(at 0 -2.8194 180)
			(unlocked yes)
			(layer "F.Fab")
			(hide yes)
			(effects
				(font
					(size 1.016 1.016)
					(thickness 0.1524)
				)
			)
		)
		(property "Device Type" "C603H36"
			(at 0 -4.3434 180)
			(unlocked yes)
			(layer "F.Fab")
			(hide yes)
			(effects
				(font
					(size 1.016 1.016)
					(thickness 0.1524)
				)
			)
		)
		(duplicate_pad_numbers_are_jumpers no)
		(fp_line
			(start 0.508 0)
			(end -0.508 0)
			(stroke
				(width 0.2032)
				(type default)
			)
			(layer "F.SilkS")
		)
		(fp_rect
			(start -0.5842 1.3335)
			(end 0.5842 -1.3335)
			(stroke
				(width 0)
				(type default)
			)
			(fill no)
			(layer "F.CrtYd")
		)
		(fp_rect
			(start -0.5842 1.3335)
			(end 0.5842 -1.3335)
			(stroke
				(width 0)
				(type default)
			)
			(fill no)
			(layer "F.Fab")
		)
		(pad "1" smd custom
			(at 0 -0.762 180)
			(size 0.2159 0.2159)
			(layers "F.Cu" "F.Mask" "F.Paste")
			(net "P12V_SLOT2")
			(options
				(clearance outline)
				(anchor circle)
			)
			(primitives
				(gr_poly
					(pts
						(arc
							(start -0.3302 -0.4318)
							(mid -0.402042 -0.402042)
							(end -0.4318 -0.3302)
						)
						(arc
							(start -0.4318 0.3302)
							(mid -0.402042 0.402042)
							(end -0.3302 0.4318)
						)
						(arc
							(start 0.3302 0.4318)
							(mid 0.402042 0.402042)
							(end 0.4318 0.3302)
						)
						(arc
							(start 0.4318 -0.3302)
							(mid 0.402042 -0.402042)
							(end 0.3302 -0.4318)
						)
					)
					(width 0)
					(fill yes)
				)
			)
		)
		(pad "2" smd custom
			(at 0 0.762 180)
			(size 0.2159 0.2159)
			(layers "F.Cu" "F.Mask" "F.Paste")
			(net "GND")
			(options
				(clearance outline)
				(anchor circle)
			)
			(primitives
				(gr_poly
					(pts
						(arc
							(start -0.3302 -0.4318)
							(mid -0.402042 -0.402042)
							(end -0.4318 -0.3302)
						)
						(arc
							(start -0.4318 0.3302)
							(mid -0.402042 0.402042)
							(end -0.3302 0.4318)
						)
						(arc
							(start 0.3302 0.4318)
							(mid 0.402042 0.402042)
							(end 0.4318 0.3302)
						)
						(arc
							(start 0.4318 -0.3302)
							(mid 0.402042 -0.402042)
							(end 0.3302 -0.4318)
						)
					)
					(width 0)
					(fill yes)
				)
			)
		)
	)
	(footprint ""
		(layer "F.Cu")
		(at 131.7498 -10.4394 90)
		(property "Reference" "R123"
			(at 0 0 90)
			(layer "F.SilkS")
			(hide yes)
			(effects
				(font
					(size 1.27 1.27)
				)
			)
		)
		(property "Value" "10KR2F-2-GP"
			(at 0.064008 -3.993896 90)
			(unlocked yes)
			(layer "F.Fab")
			(hide yes)
			(effects
				(font
					(size 1.016 1.016)
					(thickness 0.1524)
				)
			)
		)
		(property "Device Type" "R402H16"
			(at 0.064008 -5.517896 90)
			(unlocked yes)
			(layer "F.Fab")
			(hide yes)
			(effects
				(font
					(size 1.016 1.016)
					(thickness 0.1524)
				)
			)
		)
		(duplicate_pad_numbers_are_jumpers no)
		(fp_line
			(start 0.508 -0.9398)
			(end -0.508 -0.9398)
			(stroke
				(width 0.1524)
				(type default)
			)
			(layer "F.SilkS")
		)
		(fp_line
			(start -0.508 -0.9398)
			(end -0.508 0.9398)
			(stroke
				(width 0.1524)
				(type default)
			)
			(layer "F.SilkS")
		)
		(fp_rect
			(start -0.508 0.9398)
			(end 0.508 -0.9398)
			(stroke
				(width 0)
				(type default)
			)
			(fill no)
			(layer "F.CrtYd")
		)
		(fp_rect
			(start -0.508 0.9398)
			(end 0.508 -0.9398)
			(stroke
				(width 0)
				(type default)
			)
			(fill no)
			(layer "F.Fab")
		)
		(pad "1" smd custom
			(at 0 -0.4445 90)
			(size 0.1397 0.1397)
			(layers "F.Cu" "F.Mask" "F.Paste")
			(net "GPIO_B_IO1_3")
			(options
				(clearance outline)
				(anchor circle)
			)
			(primitives
				(gr_poly
					(pts
						(arc
							(start -0.1778 -0.2794)
							(mid -0.249642 -0.249642)
							(end -0.2794 -0.1778)
						)
						(arc
							(start -0.2794 0.1778)
							(mid -0.249642 0.249642)
							(end -0.1778 0.2794)
						)
						(arc
							(start 0.1778 0.2794)
							(mid 0.249642 0.249642)
							(end 0.2794 0.1778)
						)
						(arc
							(start 0.2794 -0.1778)
							(mid 0.249642 -0.249642)
							(end 0.1778 -0.2794)
						)
					)
					(width 0)
					(fill yes)
				)
			)
		)
		(pad "2" smd custom
			(at 0 0.4445 90)
			(size 0.1397 0.1397)
			(layers "F.Cu" "F.Mask" "F.Paste")
			(net "GND")
			(options
				(clearance outline)
				(anchor circle)
			)
			(primitives
				(gr_poly
					(pts
						(arc
							(start -0.1778 -0.2794)
							(mid -0.249642 -0.249642)
							(end -0.2794 -0.1778)
						)
						(arc
							(start -0.2794 0.1778)
							(mid -0.249642 0.249642)
							(end -0.1778 0.2794)
						)
						(arc
							(start 0.1778 0.2794)
							(mid 0.249642 0.249642)
							(end 0.2794 0.1778)
						)
						(arc
							(start 0.2794 -0.1778)
							(mid 0.249642 -0.249642)
							(end 0.1778 -0.2794)
						)
					)
					(width 0)
					(fill yes)
				)
			)
		)
	)
	(footprint ""
		(layer "F.Cu")
		(at 23.1394 -13.7922 90)
		(property "Reference" "PC1"
			(at 0 0 90)
			(layer "F.SilkS")
			(hide yes)
			(effects
				(font
					(size 1.27 1.27)
				)
			)
		)
		(property "Value" "SC22U16V5MX-4-GP"
			(at -0.0762 -6.1214 90)
			(unlocked yes)
			(layer "F.Fab")
			(hide yes)
			(effects
				(font
					(size 1.016 1.016)
					(thickness 0.1524)
				)
			)
		)
		(property "Device Type" "C805H58"
			(at -0.0762 -8.1534 90)
			(unlocked yes)
			(layer "F.Fab")
			(hide yes)
			(effects
				(font
					(size 1.016 1.016)
					(thickness 0.1524)
				)
			)
		)
		(duplicate_pad_numbers_are_jumpers no)
		(fp_line
			(start 0.635 0)
			(end -0.635 0)
			(stroke
				(width 0.508)
				(type default)
			)
			(layer "F.SilkS")
		)
		(fp_rect
			(start -0.9652 1.778)
			(end 0.9652 -1.778)
			(stroke
				(width 0)
				(type default)
			)
			(fill no)
			(layer "F.CrtYd")
		)
		(fp_poly
			(pts
				(xy -0.9652 -1.778) (xy 0.9652 -1.778) (xy 0.9652 1.778) (xy -0.9652 1.778)
			)
			(stroke
				(width 0)
				(type default)
			)
			(fill no)
			(layer "F.Fab")
		)
		(pad "1" smd rect
			(at 0 -0.9652 90)
			(size 1.397 1.143)
			(layers "F.Cu" "F.Mask" "F.Paste")
			(net "P3V3_VIN")
		)
		(pad "2" smd rect
			(at 0 0.9652 90)
			(size 1.397 1.143)
			(layers "F.Cu" "F.Mask" "F.Paste")
			(net "GND")
		)
	)
	(footprint ""
		(layer "F.Cu")
		(at 42.729912 -30.820106)
		(property "Reference" "SLOT3"
			(at 0 0 0)
			(layer "F.SilkS")
			(hide yes)
			(effects
				(font
					(size 1.27 1.27)
				)
			)
		)
		(property "Value" "PCISLT164-129-GP"
			(at -15.9639 4.8514 0)
			(unlocked yes)
			(layer "F.Fab")
			(hide yes)
			(effects
				(font
					(size 1.016 1.016)
					(thickness 0.1524)
				)
			)
		)
		(property "Device Type" "10018783-10203TLF"
			(at -15.9639 3.3274 0)
			(unlocked yes)
			(layer "F.Fab")
			(hide yes)
			(effects
				(font
					(size 1.016 1.016)
					(thickness 0.1524)
				)
			)
		)
		(duplicate_pad_numbers_are_jumpers no)
		(fp_line
			(start -14.9098 -4.0386)
			(end 74.5998 -4.0386)
			(stroke
				(width 0.1524)
				(type default)
			)
			(layer "F.SilkS")
		)
		(fp_line
			(start -14.9098 5.3594)
			(end -14.9098 -4.0386)
			(stroke
				(width 0.1524)
				(type default)
			)
			(layer "F.SilkS")
		)
		(fp_line
			(start 74.5998 -4.0386)
			(end 74.5998 5.3594)
			(stroke
				(width 0.1524)
				(type default)
			)
			(layer "F.SilkS")
		)
		(fp_line
			(start 74.5998 5.3594)
			(end -14.9098 5.3594)
			(stroke
				(width 0.1524)
				(type default)
			)
			(layer "F.SilkS")
		)
		(fp_rect
			(start -14.6558 5.1054)
			(end 74.3458 -3.683)
			(stroke
				(width 0)
				(type default)
			)
			(fill no)
			(layer "F.CrtYd")
		)
		(fp_poly
			(pts
				(xy -15.1638 5.6134) (xy -15.1638 0.00254) (xy -14.6558 0.00254) (xy -14.6558 5.1054) (xy 74.3458 5.1054)
				(xy 74.3458 -3.683) (xy -14.6558 -3.683) (xy -14.6558 -0.00254) (xy -15.1638 -0.00254) (xy -15.1638 -4.2926)
				(xy 74.8538 -4.2926) (xy 74.8538 5.6134)
			)
			(stroke
				(width 0)
				(type default)
			)
			(fill no)
			(layer "F.CrtYd")
		)
		(fp_rect
			(start -15.1638 5.6134)
			(end 74.8538 -4.2926)
			(stroke
				(width 0)
				(type default)
			)
			(fill no)
			(layer "F.Fab")
		)
		(pad "" np_thru_hole circle
			(at 0 0)
			(size 0.254 0.254)
			(drill 2.3622)
			(layers "*.Cu" "*.Mask")
			(clearance 1.4097)
			(thermal_gap 1.4097)
		)
		(pad "" np_thru_hole circle
			(at 73.14946 0)
			(size 0.254 0.254)
			(drill 2.3622)
			(layers "*.Cu" "*.Mask")
			(clearance 1.4097)
			(thermal_gap 1.4097)
		)
		(pad "A1" thru_hole circle
			(at -11.64971 -1.24968)
			(size 1.0668 1.0668)
			(drill 0.7112)
			(layers "*.Cu" "*.Mask")
			(remove_unused_layers no)
			(net "PD_SLOT3_PRSNT1")
			(clearance 0.1778)
			(thermal_gap 0.1778)
		)
		(pad "A2" thru_hole circle
			(at -10.65022 -3.24993)
			(size 1.0668 1.0668)
			(drill 0.7112)
			(layers "*.Cu" "*.Mask")
			(remove_unused_layers no)
			(net "P12V_SLOT3")
			(clearance 0.1778)
			(thermal_gap 0.1778)
		)
		(pad "A3" thru_hole circle
			(at -9.64946 -1.24968)
			(size 1.0668 1.0668)
			(drill 0.7112)
			(layers "*.Cu" "*.Mask")
			(remove_unused_layers no)
			(net "P12V_SLOT3")
			(clearance 0.1778)
			(thermal_gap 0.1778)
		)
		(pad "A4" thru_hole circle
			(at -8.64997 -3.24993)
			(size 1.0668 1.0668)
			(drill 0.7112)
			(layers "*.Cu" "*.Mask")
			(remove_unused_layers no)
			(net "GND")
			(clearance 0.1778)
			(thermal_gap 0.1778)
		)
		(pad "A5" thru_hole circle
			(at -7.65048 -1.24968)
			(size 1.0668 1.0668)
			(drill 0.7112)
			(layers "*.Cu" "*.Mask")
			(remove_unused_layers no)
			(net "Net_95")
			(clearance 0.1778)
			(thermal_gap 0.1778)
		)
		(pad "A6" thru_hole circle
			(at -6.64972 -3.24993)
			(size 1.0668 1.0668)
			(drill 0.7112)
			(layers "*.Cu" "*.Mask")
			(remove_unused_layers no)
			(net "Net_96")
			(clearance 0.1778)
			(thermal_gap 0.1778)
		)
		(pad "A7" thru_hole circle
			(at -5.65023 -1.24968)
			(size 1.0668 1.0668)
			(drill 0.7112)
			(layers "*.Cu" "*.Mask")
			(remove_unused_layers no)
			(net "SMCLK_PCH_SLOT3_R")
			(clearance 0.1778)
			(thermal_gap 0.1778)
		)
		(pad "A8" thru_hole circle
			(at -4.64947 -3.24993)
			(size 1.0668 1.0668)
			(drill 0.7112)
			(layers "*.Cu" "*.Mask")
			(remove_unused_layers no)
			(net "SMDAT_PCH_SLOT3_R")
			(clearance 0.1778)
			(thermal_gap 0.1778)
		)
		(pad "A9" thru_hole circle
			(at -3.64998 -1.24968)
			(size 1.0668 1.0668)
			(drill 0.7112)
			(layers "*.Cu" "*.Mask")
			(remove_unused_layers no)
			(net "P3V3")
			(clearance 0.1778)
			(thermal_gap 0.1778)
		)
		(pad "A10" thru_hole circle
			(at -2.65049 -3.24993)
			(size 1.0668 1.0668)
			(drill 0.7112)
			(layers "*.Cu" "*.Mask")
			(remove_unused_layers no)
			(net "P3V3")
			(clearance 0.1778)
			(thermal_gap 0.1778)
		)
		(pad "A11" thru_hole circle
			(at -1.64973 -1.24968)
			(size 1.0668 1.0668)
			(drill 0.7112)
			(layers "*.Cu" "*.Mask")
			(remove_unused_layers no)
			(net "RESET_BUF_N_SLOT3")
			(clearance 0.1778)
			(thermal_gap 0.1778)
		)
		(pad "A12" thru_hole circle
			(at 1.35001 -3.24993)
			(size 1.0668 1.0668)
			(drill 0.7112)
			(layers "*.Cu" "*.Mask")
			(remove_unused_layers no)
			(net "GND")
			(clearance 0.1778)
			(thermal_gap 0.1778)
		)
		(pad "A13" thru_hole circle
			(at 2.3495 -1.24968)
			(size 1.0668 1.0668)
			(drill 0.7112)
			(layers "*.Cu" "*.Mask")
			(remove_unused_layers no)
			(net "CLK_100M_PCH_SLOTX24_S4_DP")
			(clearance 0.1778)
			(thermal_gap 0.1778)
		)
		(pad "A14" thru_hole circle
			(at 3.35026 -3.24993)
			(size 1.0668 1.0668)
			(drill 0.7112)
			(layers "*.Cu" "*.Mask")
			(remove_unused_layers no)
			(net "CLK_100M_PCH_SLOTX24_S4_DN")
			(clearance 0.1778)
			(thermal_gap 0.1778)
		)
		(pad "A15" thru_hole circle
			(at 4.34975 -1.24968)
			(size 1.0668 1.0668)
			(drill 0.7112)
			(layers "*.Cu" "*.Mask")
			(remove_unused_layers no)
			(net "GND")
			(clearance 0.1778)
			(thermal_gap 0.1778)
		)
		(pad "A16" thru_hole circle
			(at 5.35051 -3.24993)
			(size 1.0668 1.0668)
			(drill 0.7112)
			(layers "*.Cu" "*.Mask")
			(remove_unused_layers no)
			(net "P3E_CPU0_PE2_SS_RXP<0>")
			(clearance 0.1778)
			(thermal_gap 0.1778)
		)
		(pad "A17" thru_hole circle
			(at 6.35 -1.24968)
			(size 1.0668 1.0668)
			(drill 0.7112)
			(layers "*.Cu" "*.Mask")
			(remove_unused_layers no)
			(net "P3E_CPU0_PE2_SS_RXN<0>")
			(clearance 0.1778)
			(thermal_gap 0.1778)
		)
		(pad "A18" thru_hole circle
			(at 7.34949 -3.24993)
			(size 1.0668 1.0668)
			(drill 0.7112)
			(layers "*.Cu" "*.Mask")
			(remove_unused_layers no)
			(net "GND")
			(clearance 0.1778)
			(thermal_gap 0.1778)
		)
		(pad "A19" thru_hole circle
			(at 8.35025 -1.24968)
			(size 1.0668 1.0668)
			(drill 0.7112)
			(layers "*.Cu" "*.Mask")
			(remove_unused_layers no)
			(net "Net_92")
			(clearance 0.1778)
			(thermal_gap 0.1778)
		)
		(pad "A20" thru_hole circle
			(at 9.34974 -3.24993)
			(size 1.0668 1.0668)
			(drill 0.7112)
			(layers "*.Cu" "*.Mask")
			(remove_unused_layers no)
			(net "GND")
			(clearance 0.1778)
			(thermal_gap 0.1778)
		)
		(pad "A21" thru_hole circle
			(at 10.3505 -1.24968)
			(size 1.0668 1.0668)
			(drill 0.7112)
			(layers "*.Cu" "*.Mask")
			(remove_unused_layers no)
			(net "P3E_CPU0_PE2_SS_RXP<1>")
			(clearance 0.1778)
			(thermal_gap 0.1778)
		)
		(pad "A22" thru_hole circle
			(at 11.34999 -3.24993)
			(size 1.0668 1.0668)
			(drill 0.7112)
			(layers "*.Cu" "*.Mask")
			(remove_unused_layers no)
			(net "P3E_CPU0_PE2_SS_RXN<1>")
			(clearance 0.1778)
			(thermal_gap 0.1778)
		)
		(pad "A23" thru_hole circle
			(at 12.34948 -1.24968)
			(size 1.0668 1.0668)
			(drill 0.7112)
			(layers "*.Cu" "*.Mask")
			(remove_unused_layers no)
			(net "GND")
			(clearance 0.1778)
			(thermal_gap 0.1778)
		)
		(pad "A24" thru_hole circle
			(at 13.35024 -3.24993)
			(size 1.0668 1.0668)
			(drill 0.7112)
			(layers "*.Cu" "*.Mask")
			(remove_unused_layers no)
			(net "GND")
			(clearance 0.1778)
			(thermal_gap 0.1778)
		)
		(pad "A25" thru_hole circle
			(at 14.34973 -1.24968)
			(size 1.0668 1.0668)
			(drill 0.7112)
			(layers "*.Cu" "*.Mask")
			(remove_unused_layers no)
			(net "P3E_CPU0_PE2_SS_RXP<2>")
			(clearance 0.1778)
			(thermal_gap 0.1778)
		)
		(pad "A26" thru_hole circle
			(at 15.35049 -3.24993)
			(size 1.0668 1.0668)
			(drill 0.7112)
			(layers "*.Cu" "*.Mask")
			(remove_unused_layers no)
			(net "P3E_CPU0_PE2_SS_RXN<2>")
			(clearance 0.1778)
			(thermal_gap 0.1778)
		)
		(pad "A27" thru_hole circle
			(at 16.34998 -1.24968)
			(size 1.0668 1.0668)
			(drill 0.7112)
			(layers "*.Cu" "*.Mask")
			(remove_unused_layers no)
			(net "GND")
			(clearance 0.1778)
			(thermal_gap 0.1778)
		)
		(pad "A28" thru_hole circle
			(at 17.34947 -3.24993)
			(size 1.0668 1.0668)
			(drill 0.7112)
			(layers "*.Cu" "*.Mask")
			(remove_unused_layers no)
			(net "GND")
			(clearance 0.1778)
			(thermal_gap 0.1778)
		)
		(pad "A29" thru_hole circle
			(at 18.35023 -1.24968)
			(size 1.0668 1.0668)
			(drill 0.7112)
			(layers "*.Cu" "*.Mask")
			(remove_unused_layers no)
			(net "P3E_CPU0_PE2_SS_RXP<3>")
			(clearance 0.1778)
			(thermal_gap 0.1778)
		)
		(pad "A30" thru_hole circle
			(at 19.34972 -3.24993)
			(size 1.0668 1.0668)
			(drill 0.7112)
			(layers "*.Cu" "*.Mask")
			(remove_unused_layers no)
			(net "P3E_CPU0_PE2_SS_RXN<3>")
			(clearance 0.1778)
			(thermal_gap 0.1778)
		)
		(pad "A31" thru_hole circle
			(at 20.35048 -1.24968)
			(size 1.0668 1.0668)
			(drill 0.7112)
			(layers "*.Cu" "*.Mask")
			(remove_unused_layers no)
			(net "GND")
			(clearance 0.1778)
			(thermal_gap 0.1778)
		)
		(pad "A32" thru_hole circle
			(at 21.34997 -3.24993)
			(size 1.0668 1.0668)
			(drill 0.7112)
			(layers "*.Cu" "*.Mask")
			(remove_unused_layers no)
			(net "USB_HUB_PCIE_DP1")
			(clearance 0.1778)
			(thermal_gap 0.1778)
		)
		(pad "A33" thru_hole circle
			(at 22.34946 -1.24968)
			(size 1.0668 1.0668)
			(drill 0.7112)
			(layers "*.Cu" "*.Mask")
			(remove_unused_layers no)
			(net "USB_HUB_PCIE_DN1")
			(clearance 0.1778)
			(thermal_gap 0.1778)
		)
		(pad "A34" thru_hole circle
			(at 23.35022 -3.24993)
			(size 1.0668 1.0668)
			(drill 0.7112)
			(layers "*.Cu" "*.Mask")
			(remove_unused_layers no)
			(net "GND")
			(clearance 0.1778)
			(thermal_gap 0.1778)
		)
		(pad "A35" thru_hole circle
			(at 24.34971 -1.24968)
			(size 1.0668 1.0668)
			(drill 0.7112)
			(layers "*.Cu" "*.Mask")
			(remove_unused_layers no)
			(net "P3E_CPU0_PE2_SS_RXP<4>")
			(clearance 0.1778)
			(thermal_gap 0.1778)
		)
		(pad "A36" thru_hole circle
			(at 25.35047 -3.24993)
			(size 1.0668 1.0668)
			(drill 0.7112)
			(layers "*.Cu" "*.Mask")
			(remove_unused_layers no)
			(net "P3E_CPU0_PE2_SS_RXN<4>")
			(clearance 0.1778)
			(thermal_gap 0.1778)
		)
		(pad "A37" thru_hole circle
			(at 26.34996 -1.24968)
			(size 1.0668 1.0668)
			(drill 0.7112)
			(layers "*.Cu" "*.Mask")
			(remove_unused_layers no)
			(net "GND")
			(clearance 0.1778)
			(thermal_gap 0.1778)
		)
		(pad "A38" thru_hole circle
			(at 27.34945 -3.24993)
			(size 1.0668 1.0668)
			(drill 0.7112)
			(layers "*.Cu" "*.Mask")
			(remove_unused_layers no)
			(net "GND")
			(clearance 0.1778)
			(thermal_gap 0.1778)
		)
		(pad "A39" thru_hole circle
			(at 28.35021 -1.24968)
			(size 1.0668 1.0668)
			(drill 0.7112)
			(layers "*.Cu" "*.Mask")
			(remove_unused_layers no)
			(net "P3E_CPU0_PE2_SS_RXP<5>")
			(clearance 0.1778)
			(thermal_gap 0.1778)
		)
		(pad "A40" thru_hole circle
			(at 29.3497 -3.24993)
			(size 1.0668 1.0668)
			(drill 0.7112)
			(layers "*.Cu" "*.Mask")
			(remove_unused_layers no)
			(net "P3E_CPU0_PE2_SS_RXN<5>")
			(clearance 0.1778)
			(thermal_gap 0.1778)
		)
		(pad "A41" thru_hole circle
			(at 30.35046 -1.24968)
			(size 1.0668 1.0668)
			(drill 0.7112)
			(layers "*.Cu" "*.Mask")
			(remove_unused_layers no)
			(net "GND")
			(clearance 0.1778)
			(thermal_gap 0.1778)
		)
		(pad "A42" thru_hole circle
			(at 31.34995 -3.24993)
			(size 1.0668 1.0668)
			(drill 0.7112)
			(layers "*.Cu" "*.Mask")
			(remove_unused_layers no)
			(net "GND")
			(clearance 0.1778)
			(thermal_gap 0.1778)
		)
		(pad "A43" thru_hole circle
			(at 32.34944 -1.24968)
			(size 1.0668 1.0668)
			(drill 0.7112)
			(layers "*.Cu" "*.Mask")
			(remove_unused_layers no)
			(net "P3E_CPU0_PE2_SS_RXP<6>")
			(clearance 0.1778)
			(thermal_gap 0.1778)
		)
		(pad "A44" thru_hole circle
			(at 33.3502 -3.24993)
			(size 1.0668 1.0668)
			(drill 0.7112)
			(layers "*.Cu" "*.Mask")
			(remove_unused_layers no)
			(net "P3E_CPU0_PE2_SS_RXN<6>")
			(clearance 0.1778)
			(thermal_gap 0.1778)
		)
		(pad "A45" thru_hole circle
			(at 34.34969 -1.24968)
			(size 1.0668 1.0668)
			(drill 0.7112)
			(layers "*.Cu" "*.Mask")
			(remove_unused_layers no)
			(net "GND")
			(clearance 0.1778)
			(thermal_gap 0.1778)
		)
		(pad "A46" thru_hole circle
			(at 35.35045 -3.24993)
			(size 1.0668 1.0668)
			(drill 0.7112)
			(layers "*.Cu" "*.Mask")
			(remove_unused_layers no)
			(net "GND")
			(clearance 0.1778)
			(thermal_gap 0.1778)
		)
		(pad "A47" thru_hole circle
			(at 36.34994 -1.24968)
			(size 1.0668 1.0668)
			(drill 0.7112)
			(layers "*.Cu" "*.Mask")
			(remove_unused_layers no)
			(net "P3E_CPU0_PE2_SS_RXP<7>")
			(clearance 0.1778)
			(thermal_gap 0.1778)
		)
		(pad "A48" thru_hole circle
			(at 37.34943 -3.24993)
			(size 1.0668 1.0668)
			(drill 0.7112)
			(layers "*.Cu" "*.Mask")
			(remove_unused_layers no)
			(net "P3E_CPU0_PE2_SS_RXN<7>")
			(clearance 0.1778)
			(thermal_gap 0.1778)
		)
		(pad "A49" thru_hole circle
			(at 38.35019 -1.24968)
			(size 1.0668 1.0668)
			(drill 0.7112)
			(layers "*.Cu" "*.Mask")
			(remove_unused_layers no)
			(net "GND")
			(clearance 0.1778)
			(thermal_gap 0.1778)
		)
		(pad "A50" thru_hole circle
			(at 39.34968 -3.24993)
			(size 1.0668 1.0668)
			(drill 0.7112)
			(layers "*.Cu" "*.Mask")
			(remove_unused_layers no)
			(net "Net_91")
			(clearance 0.1778)
			(thermal_gap 0.1778)
		)
		(pad "A51" thru_hole circle
			(at 40.35044 -1.24968)
			(size 1.0668 1.0668)
			(drill 0.7112)
			(layers "*.Cu" "*.Mask")
			(remove_unused_layers no)
			(net "GND")
			(clearance 0.1778)
			(thermal_gap 0.1778)
		)
		(pad "A52" thru_hole circle
			(at 41.34993 -3.24993)
			(size 1.0668 1.0668)
			(drill 0.7112)
			(layers "*.Cu" "*.Mask")
			(remove_unused_layers no)
			(net "P3E_CPU0_PE2_SS_RXP<8>")
			(clearance 0.1778)
			(thermal_gap 0.1778)
		)
		(pad "A53" thru_hole circle
			(at 42.34942 -1.24968)
			(size 1.0668 1.0668)
			(drill 0.7112)
			(layers "*.Cu" "*.Mask")
			(remove_unused_layers no)
			(net "P3E_CPU0_PE2_SS_RXN<8>")
			(clearance 0.1778)
			(thermal_gap 0.1778)
		)
		(pad "A54" thru_hole circle
			(at 43.35018 -3.24993)
			(size 1.0668 1.0668)
			(drill 0.7112)
			(layers "*.Cu" "*.Mask")
			(remove_unused_layers no)
			(net "GND")
			(clearance 0.1778)
			(thermal_gap 0.1778)
		)
		(pad "A55" thru_hole circle
			(at 44.34967 -1.24968)
			(size 1.0668 1.0668)
			(drill 0.7112)
			(layers "*.Cu" "*.Mask")
			(remove_unused_layers no)
			(net "GND")
			(clearance 0.1778)
			(thermal_gap 0.1778)
		)
		(pad "A56" thru_hole circle
			(at 45.35043 -3.24993)
			(size 1.0668 1.0668)
			(drill 0.7112)
			(layers "*.Cu" "*.Mask")
			(remove_unused_layers no)
			(net "P3E_CPU0_PE2_SS_RXP<9>")
			(clearance 0.1778)
			(thermal_gap 0.1778)
		)
		(pad "A57" thru_hole circle
			(at 46.34992 -1.24968)
			(size 1.0668 1.0668)
			(drill 0.7112)
			(layers "*.Cu" "*.Mask")
			(remove_unused_layers no)
			(net "P3E_CPU0_PE2_SS_RXN<9>")
			(clearance 0.1778)
			(thermal_gap 0.1778)
		)
		(pad "A58" thru_hole circle
			(at 47.34941 -3.24993)
			(size 1.0668 1.0668)
			(drill 0.7112)
			(layers "*.Cu" "*.Mask")
			(remove_unused_layers no)
			(net "GND")
			(clearance 0.1778)
			(thermal_gap 0.1778)
		)
		(pad "A59" thru_hole circle
			(at 48.35017 -1.24968)
			(size 1.0668 1.0668)
			(drill 0.7112)
			(layers "*.Cu" "*.Mask")
			(remove_unused_layers no)
			(net "GND")
			(clearance 0.1778)
			(thermal_gap 0.1778)
		)
		(pad "A60" thru_hole circle
			(at 49.34966 -3.24993)
			(size 1.0668 1.0668)
			(drill 0.7112)
			(layers "*.Cu" "*.Mask")
			(remove_unused_layers no)
			(net "P3E_CPU0_PE2_SS_RXP<10>")
			(clearance 0.1778)
			(thermal_gap 0.1778)
		)
		(pad "A61" thru_hole circle
			(at 50.35042 -1.24968)
			(size 1.0668 1.0668)
			(drill 0.7112)
			(layers "*.Cu" "*.Mask")
			(remove_unused_layers no)
			(net "P3E_CPU0_PE2_SS_RXN<10>")
			(clearance 0.1778)
			(thermal_gap 0.1778)
		)
		(pad "A62" thru_hole circle
			(at 51.34991 -3.24993)
			(size 1.0668 1.0668)
			(drill 0.7112)
			(layers "*.Cu" "*.Mask")
			(remove_unused_layers no)
			(net "GND")
			(clearance 0.1778)
			(thermal_gap 0.1778)
		)
		(pad "A63" thru_hole circle
			(at 52.3494 -1.24968)
			(size 1.0668 1.0668)
			(drill 0.7112)
			(layers "*.Cu" "*.Mask")
			(remove_unused_layers no)
			(net "GND")
			(clearance 0.1778)
			(thermal_gap 0.1778)
		)
		(pad "A64" thru_hole circle
			(at 53.35016 -3.24993)
			(size 1.0668 1.0668)
			(drill 0.7112)
			(layers "*.Cu" "*.Mask")
			(remove_unused_layers no)
			(net "P3E_CPU0_PE2_SS_RXP<11>")
			(clearance 0.1778)
			(thermal_gap 0.1778)
		)
		(pad "A65" thru_hole circle
			(at 54.34965 -1.24968)
			(size 1.0668 1.0668)
			(drill 0.7112)
			(layers "*.Cu" "*.Mask")
			(remove_unused_layers no)
			(net "P3E_CPU0_PE2_SS_RXN<11>")
			(clearance 0.1778)
			(thermal_gap 0.1778)
		)
		(pad "A66" thru_hole circle
			(at 55.35041 -3.24993)
			(size 1.0668 1.0668)
			(drill 0.7112)
			(layers "*.Cu" "*.Mask")
			(remove_unused_layers no)
			(net "GND")
			(clearance 0.1778)
			(thermal_gap 0.1778)
		)
		(pad "A67" thru_hole circle
			(at 56.3499 -1.24968)
			(size 1.0668 1.0668)
			(drill 0.7112)
			(layers "*.Cu" "*.Mask")
			(remove_unused_layers no)
			(net "GND")
			(clearance 0.1778)
			(thermal_gap 0.1778)
		)
		(pad "A68" thru_hole circle
			(at 57.34939 -3.24993)
			(size 1.0668 1.0668)
			(drill 0.7112)
			(layers "*.Cu" "*.Mask")
			(remove_unused_layers no)
			(net "P3E_CPU0_PE2_SS_RXP<12>")
			(clearance 0.1778)
			(thermal_gap 0.1778)
		)
		(pad "A69" thru_hole circle
			(at 58.35015 -1.24968)
			(size 1.0668 1.0668)
			(drill 0.7112)
			(layers "*.Cu" "*.Mask")
			(remove_unused_layers no)
			(net "P3E_CPU0_PE2_SS_RXN<12>")
			(clearance 0.1778)
			(thermal_gap 0.1778)
		)
		(pad "A70" thru_hole circle
			(at 59.34964 -3.24993)
			(size 1.0668 1.0668)
			(drill 0.7112)
			(layers "*.Cu" "*.Mask")
			(remove_unused_layers no)
			(net "GND")
			(clearance 0.1778)
			(thermal_gap 0.1778)
		)
		(pad "A71" thru_hole circle
			(at 60.3504 -1.24968)
			(size 1.0668 1.0668)
			(drill 0.7112)
			(layers "*.Cu" "*.Mask")
			(remove_unused_layers no)
			(net "GND")
			(clearance 0.1778)
			(thermal_gap 0.1778)
		)
		(pad "A72" thru_hole circle
			(at 61.34989 -3.24993)
			(size 1.0668 1.0668)
			(drill 0.7112)
			(layers "*.Cu" "*.Mask")
			(remove_unused_layers no)
			(net "P3E_CPU0_PE2_SS_RXP<13>")
			(clearance 0.1778)
			(thermal_gap 0.1778)
		)
		(pad "A73" thru_hole circle
			(at 62.34938 -1.24968)
			(size 1.0668 1.0668)
			(drill 0.7112)
			(layers "*.Cu" "*.Mask")
			(remove_unused_layers no)
			(net "P3E_CPU0_PE2_SS_RXN<13>")
			(clearance 0.1778)
			(thermal_gap 0.1778)
		)
		(pad "A74" thru_hole circle
			(at 63.35014 -3.24993)
			(size 1.0668 1.0668)
			(drill 0.7112)
			(layers "*.Cu" "*.Mask")
			(remove_unused_layers no)
			(net "GND")
			(clearance 0.1778)
			(thermal_gap 0.1778)
		)
		(pad "A75" thru_hole circle
			(at 64.34963 -1.24968)
			(size 1.0668 1.0668)
			(drill 0.7112)
			(layers "*.Cu" "*.Mask")
			(remove_unused_layers no)
			(net "GND")
			(clearance 0.1778)
			(thermal_gap 0.1778)
		)
		(pad "A76" thru_hole circle
			(at 65.35039 -3.24993)
			(size 1.0668 1.0668)
			(drill 0.7112)
			(layers "*.Cu" "*.Mask")
			(remove_unused_layers no)
			(net "P3E_CPU0_PE2_SS_RXP<14>")
			(clearance 0.1778)
			(thermal_gap 0.1778)
		)
		(pad "A77" thru_hole circle
			(at 66.34988 -1.24968)
			(size 1.0668 1.0668)
			(drill 0.7112)
			(layers "*.Cu" "*.Mask")
			(remove_unused_layers no)
			(net "P3E_CPU0_PE2_SS_RXN<14>")
			(clearance 0.1778)
			(thermal_gap 0.1778)
		)
		(pad "A78" thru_hole circle
			(at 67.34937 -3.24993)
			(size 1.0668 1.0668)
			(drill 0.7112)
			(layers "*.Cu" "*.Mask")
			(remove_unused_layers no)
			(net "GND")
			(clearance 0.1778)
			(thermal_gap 0.1778)
		)
		(pad "A79" thru_hole circle
			(at 68.35013 -1.24968)
			(size 1.0668 1.0668)
			(drill 0.7112)
			(layers "*.Cu" "*.Mask")
			(remove_unused_layers no)
			(net "GND")
			(clearance 0.1778)
			(thermal_gap 0.1778)
		)
		(pad "A80" thru_hole circle
			(at 69.34962 -3.24993)
			(size 1.0668 1.0668)
			(drill 0.7112)
			(layers "*.Cu" "*.Mask")
			(remove_unused_layers no)
			(net "P3E_CPU0_PE2_SS_RXP<15>")
			(clearance 0.1778)
			(thermal_gap 0.1778)
		)
		(pad "A81" thru_hole circle
			(at 70.35038 -1.24968)
			(size 1.0668 1.0668)
			(drill 0.7112)
			(layers "*.Cu" "*.Mask")
			(remove_unused_layers no)
			(net "P3E_CPU0_PE2_SS_RXN<15>")
			(clearance 0.1778)
			(thermal_gap 0.1778)
		)
		(pad "A82" thru_hole circle
			(at 71.34987 -3.24993)
			(size 1.0668 1.0668)
			(drill 0.7112)
			(layers "*.Cu" "*.Mask")
			(remove_unused_layers no)
			(net "GND")
			(clearance 0.1778)
			(thermal_gap 0.1778)
		)
		(pad "B1" thru_hole circle
			(at -11.64971 1.24968)
			(size 1.0668 1.0668)
			(drill 0.7112)
			(layers "*.Cu" "*.Mask")
			(remove_unused_layers no)
			(net "P12V_SLOT3")
			(clearance 0.1778)
			(thermal_gap 0.1778)
		)
		(pad "B2" thru_hole circle
			(at -10.65022 3.24993)
			(size 1.0668 1.0668)
			(drill 0.7112)
			(layers "*.Cu" "*.Mask")
			(remove_unused_layers no)
			(net "P12V_SLOT3")
			(clearance 0.1778)
			(thermal_gap 0.1778)
		)
		(pad "B3" thru_hole circle
			(at -9.64946 1.24968)
			(size 1.0668 1.0668)
			(drill 0.7112)
			(layers "*.Cu" "*.Mask")
			(remove_unused_layers no)
			(net "P12V_SLOT3")
			(clearance 0.1778)
			(thermal_gap 0.1778)
		)
		(pad "B4" thru_hole circle
			(at -8.64997 3.24993)
			(size 1.0668 1.0668)
			(drill 0.7112)
			(layers "*.Cu" "*.Mask")
			(remove_unused_layers no)
			(net "GND")
			(clearance 0.1778)
			(thermal_gap 0.1778)
		)
		(pad "B5" thru_hole circle
			(at -7.65048 1.24968)
			(size 1.0668 1.0668)
			(drill 0.7112)
			(layers "*.Cu" "*.Mask")
			(remove_unused_layers no)
			(net "SMCLK_BMC_SLOT3_R")
			(clearance 0.1778)
			(thermal_gap 0.1778)
		)
		(pad "B6" thru_hole circle
			(at -6.64972 3.24993)
			(size 1.0668 1.0668)
			(drill 0.7112)
			(layers "*.Cu" "*.Mask")
			(remove_unused_layers no)
			(net "SMDAT_BMC_SLOT3_R")
			(clearance 0.1778)
			(thermal_gap 0.1778)
		)
		(pad "B7" thru_hole circle
			(at -5.65023 1.24968)
			(size 1.0668 1.0668)
			(drill 0.7112)
			(layers "*.Cu" "*.Mask")
			(remove_unused_layers no)
			(net "GND")
			(clearance 0.1778)
			(thermal_gap 0.1778)
		)
		(pad "B8" thru_hole circle
			(at -4.64947 3.24993)
			(size 1.0668 1.0668)
			(drill 0.7112)
			(layers "*.Cu" "*.Mask")
			(remove_unused_layers no)
			(net "P3V3")
			(clearance 0.1778)
			(thermal_gap 0.1778)
		)
		(pad "B9" thru_hole circle
			(at -3.64998 1.24968)
			(size 1.0668 1.0668)
			(drill 0.7112)
			(layers "*.Cu" "*.Mask")
			(remove_unused_layers no)
			(net "Net_94")
			(clearance 0.1778)
			(thermal_gap 0.1778)
		)
		(pad "B10" thru_hole circle
			(at -2.65049 3.24993)
			(size 1.0668 1.0668)
			(drill 0.7112)
			(layers "*.Cu" "*.Mask")
			(remove_unused_layers no)
			(net "P3V3_STBY")
			(clearance 0.1778)
			(thermal_gap 0.1778)
		)
		(pad "B11" thru_hole circle
			(at -1.64973 1.24968)
			(size 1.0668 1.0668)
			(drill 0.7112)
			(layers "*.Cu" "*.Mask")
			(remove_unused_layers no)
			(net "FM_PE_SLOTX24_WAKE_N")
			(clearance 0.1778)
			(thermal_gap 0.1778)
		)
		(pad "B12" thru_hole circle
			(at 1.35001 3.24993)
			(size 1.0668 1.0668)
			(drill 0.7112)
			(layers "*.Cu" "*.Mask")
			(remove_unused_layers no)
			(net "SMB_ALERT_S3_B12_N")
			(clearance 0.1778)
			(thermal_gap 0.1778)
		)
		(pad "B13" thru_hole circle
			(at 2.3495 1.24968)
			(size 1.0668 1.0668)
			(drill 0.7112)
			(layers "*.Cu" "*.Mask")
			(remove_unused_layers no)
			(net "GND")
			(clearance 0.1778)
			(thermal_gap 0.1778)
		)
		(pad "B14" thru_hole circle
			(at 3.35026 3.24993)
			(size 1.0668 1.0668)
			(drill 0.7112)
			(layers "*.Cu" "*.Mask")
			(remove_unused_layers no)
			(net "P3E_CPU0_PE2_SS_C_TXP<0>")
			(clearance 0.1778)
			(thermal_gap 0.1778)
		)
		(pad "B15" thru_hole circle
			(at 4.34975 1.24968)
			(size 1.0668 1.0668)
			(drill 0.7112)
			(layers "*.Cu" "*.Mask")
			(remove_unused_layers no)
			(net "P3E_CPU0_PE2_SS_C_TXN<0>")
			(clearance 0.1778)
			(thermal_gap 0.1778)
		)
		(pad "B16" thru_hole circle
			(at 5.35051 3.24993)
			(size 1.0668 1.0668)
			(drill 0.7112)
			(layers "*.Cu" "*.Mask")
			(remove_unused_layers no)
			(net "GND")
			(clearance 0.1778)
			(thermal_gap 0.1778)
		)
		(pad "B17" thru_hole circle
			(at 6.35 1.24968)
			(size 1.0668 1.0668)
			(drill 0.7112)
			(layers "*.Cu" "*.Mask")
			(remove_unused_layers no)
			(net "PCIE_SLOT3_PRSNT2_1_N")
			(clearance 0.1778)
			(thermal_gap 0.1778)
		)
		(pad "B18" thru_hole circle
			(at 7.34949 3.24993)
			(size 1.0668 1.0668)
			(drill 0.7112)
			(layers "*.Cu" "*.Mask")
			(remove_unused_layers no)
			(net "GND")
			(clearance 0.1778)
			(thermal_gap 0.1778)
		)
		(pad "B19" thru_hole circle
			(at 8.35025 1.24968)
			(size 1.0668 1.0668)
			(drill 0.7112)
			(layers "*.Cu" "*.Mask")
			(remove_unused_layers no)
			(net "P3E_CPU0_PE2_SS_C_TXP<1>")
			(clearance 0.1778)
			(thermal_gap 0.1778)
		)
		(pad "B20" thru_hole circle
			(at 9.34974 3.24993)
			(size 1.0668 1.0668)
			(drill 0.7112)
			(layers "*.Cu" "*.Mask")
			(remove_unused_layers no)
			(net "P3E_CPU0_PE2_SS_C_TXN<1>")
			(clearance 0.1778)
			(thermal_gap 0.1778)
		)
		(pad "B21" thru_hole circle
			(at 10.3505 1.24968)
			(size 1.0668 1.0668)
			(drill 0.7112)
			(layers "*.Cu" "*.Mask")
			(remove_unused_layers no)
			(net "GND")
			(clearance 0.1778)
			(thermal_gap 0.1778)
		)
		(pad "B22" thru_hole circle
			(at 11.34999 3.24993)
			(size 1.0668 1.0668)
			(drill 0.7112)
			(layers "*.Cu" "*.Mask")
			(remove_unused_layers no)
			(net "GND")
			(clearance 0.1778)
			(thermal_gap 0.1778)
		)
		(pad "B23" thru_hole circle
			(at 12.34948 1.24968)
			(size 1.0668 1.0668)
			(drill 0.7112)
			(layers "*.Cu" "*.Mask")
			(remove_unused_layers no)
			(net "P3E_CPU0_PE2_SS_C_TXP<2>")
			(clearance 0.1778)
			(thermal_gap 0.1778)
		)
		(pad "B24" thru_hole circle
			(at 13.35024 3.24993)
			(size 1.0668 1.0668)
			(drill 0.7112)
			(layers "*.Cu" "*.Mask")
			(remove_unused_layers no)
			(net "P3E_CPU0_PE2_SS_C_TXN<2>")
			(clearance 0.1778)
			(thermal_gap 0.1778)
		)
		(pad "B25" thru_hole circle
			(at 14.34973 1.24968)
			(size 1.0668 1.0668)
			(drill 0.7112)
			(layers "*.Cu" "*.Mask")
			(remove_unused_layers no)
			(net "GND")
			(clearance 0.1778)
			(thermal_gap 0.1778)
		)
		(pad "B26" thru_hole circle
			(at 15.35049 3.24993)
			(size 1.0668 1.0668)
			(drill 0.7112)
			(layers "*.Cu" "*.Mask")
			(remove_unused_layers no)
			(net "GND")
			(clearance 0.1778)
			(thermal_gap 0.1778)
		)
		(pad "B27" thru_hole circle
			(at 16.34998 1.24968)
			(size 1.0668 1.0668)
			(drill 0.7112)
			(layers "*.Cu" "*.Mask")
			(remove_unused_layers no)
			(net "P3E_CPU0_PE2_SS_C_TXP<3>")
			(clearance 0.1778)
			(thermal_gap 0.1778)
		)
		(pad "B28" thru_hole circle
			(at 17.34947 3.24993)
			(size 1.0668 1.0668)
			(drill 0.7112)
			(layers "*.Cu" "*.Mask")
			(remove_unused_layers no)
			(net "P3E_CPU0_PE2_SS_C_TXN<3>")
			(clearance 0.1778)
			(thermal_gap 0.1778)
		)
		(pad "B29" thru_hole circle
			(at 18.35023 1.24968)
			(size 1.0668 1.0668)
			(drill 0.7112)
			(layers "*.Cu" "*.Mask")
			(remove_unused_layers no)
			(net "GND")
			(clearance 0.1778)
			(thermal_gap 0.1778)
		)
		(pad "B30" thru_hole circle
			(at 19.34972 3.24993)
			(size 1.0668 1.0668)
			(drill 0.7112)
			(layers "*.Cu" "*.Mask")
			(remove_unused_layers no)
			(net "FM_PWRBRK_SLOT_N")
			(clearance 0.1778)
			(thermal_gap 0.1778)
		)
		(pad "B31" thru_hole circle
			(at 20.35048 1.24968)
			(size 1.0668 1.0668)
			(drill 0.7112)
			(layers "*.Cu" "*.Mask")
			(remove_unused_layers no)
			(net "PCIE_SLOT3_PRSNT2_2_N")
			(clearance 0.1778)
			(thermal_gap 0.1778)
		)
		(pad "B32" thru_hole circle
			(at 21.34997 3.24993)
			(size 1.0668 1.0668)
			(drill 0.7112)
			(layers "*.Cu" "*.Mask")
			(remove_unused_layers no)
			(net "GND")
			(clearance 0.1778)
			(thermal_gap 0.1778)
		)
		(pad "B33" thru_hole circle
			(at 22.34946 1.24968)
			(size 1.0668 1.0668)
			(drill 0.7112)
			(layers "*.Cu" "*.Mask")
			(remove_unused_layers no)
			(net "P3E_CPU0_PE2_SS_C_TXP<4>")
			(clearance 0.1778)
			(thermal_gap 0.1778)
		)
		(pad "B34" thru_hole circle
			(at 23.35022 3.24993)
			(size 1.0668 1.0668)
			(drill 0.7112)
			(layers "*.Cu" "*.Mask")
			(remove_unused_layers no)
			(net "P3E_CPU0_PE2_SS_C_TXN<4>")
			(clearance 0.1778)
			(thermal_gap 0.1778)
		)
		(pad "B35" thru_hole circle
			(at 24.34971 1.24968)
			(size 1.0668 1.0668)
			(drill 0.7112)
			(layers "*.Cu" "*.Mask")
			(remove_unused_layers no)
			(net "GND")
			(clearance 0.1778)
			(thermal_gap 0.1778)
		)
		(pad "B36" thru_hole circle
			(at 25.35047 3.24993)
			(size 1.0668 1.0668)
			(drill 0.7112)
			(layers "*.Cu" "*.Mask")
			(remove_unused_layers no)
			(net "GND")
			(clearance 0.1778)
			(thermal_gap 0.1778)
		)
		(pad "B37" thru_hole circle
			(at 26.34996 1.24968)
			(size 1.0668 1.0668)
			(drill 0.7112)
			(layers "*.Cu" "*.Mask")
			(remove_unused_layers no)
			(net "P3E_CPU0_PE2_SS_C_TXP<5>")
			(clearance 0.1778)
			(thermal_gap 0.1778)
		)
		(pad "B38" thru_hole circle
			(at 27.34945 3.24993)
			(size 1.0668 1.0668)
			(drill 0.7112)
			(layers "*.Cu" "*.Mask")
			(remove_unused_layers no)
			(net "P3E_CPU0_PE2_SS_C_TXN<5>")
			(clearance 0.1778)
			(thermal_gap 0.1778)
		)
		(pad "B39" thru_hole circle
			(at 28.35021 1.24968)
			(size 1.0668 1.0668)
			(drill 0.7112)
			(layers "*.Cu" "*.Mask")
			(remove_unused_layers no)
			(net "GND")
			(clearance 0.1778)
			(thermal_gap 0.1778)
		)
		(pad "B40" thru_hole circle
			(at 29.3497 3.24993)
			(size 1.0668 1.0668)
			(drill 0.7112)
			(layers "*.Cu" "*.Mask")
			(remove_unused_layers no)
			(net "GND")
			(clearance 0.1778)
			(thermal_gap 0.1778)
		)
		(pad "B41" thru_hole circle
			(at 30.35046 1.24968)
			(size 1.0668 1.0668)
			(drill 0.7112)
			(layers "*.Cu" "*.Mask")
			(remove_unused_layers no)
			(net "P3E_CPU0_PE2_SS_C_TXP<6>")
			(clearance 0.1778)
			(thermal_gap 0.1778)
		)
		(pad "B42" thru_hole circle
			(at 31.34995 3.24993)
			(size 1.0668 1.0668)
			(drill 0.7112)
			(layers "*.Cu" "*.Mask")
			(remove_unused_layers no)
			(net "P3E_CPU0_PE2_SS_C_TXN<6>")
			(clearance 0.1778)
			(thermal_gap 0.1778)
		)
		(pad "B43" thru_hole circle
			(at 32.34944 1.24968)
			(size 1.0668 1.0668)
			(drill 0.7112)
			(layers "*.Cu" "*.Mask")
			(remove_unused_layers no)
			(net "GND")
			(clearance 0.1778)
			(thermal_gap 0.1778)
		)
		(pad "B44" thru_hole circle
			(at 33.3502 3.24993)
			(size 1.0668 1.0668)
			(drill 0.7112)
			(layers "*.Cu" "*.Mask")
			(remove_unused_layers no)
			(net "GND")
			(clearance 0.1778)
			(thermal_gap 0.1778)
		)
		(pad "B45" thru_hole circle
			(at 34.34969 1.24968)
			(size 1.0668 1.0668)
			(drill 0.7112)
			(layers "*.Cu" "*.Mask")
			(remove_unused_layers no)
			(net "P3E_CPU0_PE2_SS_C_TXP<7>")
			(clearance 0.1778)
			(thermal_gap 0.1778)
		)
		(pad "B46" thru_hole circle
			(at 35.35045 3.24993)
			(size 1.0668 1.0668)
			(drill 0.7112)
			(layers "*.Cu" "*.Mask")
			(remove_unused_layers no)
			(net "P3E_CPU0_PE2_SS_C_TXN<7>")
			(clearance 0.1778)
			(thermal_gap 0.1778)
		)
		(pad "B47" thru_hole circle
			(at 36.34994 1.24968)
			(size 1.0668 1.0668)
			(drill 0.7112)
			(layers "*.Cu" "*.Mask")
			(remove_unused_layers no)
			(net "GND")
			(clearance 0.1778)
			(thermal_gap 0.1778)
		)
		(pad "B48" thru_hole circle
			(at 37.34943 3.24993)
			(size 1.0668 1.0668)
			(drill 0.7112)
			(layers "*.Cu" "*.Mask")
			(remove_unused_layers no)
			(net "PCIE_SLOT3_PRSNT2_3_N")
			(clearance 0.1778)
			(thermal_gap 0.1778)
		)
		(pad "B49" thru_hole circle
			(at 38.35019 1.24968)
			(size 1.0668 1.0668)
			(drill 0.7112)
			(layers "*.Cu" "*.Mask")
			(remove_unused_layers no)
			(net "GND")
			(clearance 0.1778)
			(thermal_gap 0.1778)
		)
		(pad "B50" thru_hole circle
			(at 39.34968 3.24993)
			(size 1.0668 1.0668)
			(drill 0.7112)
			(layers "*.Cu" "*.Mask")
			(remove_unused_layers no)
			(net "P3E_CPU0_PE2_SS_C_TXP<8>")
			(clearance 0.1778)
			(thermal_gap 0.1778)
		)
		(pad "B51" thru_hole circle
			(at 40.35044 1.24968)
			(size 1.0668 1.0668)
			(drill 0.7112)
			(layers "*.Cu" "*.Mask")
			(remove_unused_layers no)
			(net "P3E_CPU0_PE2_SS_C_TXN<8>")
			(clearance 0.1778)
			(thermal_gap 0.1778)
		)
		(pad "B52" thru_hole circle
			(at 41.34993 3.24993)
			(size 1.0668 1.0668)
			(drill 0.7112)
			(layers "*.Cu" "*.Mask")
			(remove_unused_layers no)
			(net "GND")
			(clearance 0.1778)
			(thermal_gap 0.1778)
		)
		(pad "B53" thru_hole circle
			(at 42.34942 1.24968)
			(size 1.0668 1.0668)
			(drill 0.7112)
			(layers "*.Cu" "*.Mask")
			(remove_unused_layers no)
			(net "GND")
			(clearance 0.1778)
			(thermal_gap 0.1778)
		)
		(pad "B54" thru_hole circle
			(at 43.35018 3.24993)
			(size 1.0668 1.0668)
			(drill 0.7112)
			(layers "*.Cu" "*.Mask")
			(remove_unused_layers no)
			(net "P3E_CPU0_PE2_SS_C_TXP<9>")
			(clearance 0.1778)
			(thermal_gap 0.1778)
		)
		(pad "B55" thru_hole circle
			(at 44.34967 1.24968)
			(size 1.0668 1.0668)
			(drill 0.7112)
			(layers "*.Cu" "*.Mask")
			(remove_unused_layers no)
			(net "P3E_CPU0_PE2_SS_C_TXN<9>")
			(clearance 0.1778)
			(thermal_gap 0.1778)
		)
		(pad "B56" thru_hole circle
			(at 45.35043 3.24993)
			(size 1.0668 1.0668)
			(drill 0.7112)
			(layers "*.Cu" "*.Mask")
			(remove_unused_layers no)
			(net "GND")
			(clearance 0.1778)
			(thermal_gap 0.1778)
		)
		(pad "B57" thru_hole circle
			(at 46.34992 1.24968)
			(size 1.0668 1.0668)
			(drill 0.7112)
			(layers "*.Cu" "*.Mask")
			(remove_unused_layers no)
			(net "GND")
			(clearance 0.1778)
			(thermal_gap 0.1778)
		)
		(pad "B58" thru_hole circle
			(at 47.34941 3.24993)
			(size 1.0668 1.0668)
			(drill 0.7112)
			(layers "*.Cu" "*.Mask")
			(remove_unused_layers no)
			(net "P3E_CPU0_PE2_SS_C_TXP<10>")
			(clearance 0.1778)
			(thermal_gap 0.1778)
		)
		(pad "B59" thru_hole circle
			(at 48.35017 1.24968)
			(size 1.0668 1.0668)
			(drill 0.7112)
			(layers "*.Cu" "*.Mask")
			(remove_unused_layers no)
			(net "P3E_CPU0_PE2_SS_C_TXN<10>")
			(clearance 0.1778)
			(thermal_gap 0.1778)
		)
		(pad "B60" thru_hole circle
			(at 49.34966 3.24993)
			(size 1.0668 1.0668)
			(drill 0.7112)
			(layers "*.Cu" "*.Mask")
			(remove_unused_layers no)
			(net "GND")
			(clearance 0.1778)
			(thermal_gap 0.1778)
		)
		(pad "B61" thru_hole circle
			(at 50.35042 1.24968)
			(size 1.0668 1.0668)
			(drill 0.7112)
			(layers "*.Cu" "*.Mask")
			(remove_unused_layers no)
			(net "GND")
			(clearance 0.1778)
			(thermal_gap 0.1778)
		)
		(pad "B62" thru_hole circle
			(at 51.34991 3.24993)
			(size 1.0668 1.0668)
			(drill 0.7112)
			(layers "*.Cu" "*.Mask")
			(remove_unused_layers no)
			(net "P3E_CPU0_PE2_SS_C_TXP<11>")
			(clearance 0.1778)
			(thermal_gap 0.1778)
		)
		(pad "B63" thru_hole circle
			(at 52.3494 1.24968)
			(size 1.0668 1.0668)
			(drill 0.7112)
			(layers "*.Cu" "*.Mask")
			(remove_unused_layers no)
			(net "P3E_CPU0_PE2_SS_C_TXN<11>")
			(clearance 0.1778)
			(thermal_gap 0.1778)
		)
		(pad "B64" thru_hole circle
			(at 53.35016 3.24993)
			(size 1.0668 1.0668)
			(drill 0.7112)
			(layers "*.Cu" "*.Mask")
			(remove_unused_layers no)
			(net "GND")
			(clearance 0.1778)
			(thermal_gap 0.1778)
		)
		(pad "B65" thru_hole circle
			(at 54.34965 1.24968)
			(size 1.0668 1.0668)
			(drill 0.7112)
			(layers "*.Cu" "*.Mask")
			(remove_unused_layers no)
			(net "GND")
			(clearance 0.1778)
			(thermal_gap 0.1778)
		)
		(pad "B66" thru_hole circle
			(at 55.35041 3.24993)
			(size 1.0668 1.0668)
			(drill 0.7112)
			(layers "*.Cu" "*.Mask")
			(remove_unused_layers no)
			(net "P3E_CPU0_PE2_SS_C_TXP<12>")
			(clearance 0.1778)
			(thermal_gap 0.1778)
		)
		(pad "B67" thru_hole circle
			(at 56.3499 1.24968)
			(size 1.0668 1.0668)
			(drill 0.7112)
			(layers "*.Cu" "*.Mask")
			(remove_unused_layers no)
			(net "P3E_CPU0_PE2_SS_C_TXN<12>")
			(clearance 0.1778)
			(thermal_gap 0.1778)
		)
		(pad "B68" thru_hole circle
			(at 57.34939 3.24993)
			(size 1.0668 1.0668)
			(drill 0.7112)
			(layers "*.Cu" "*.Mask")
			(remove_unused_layers no)
			(net "GND")
			(clearance 0.1778)
			(thermal_gap 0.1778)
		)
		(pad "B69" thru_hole circle
			(at 58.35015 1.24968)
			(size 1.0668 1.0668)
			(drill 0.7112)
			(layers "*.Cu" "*.Mask")
			(remove_unused_layers no)
			(net "GND")
			(clearance 0.1778)
			(thermal_gap 0.1778)
		)
		(pad "B70" thru_hole circle
			(at 59.34964 3.24993)
			(size 1.0668 1.0668)
			(drill 0.7112)
			(layers "*.Cu" "*.Mask")
			(remove_unused_layers no)
			(net "P3E_CPU0_PE2_SS_C_TXP<13>")
			(clearance 0.1778)
			(thermal_gap 0.1778)
		)
		(pad "B71" thru_hole circle
			(at 60.3504 1.24968)
			(size 1.0668 1.0668)
			(drill 0.7112)
			(layers "*.Cu" "*.Mask")
			(remove_unused_layers no)
			(net "P3E_CPU0_PE2_SS_C_TXN<13>")
			(clearance 0.1778)
			(thermal_gap 0.1778)
		)
		(pad "B72" thru_hole circle
			(at 61.34989 3.24993)
			(size 1.0668 1.0668)
			(drill 0.7112)
			(layers "*.Cu" "*.Mask")
			(remove_unused_layers no)
			(net "GND")
			(clearance 0.1778)
			(thermal_gap 0.1778)
		)
		(pad "B73" thru_hole circle
			(at 62.34938 1.24968)
			(size 1.0668 1.0668)
			(drill 0.7112)
			(layers "*.Cu" "*.Mask")
			(remove_unused_layers no)
			(net "GND")
			(clearance 0.1778)
			(thermal_gap 0.1778)
		)
		(pad "B74" thru_hole circle
			(at 63.35014 3.24993)
			(size 1.0668 1.0668)
			(drill 0.7112)
			(layers "*.Cu" "*.Mask")
			(remove_unused_layers no)
			(net "P3E_CPU0_PE2_SS_C_TXP<14>")
			(clearance 0.1778)
			(thermal_gap 0.1778)
		)
		(pad "B75" thru_hole circle
			(at 64.34963 1.24968)
			(size 1.0668 1.0668)
			(drill 0.7112)
			(layers "*.Cu" "*.Mask")
			(remove_unused_layers no)
			(net "P3E_CPU0_PE2_SS_C_TXN<14>")
			(clearance 0.1778)
			(thermal_gap 0.1778)
		)
		(pad "B76" thru_hole circle
			(at 65.35039 3.24993)
			(size 1.0668 1.0668)
			(drill 0.7112)
			(layers "*.Cu" "*.Mask")
			(remove_unused_layers no)
			(net "GND")
			(clearance 0.1778)
			(thermal_gap 0.1778)
		)
		(pad "B77" thru_hole circle
			(at 66.34988 1.24968)
			(size 1.0668 1.0668)
			(drill 0.7112)
			(layers "*.Cu" "*.Mask")
			(remove_unused_layers no)
			(net "GND")
			(clearance 0.1778)
			(thermal_gap 0.1778)
		)
		(pad "B78" thru_hole circle
			(at 67.34937 3.24993)
			(size 1.0668 1.0668)
			(drill 0.7112)
			(layers "*.Cu" "*.Mask")
			(remove_unused_layers no)
			(net "P3E_CPU0_PE2_SS_C_TXP<15>")
			(clearance 0.1778)
			(thermal_gap 0.1778)
		)
		(pad "B79" thru_hole circle
			(at 68.35013 1.24968)
			(size 1.0668 1.0668)
			(drill 0.7112)
			(layers "*.Cu" "*.Mask")
			(remove_unused_layers no)
			(net "P3E_CPU0_PE2_SS_C_TXN<15>")
			(clearance 0.1778)
			(thermal_gap 0.1778)
		)
		(pad "B80" thru_hole circle
			(at 69.34962 3.24993)
			(size 1.0668 1.0668)
			(drill 0.7112)
			(layers "*.Cu" "*.Mask")
			(remove_unused_layers no)
			(net "GND")
			(clearance 0.1778)
			(thermal_gap 0.1778)
		)
		(pad "B81" thru_hole circle
			(at 70.35038 1.24968)
			(size 1.0668 1.0668)
			(drill 0.7112)
			(layers "*.Cu" "*.Mask")
			(remove_unused_layers no)
			(net "PCIE_SLOT3_PRSNT2_4_N")
			(clearance 0.1778)
			(thermal_gap 0.1778)
		)
		(pad "B82" thru_hole circle
			(at 71.34987 3.24993)
			(size 1.0668 1.0668)
			(drill 0.7112)
			(layers "*.Cu" "*.Mask")
			(remove_unused_layers no)
			(net "TP_RSVD_SLOT3_PIN82")
			(clearance 0.1778)
			(thermal_gap 0.1778)
		)
		(zone
			(layers "F.Cu" "B.Cu" "In1.Cu" "In2.Cu" "In3.Cu" "In4.Cu")
			(hatch none 0.5)
			(connect_pads
				(clearance 0)
			)
			(min_thickness 0.25)
			(keepout
				(tracks not_allowed)
				(vias allowed)
				(pads allowed)
				(copperpour not_allowed)
				(footprints allowed)
			)
			(placement
				(enabled no)
				(sheetname "")
			)
			(fill
				(thermal_gap 0.5)
				(thermal_bridge_width 0.5)
				(island_removal_mode 0)
			)
			(polygon
				(pts
					(arc
						(start 44.215812 -30.820106)
						(mid 41.244012 -30.820106)
						(end 44.215812 -30.820106)
					)
				)
			)
		)
		(zone
			(layers "F.Cu" "B.Cu" "In1.Cu" "In2.Cu" "In3.Cu" "In4.Cu")
			(hatch none 0.5)
			(connect_pads
				(clearance 0)
			)
			(min_thickness 0.25)
			(keepout
				(tracks not_allowed)
				(vias allowed)
				(pads allowed)
				(copperpour not_allowed)
				(footprints allowed)
			)
			(placement
				(enabled no)
				(sheetname "")
			)
			(fill
				(thermal_gap 0.5)
				(thermal_bridge_width 0.5)
				(island_removal_mode 0)
			)
			(polygon
				(pts
					(arc
						(start 117.365272 -30.820106)
						(mid 114.393472 -30.820106)
						(end 117.365272 -30.820106)
					)
				)
			)
		)
	)
	(footprint ""
		(layer "F.Cu")
		(at 93.5482 -19.9136 90)
		(property "Reference" "C34"
			(at 0 0 90)
			(layer "F.SilkS")
			(hide yes)
			(effects
				(font
					(size 1.27 1.27)
				)
			)
		)
		(property "Value" "SCD1U16V2KX-3GP"
			(at 1.1811 -2.7051 90)
			(unlocked yes)
			(layer "F.Fab")
			(hide yes)
			(effects
				(font
					(size 1.016 1.016)
					(thickness 0.1524)
				)
			)
		)
		(property "Device Type" "C402H22"
			(at 1.1811 -4.2291 90)
			(unlocked yes)
			(layer "F.Fab")
			(hide yes)
			(effects
				(font
					(size 1.016 1.016)
					(thickness 0.1524)
				)
			)
		)
		(duplicate_pad_numbers_are_jumpers no)
		(fp_rect
			(start -0.4318 0.9525)
			(end 0.4318 -0.9525)
			(stroke
				(width 0)
				(type default)
			)
			(fill no)
			(layer "F.CrtYd")
		)
		(fp_rect
			(start -0.4318 0.9525)
			(end 0.4318 -0.9525)
			(stroke
				(width 0)
				(type default)
			)
			(fill no)
			(layer "F.Fab")
		)
		(pad "1" smd custom
			(at 0 -0.4445 90)
			(size 0.1524 0.1524)
			(layers "F.Cu" "F.Mask" "F.Paste")
			(net "P3V3_STBY")
			(options
				(clearance outline)
				(anchor circle)
			)
			(primitives
				(gr_poly
					(pts
						(arc
							(start 0.3048 -0.2032)
							(mid 0.275042 -0.275042)
							(end 0.2032 -0.3048)
						)
						(arc
							(start -0.2032 -0.3048)
							(mid -0.275042 -0.275042)
							(end -0.3048 -0.2032)
						)
						(arc
							(start -0.3048 0.2032)
							(mid -0.275042 0.275042)
							(end -0.2032 0.3048)
						)
						(arc
							(start 0.2032 0.3048)
							(mid 0.275042 0.275042)
							(end 0.3048 0.2032)
						)
					)
					(width 0)
					(fill yes)
				)
			)
		)
		(pad "2" smd custom
			(at 0 0.4445 90)
			(size 0.1524 0.1524)
			(layers "F.Cu" "F.Mask" "F.Paste")
			(net "GND")
			(options
				(clearance outline)
				(anchor circle)
			)
			(primitives
				(gr_poly
					(pts
						(arc
							(start 0.3048 -0.2032)
							(mid 0.275042 -0.275042)
							(end 0.2032 -0.3048)
						)
						(arc
							(start -0.2032 -0.3048)
							(mid -0.275042 -0.275042)
							(end -0.3048 -0.2032)
						)
						(arc
							(start -0.3048 0.2032)
							(mid -0.275042 0.275042)
							(end -0.2032 0.3048)
						)
						(arc
							(start 0.2032 0.3048)
							(mid 0.275042 0.275042)
							(end 0.3048 0.2032)
						)
					)
					(width 0)
					(fill yes)
				)
			)
		)
	)
	(footprint ""
		(layer "F.Cu")
		(at 56.2864 -15.9004 -90)
		(property "Reference" "R45"
			(at 0 0 270)
			(layer "F.SilkS")
			(hide yes)
			(effects
				(font
					(size 1.27 1.27)
				)
			)
		)
		(property "Value" "4K7R2F-GP"
			(at 0.064008 -3.993896 270)
			(unlocked yes)
			(layer "F.Fab")
			(hide yes)
			(effects
				(font
					(size 1.016 1.016)
					(thickness 0.1524)
				)
			)
		)
		(property "Device Type" "R402H16"
			(at 0.064008 -5.517896 270)
			(unlocked yes)
			(layer "F.Fab")
			(hide yes)
			(effects
				(font
					(size 1.016 1.016)
					(thickness 0.1524)
				)
			)
		)
		(duplicate_pad_numbers_are_jumpers no)
		(fp_line
			(start -0.508 -0.9398)
			(end -0.508 0.9398)
			(stroke
				(width 0.1524)
				(type default)
			)
			(layer "F.SilkS")
		)
		(fp_line
			(start 0.508 -0.9398)
			(end -0.508 -0.9398)
			(stroke
				(width 0.1524)
				(type default)
			)
			(layer "F.SilkS")
		)
		(fp_rect
			(start -0.508 0.9398)
			(end 0.508 -0.9398)
			(stroke
				(width 0)
				(type default)
			)
			(fill no)
			(layer "F.CrtYd")
		)
		(fp_rect
			(start -0.508 0.9398)
			(end 0.508 -0.9398)
			(stroke
				(width 0)
				(type default)
			)
			(fill no)
			(layer "F.Fab")
		)
		(pad "1" smd custom
			(at 0 -0.4445 270)
			(size 0.1397 0.1397)
			(layers "F.Cu" "F.Mask" "F.Paste")
			(net "P3V3_STBY")
			(options
				(clearance outline)
				(anchor circle)
			)
			(primitives
				(gr_poly
					(pts
						(arc
							(start -0.1778 -0.2794)
							(mid -0.249642 -0.249642)
							(end -0.2794 -0.1778)
						)
						(arc
							(start -0.2794 0.1778)
							(mid -0.249642 0.249642)
							(end -0.1778 0.2794)
						)
						(arc
							(start 0.1778 0.2794)
							(mid 0.249642 0.249642)
							(end 0.2794 0.1778)
						)
						(arc
							(start 0.2794 -0.1778)
							(mid 0.249642 -0.249642)
							(end 0.1778 -0.2794)
						)
					)
					(width 0)
					(fill yes)
				)
			)
		)
		(pad "2" smd custom
			(at 0 0.4445 270)
			(size 0.1397 0.1397)
			(layers "F.Cu" "F.Mask" "F.Paste")
			(net "PCIE_SLOT2_PRSNT2_1_N")
			(options
				(clearance outline)
				(anchor circle)
			)
			(primitives
				(gr_poly
					(pts
						(arc
							(start -0.1778 -0.2794)
							(mid -0.249642 -0.249642)
							(end -0.2794 -0.1778)
						)
						(arc
							(start -0.2794 0.1778)
							(mid -0.249642 0.249642)
							(end -0.1778 0.2794)
						)
						(arc
							(start 0.1778 0.2794)
							(mid 0.249642 0.249642)
							(end 0.2794 0.1778)
						)
						(arc
							(start 0.2794 -0.1778)
							(mid 0.249642 -0.249642)
							(end 0.1778 -0.2794)
						)
					)
					(width 0)
					(fill yes)
				)
			)
		)
	)
	(footprint ""
		(layer "F.Cu")
		(at 26.5176 -27.686 -90)
		(property "Reference" "R94"
			(at 0 0 270)
			(layer "F.SilkS")
			(hide yes)
			(effects
				(font
					(size 1.27 1.27)
				)
			)
		)
		(property "Value" "10KR2F-2-GP"
			(at 0.064008 -3.993896 270)
			(unlocked yes)
			(layer "F.Fab")
			(hide yes)
			(effects
				(font
					(size 1.016 1.016)
					(thickness 0.1524)
				)
			)
		)
		(property "Device Type" "R402H16"
			(at 0.064008 -5.517896 270)
			(unlocked yes)
			(layer "F.Fab")
			(hide yes)
			(effects
				(font
					(size 1.016 1.016)
					(thickness 0.1524)
				)
			)
		)
		(duplicate_pad_numbers_are_jumpers no)
		(fp_line
			(start -0.508 -0.9398)
			(end -0.508 0.9398)
			(stroke
				(width 0.1524)
				(type default)
			)
			(layer "F.SilkS")
		)
		(fp_line
			(start 0.508 -0.9398)
			(end -0.508 -0.9398)
			(stroke
				(width 0.1524)
				(type default)
			)
			(layer "F.SilkS")
		)
		(fp_rect
			(start -0.508 0.9398)
			(end 0.508 -0.9398)
			(stroke
				(width 0)
				(type default)
			)
			(fill no)
			(layer "F.CrtYd")
		)
		(fp_rect
			(start -0.508 0.9398)
			(end 0.508 -0.9398)
			(stroke
				(width 0)
				(type default)
			)
			(fill no)
			(layer "F.Fab")
		)
		(pad "1" smd custom
			(at 0 -0.4445 270)
			(size 0.1397 0.1397)
			(layers "F.Cu" "F.Mask" "F.Paste")
			(net "P3V3_STBY")
			(options
				(clearance outline)
				(anchor circle)
			)
			(primitives
				(gr_poly
					(pts
						(arc
							(start -0.1778 -0.2794)
							(mid -0.249642 -0.249642)
							(end -0.2794 -0.1778)
						)
						(arc
							(start -0.2794 0.1778)
							(mid -0.249642 0.249642)
							(end -0.1778 0.2794)
						)
						(arc
							(start 0.1778 0.2794)
							(mid 0.249642 0.249642)
							(end 0.2794 0.1778)
						)
						(arc
							(start 0.2794 -0.1778)
							(mid 0.249642 -0.249642)
							(end 0.1778 -0.2794)
						)
					)
					(width 0)
					(fill yes)
				)
			)
		)
		(pad "2" smd custom
			(at 0 0.4445 270)
			(size 0.1397 0.1397)
			(layers "F.Cu" "F.Mask" "F.Paste")
			(net "SLOT3_VMONITOR_A0")
			(options
				(clearance outline)
				(anchor circle)
			)
			(primitives
				(gr_poly
					(pts
						(arc
							(start -0.1778 -0.2794)
							(mid -0.249642 -0.249642)
							(end -0.2794 -0.1778)
						)
						(arc
							(start -0.2794 0.1778)
							(mid -0.249642 0.249642)
							(end -0.1778 0.2794)
						)
						(arc
							(start 0.1778 0.2794)
							(mid 0.249642 0.249642)
							(end 0.2794 0.1778)
						)
						(arc
							(start 0.2794 -0.1778)
							(mid 0.249642 -0.249642)
							(end 0.1778 -0.2794)
						)
					)
					(width 0)
					(fill yes)
				)
			)
		)
	)
	(footprint ""
		(layer "F.Cu")
		(at 124.968 -0.0508)
		(property "Reference" "R141"
			(at 0 0 0)
			(layer "F.SilkS")
			(hide yes)
			(effects
				(font
					(size 1.27 1.27)
				)
			)
		)
		(property "Value" "10KR2F-2-GP"
			(at 0.064008 -3.993896 0)
			(unlocked yes)
			(layer "F.Fab")
			(hide yes)
			(effects
				(font
					(size 1.016 1.016)
					(thickness 0.1524)
				)
			)
		)
		(property "Device Type" "R402H16"
			(at 0.064008 -5.517896 0)
			(unlocked yes)
			(layer "F.Fab")
			(hide yes)
			(effects
				(font
					(size 1.016 1.016)
					(thickness 0.1524)
				)
			)
		)
		(duplicate_pad_numbers_are_jumpers no)
		(fp_line
			(start -0.508 -0.9398)
			(end -0.508 0.9398)
			(stroke
				(width 0.1524)
				(type default)
			)
			(layer "F.SilkS")
		)
		(fp_line
			(start 0.508 -0.9398)
			(end -0.508 -0.9398)
			(stroke
				(width 0.1524)
				(type default)
			)
			(layer "F.SilkS")
		)
		(fp_rect
			(start -0.508 0.9398)
			(end 0.508 -0.9398)
			(stroke
				(width 0)
				(type default)
			)
			(fill no)
			(layer "F.CrtYd")
		)
		(fp_rect
			(start -0.508 0.9398)
			(end 0.508 -0.9398)
			(stroke
				(width 0)
				(type default)
			)
			(fill no)
			(layer "F.Fab")
		)
		(pad "1" smd custom
			(at 0 -0.4445)
			(size 0.1397 0.1397)
			(layers "F.Cu" "F.Mask" "F.Paste")
			(net "GPIO_P_IO1_5")
			(options
				(clearance outline)
				(anchor circle)
			)
			(primitives
				(gr_poly
					(pts
						(arc
							(start -0.1778 -0.2794)
							(mid -0.249642 -0.249642)
							(end -0.2794 -0.1778)
						)
						(arc
							(start -0.2794 0.1778)
							(mid -0.249642 0.249642)
							(end -0.1778 0.2794)
						)
						(arc
							(start 0.1778 0.2794)
							(mid 0.249642 0.249642)
							(end 0.2794 0.1778)
						)
						(arc
							(start 0.2794 -0.1778)
							(mid 0.249642 -0.249642)
							(end 0.1778 -0.2794)
						)
					)
					(width 0)
					(fill yes)
				)
			)
		)
		(pad "2" smd custom
			(at 0 0.4445)
			(size 0.1397 0.1397)
			(layers "F.Cu" "F.Mask" "F.Paste")
			(net "GND")
			(options
				(clearance outline)
				(anchor circle)
			)
			(primitives
				(gr_poly
					(pts
						(arc
							(start -0.1778 -0.2794)
							(mid -0.249642 -0.249642)
							(end -0.2794 -0.1778)
						)
						(arc
							(start -0.2794 0.1778)
							(mid -0.249642 0.249642)
							(end -0.1778 0.2794)
						)
						(arc
							(start 0.1778 0.2794)
							(mid 0.249642 0.249642)
							(end 0.2794 0.1778)
						)
						(arc
							(start 0.2794 -0.1778)
							(mid 0.249642 -0.249642)
							(end 0.1778 -0.2794)
						)
					)
					(width 0)
					(fill yes)
				)
			)
		)
	)
	(footprint ""
		(layer "F.Cu")
		(at 132.08 -2.7432 90)
		(property "Reference" "C42"
			(at 0 0 90)
			(layer "F.SilkS")
			(hide yes)
			(effects
				(font
					(size 1.27 1.27)
				)
			)
		)
		(property "Value" "SCD1U16V2KX-3GP"
			(at 1.1811 -2.7051 90)
			(unlocked yes)
			(layer "F.Fab")
			(hide yes)
			(effects
				(font
					(size 1.016 1.016)
					(thickness 0.1524)
				)
			)
		)
		(property "Device Type" "C402H22"
			(at 1.1811 -4.2291 90)
			(unlocked yes)
			(layer "F.Fab")
			(hide yes)
			(effects
				(font
					(size 1.016 1.016)
					(thickness 0.1524)
				)
			)
		)
		(duplicate_pad_numbers_are_jumpers no)
		(fp_rect
			(start -0.4318 0.9525)
			(end 0.4318 -0.9525)
			(stroke
				(width 0)
				(type default)
			)
			(fill no)
			(layer "F.CrtYd")
		)
		(fp_rect
			(start -0.4318 0.9525)
			(end 0.4318 -0.9525)
			(stroke
				(width 0)
				(type default)
			)
			(fill no)
			(layer "F.Fab")
		)
		(pad "1" smd custom
			(at 0 -0.4445 90)
			(size 0.1524 0.1524)
			(layers "F.Cu" "F.Mask" "F.Paste")
			(net "P3V3_STBY")
			(options
				(clearance outline)
				(anchor circle)
			)
			(primitives
				(gr_poly
					(pts
						(arc
							(start 0.3048 -0.2032)
							(mid 0.275042 -0.275042)
							(end 0.2032 -0.3048)
						)
						(arc
							(start -0.2032 -0.3048)
							(mid -0.275042 -0.275042)
							(end -0.3048 -0.2032)
						)
						(arc
							(start -0.3048 0.2032)
							(mid -0.275042 0.275042)
							(end -0.2032 0.3048)
						)
						(arc
							(start 0.2032 0.3048)
							(mid 0.275042 0.275042)
							(end 0.3048 0.2032)
						)
					)
					(width 0)
					(fill yes)
				)
			)
		)
		(pad "2" smd custom
			(at 0 0.4445 90)
			(size 0.1524 0.1524)
			(layers "F.Cu" "F.Mask" "F.Paste")
			(net "GND")
			(options
				(clearance outline)
				(anchor circle)
			)
			(primitives
				(gr_poly
					(pts
						(arc
							(start 0.3048 -0.2032)
							(mid 0.275042 -0.275042)
							(end 0.2032 -0.3048)
						)
						(arc
							(start -0.2032 -0.3048)
							(mid -0.275042 -0.275042)
							(end -0.3048 -0.2032)
						)
						(arc
							(start -0.3048 0.2032)
							(mid -0.275042 0.275042)
							(end -0.2032 0.3048)
						)
						(arc
							(start 0.2032 0.3048)
							(mid 0.275042 0.275042)
							(end 0.3048 0.2032)
						)
					)
					(width 0)
					(fill yes)
				)
			)
		)
	)
	(footprint ""
		(layer "F.Cu")
		(at 16.4084 -32.0548 180)
		(property "Reference" "C29"
			(at 0 0 180)
			(layer "F.SilkS")
			(hide yes)
			(effects
				(font
					(size 1.27 1.27)
				)
			)
		)
		(property "Value" "SCD1U25V3KX-GP"
			(at 0 -2.8194 180)
			(unlocked yes)
			(layer "F.Fab")
			(hide yes)
			(effects
				(font
					(size 1.016 1.016)
					(thickness 0.1524)
				)
			)
		)
		(property "Device Type" "C603H36"
			(at 0 -4.3434 180)
			(unlocked yes)
			(layer "F.Fab")
			(hide yes)
			(effects
				(font
					(size 1.016 1.016)
					(thickness 0.1524)
				)
			)
		)
		(duplicate_pad_numbers_are_jumpers no)
		(fp_line
			(start 0.508 0)
			(end -0.508 0)
			(stroke
				(width 0.2032)
				(type default)
			)
			(layer "F.SilkS")
		)
		(fp_rect
			(start -0.5842 1.3335)
			(end 0.5842 -1.3335)
			(stroke
				(width 0)
				(type default)
			)
			(fill no)
			(layer "F.CrtYd")
		)
		(fp_rect
			(start -0.5842 1.3335)
			(end 0.5842 -1.3335)
			(stroke
				(width 0)
				(type default)
			)
			(fill no)
			(layer "F.Fab")
		)
		(pad "1" smd custom
			(at 0 -0.762 180)
			(size 0.2159 0.2159)
			(layers "F.Cu" "F.Mask" "F.Paste")
			(net "P12V_SLOT3")
			(options
				(clearance outline)
				(anchor circle)
			)
			(primitives
				(gr_poly
					(pts
						(arc
							(start -0.3302 -0.4318)
							(mid -0.402042 -0.402042)
							(end -0.4318 -0.3302)
						)
						(arc
							(start -0.4318 0.3302)
							(mid -0.402042 0.402042)
							(end -0.3302 0.4318)
						)
						(arc
							(start 0.3302 0.4318)
							(mid 0.402042 0.402042)
							(end 0.4318 0.3302)
						)
						(arc
							(start 0.4318 -0.3302)
							(mid 0.402042 -0.402042)
							(end 0.3302 -0.4318)
						)
					)
					(width 0)
					(fill yes)
				)
			)
		)
		(pad "2" smd custom
			(at 0 0.762 180)
			(size 0.2159 0.2159)
			(layers "F.Cu" "F.Mask" "F.Paste")
			(net "GND")
			(options
				(clearance outline)
				(anchor circle)
			)
			(primitives
				(gr_poly
					(pts
						(arc
							(start -0.3302 -0.4318)
							(mid -0.402042 -0.402042)
							(end -0.4318 -0.3302)
						)
						(arc
							(start -0.4318 0.3302)
							(mid -0.402042 0.402042)
							(end -0.3302 0.4318)
						)
						(arc
							(start 0.3302 0.4318)
							(mid 0.402042 0.402042)
							(end 0.4318 0.3302)
						)
						(arc
							(start 0.4318 -0.3302)
							(mid 0.402042 -0.402042)
							(end 0.3302 -0.4318)
						)
					)
					(width 0)
					(fill yes)
				)
			)
		)
	)
	(footprint ""
		(layer "F.Cu")
		(at 121.2596 -23.3934 -90)
		(property "Reference" "RU34"
			(at 0 0 270)
			(layer "F.SilkS")
			(hide yes)
			(effects
				(font
					(size 1.27 1.27)
				)
			)
		)
		(property "Value" "100KR2F-L1-GP"
			(at 0.064008 -3.993896 270)
			(unlocked yes)
			(layer "F.Fab")
			(hide yes)
			(effects
				(font
					(size 1.016 1.016)
					(thickness 0.1524)
				)
			)
		)
		(property "Device Type" "R402H16"
			(at 0.064008 -5.517896 270)
			(unlocked yes)
			(layer "F.Fab")
			(hide yes)
			(effects
				(font
					(size 1.016 1.016)
					(thickness 0.1524)
				)
			)
		)
		(duplicate_pad_numbers_are_jumpers no)
		(fp_line
			(start -0.508 -0.9398)
			(end -0.508 0.9398)
			(stroke
				(width 0.1524)
				(type default)
			)
			(layer "F.SilkS")
		)
		(fp_line
			(start 0.508 -0.9398)
			(end -0.508 -0.9398)
			(stroke
				(width 0.1524)
				(type default)
			)
			(layer "F.SilkS")
		)
		(fp_rect
			(start -0.508 0.9398)
			(end 0.508 -0.9398)
			(stroke
				(width 0)
				(type default)
			)
			(fill no)
			(layer "F.CrtYd")
		)
		(fp_rect
			(start -0.508 0.9398)
			(end 0.508 -0.9398)
			(stroke
				(width 0)
				(type default)
			)
			(fill no)
			(layer "F.Fab")
		)
		(pad "1" smd custom
			(at 0 -0.4445 270)
			(size 0.1397 0.1397)
			(layers "F.Cu" "F.Mask" "F.Paste")
			(net "SMDAT_USB_HUB_R")
			(options
				(clearance outline)
				(anchor circle)
			)
			(primitives
				(gr_poly
					(pts
						(arc
							(start -0.1778 -0.2794)
							(mid -0.249642 -0.249642)
							(end -0.2794 -0.1778)
						)
						(arc
							(start -0.2794 0.1778)
							(mid -0.249642 0.249642)
							(end -0.1778 0.2794)
						)
						(arc
							(start 0.1778 0.2794)
							(mid 0.249642 0.249642)
							(end 0.2794 0.1778)
						)
						(arc
							(start 0.2794 -0.1778)
							(mid 0.249642 -0.249642)
							(end 0.1778 -0.2794)
						)
					)
					(width 0)
					(fill yes)
				)
			)
		)
		(pad "2" smd custom
			(at 0 0.4445 270)
			(size 0.1397 0.1397)
			(layers "F.Cu" "F.Mask" "F.Paste")
			(net "GND")
			(options
				(clearance outline)
				(anchor circle)
			)
			(primitives
				(gr_poly
					(pts
						(arc
							(start -0.1778 -0.2794)
							(mid -0.249642 -0.249642)
							(end -0.2794 -0.1778)
						)
						(arc
							(start -0.2794 0.1778)
							(mid -0.249642 0.249642)
							(end -0.1778 0.2794)
						)
						(arc
							(start 0.1778 0.2794)
							(mid 0.249642 0.249642)
							(end 0.2794 0.1778)
						)
						(arc
							(start 0.2794 -0.1778)
							(mid 0.249642 -0.249642)
							(end 0.1778 -0.2794)
						)
					)
					(width 0)
					(fill yes)
				)
			)
		)
	)
	(footprint ""
		(layer "F.Cu")
		(at 108.1532 0.2794)
		(property "Reference" "R13"
			(at 0 0 0)
			(layer "F.SilkS")
			(hide yes)
			(effects
				(font
					(size 1.27 1.27)
				)
			)
		)
		(property "Value" "10KR2F-2-GP"
			(at 0.064008 -3.993896 0)
			(unlocked yes)
			(layer "F.Fab")
			(hide yes)
			(effects
				(font
					(size 1.016 1.016)
					(thickness 0.1524)
				)
			)
		)
		(property "Device Type" "R402H16"
			(at 0.064008 -5.517896 0)
			(unlocked yes)
			(layer "F.Fab")
			(hide yes)
			(effects
				(font
					(size 1.016 1.016)
					(thickness 0.1524)
				)
			)
		)
		(duplicate_pad_numbers_are_jumpers no)
		(fp_line
			(start -0.508 -0.9398)
			(end -0.508 0.9398)
			(stroke
				(width 0.1524)
				(type default)
			)
			(layer "F.SilkS")
		)
		(fp_line
			(start 0.508 -0.9398)
			(end -0.508 -0.9398)
			(stroke
				(width 0.1524)
				(type default)
			)
			(layer "F.SilkS")
		)
		(fp_rect
			(start -0.508 0.9398)
			(end 0.508 -0.9398)
			(stroke
				(width 0)
				(type default)
			)
			(fill no)
			(layer "F.CrtYd")
		)
		(fp_rect
			(start -0.508 0.9398)
			(end 0.508 -0.9398)
			(stroke
				(width 0)
				(type default)
			)
			(fill no)
			(layer "F.Fab")
		)
		(pad "1" smd custom
			(at 0 -0.4445)
			(size 0.1397 0.1397)
			(layers "F.Cu" "F.Mask" "F.Paste")
			(net "P3V3_STBY")
			(options
				(clearance outline)
				(anchor circle)
			)
			(primitives
				(gr_poly
					(pts
						(arc
							(start -0.1778 -0.2794)
							(mid -0.249642 -0.249642)
							(end -0.2794 -0.1778)
						)
						(arc
							(start -0.2794 0.1778)
							(mid -0.249642 0.249642)
							(end -0.1778 0.2794)
						)
						(arc
							(start 0.1778 0.2794)
							(mid 0.249642 0.249642)
							(end 0.2794 0.1778)
						)
						(arc
							(start 0.2794 -0.1778)
							(mid 0.249642 -0.249642)
							(end 0.1778 -0.2794)
						)
					)
					(width 0)
					(fill yes)
				)
			)
		)
		(pad "2" smd custom
			(at 0 0.4445)
			(size 0.1397 0.1397)
			(layers "F.Cu" "F.Mask" "F.Paste")
			(net "SMB_B_HUB_A1")
			(options
				(clearance outline)
				(anchor circle)
			)
			(primitives
				(gr_poly
					(pts
						(arc
							(start -0.1778 -0.2794)
							(mid -0.249642 -0.249642)
							(end -0.2794 -0.1778)
						)
						(arc
							(start -0.2794 0.1778)
							(mid -0.249642 0.249642)
							(end -0.1778 0.2794)
						)
						(arc
							(start 0.1778 0.2794)
							(mid 0.249642 0.249642)
							(end 0.2794 0.1778)
						)
						(arc
							(start 0.2794 -0.1778)
							(mid 0.249642 -0.249642)
							(end 0.1778 -0.2794)
						)
					)
					(width 0)
					(fill yes)
				)
			)
		)
	)
	(footprint ""
		(layer "F.Cu")
		(at 22.86 -22.3012 -90)
		(property "Reference" "C48"
			(at 0 0 270)
			(layer "F.SilkS")
			(hide yes)
			(effects
				(font
					(size 1.27 1.27)
				)
			)
		)
		(property "Value" "SCD1U16V2KX-3GP"
			(at 1.1811 -2.7051 270)
			(unlocked yes)
			(layer "F.Fab")
			(hide yes)
			(effects
				(font
					(size 1.016 1.016)
					(thickness 0.1524)
				)
			)
		)
		(property "Device Type" "C402H22"
			(at 1.1811 -4.2291 270)
			(unlocked yes)
			(layer "F.Fab")
			(hide yes)
			(effects
				(font
					(size 1.016 1.016)
					(thickness 0.1524)
				)
			)
		)
		(duplicate_pad_numbers_are_jumpers no)
		(fp_rect
			(start -0.4318 0.9525)
			(end 0.4318 -0.9525)
			(stroke
				(width 0)
				(type default)
			)
			(fill no)
			(layer "F.CrtYd")
		)
		(fp_rect
			(start -0.4318 0.9525)
			(end 0.4318 -0.9525)
			(stroke
				(width 0)
				(type default)
			)
			(fill no)
			(layer "F.Fab")
		)
		(pad "1" smd custom
			(at 0 -0.4445 270)
			(size 0.1524 0.1524)
			(layers "F.Cu" "F.Mask" "F.Paste")
			(net "P3V3_STBY")
			(options
				(clearance outline)
				(anchor circle)
			)
			(primitives
				(gr_poly
					(pts
						(arc
							(start 0.3048 -0.2032)
							(mid 0.275042 -0.275042)
							(end 0.2032 -0.3048)
						)
						(arc
							(start -0.2032 -0.3048)
							(mid -0.275042 -0.275042)
							(end -0.3048 -0.2032)
						)
						(arc
							(start -0.3048 0.2032)
							(mid -0.275042 0.275042)
							(end -0.2032 0.3048)
						)
						(arc
							(start 0.2032 0.3048)
							(mid 0.275042 0.275042)
							(end 0.3048 0.2032)
						)
					)
					(width 0)
					(fill yes)
				)
			)
		)
		(pad "2" smd custom
			(at 0 0.4445 270)
			(size 0.1524 0.1524)
			(layers "F.Cu" "F.Mask" "F.Paste")
			(net "GND")
			(options
				(clearance outline)
				(anchor circle)
			)
			(primitives
				(gr_poly
					(pts
						(arc
							(start 0.3048 -0.2032)
							(mid 0.275042 -0.275042)
							(end 0.2032 -0.3048)
						)
						(arc
							(start -0.2032 -0.3048)
							(mid -0.275042 -0.275042)
							(end -0.3048 -0.2032)
						)
						(arc
							(start -0.3048 0.2032)
							(mid -0.275042 0.275042)
							(end -0.2032 0.3048)
						)
						(arc
							(start 0.2032 0.3048)
							(mid 0.275042 0.275042)
							(end 0.3048 0.2032)
						)
					)
					(width 0)
					(fill yes)
				)
			)
		)
	)
	(footprint ""
		(layer "F.Cu")
		(at 25.6921 4.1656 -90)
		(property "Reference" "R1"
			(at 0 0 270)
			(layer "F.SilkS")
			(hide yes)
			(effects
				(font
					(size 1.27 1.27)
				)
			)
		)
		(property "Value" "475R2F-L1-GP"
			(at 0.064008 -3.993896 270)
			(unlocked yes)
			(layer "F.Fab")
			(hide yes)
			(effects
				(font
					(size 1.016 1.016)
					(thickness 0.1524)
				)
			)
		)
		(property "Device Type" "R402H16"
			(at 0.064008 -5.517896 270)
			(unlocked yes)
			(layer "F.Fab")
			(hide yes)
			(effects
				(font
					(size 1.016 1.016)
					(thickness 0.1524)
				)
			)
		)
		(duplicate_pad_numbers_are_jumpers no)
		(fp_line
			(start -0.508 -0.9398)
			(end -0.508 0.9398)
			(stroke
				(width 0.1524)
				(type default)
			)
			(layer "F.SilkS")
		)
		(fp_line
			(start 0.508 -0.9398)
			(end -0.508 -0.9398)
			(stroke
				(width 0.1524)
				(type default)
			)
			(layer "F.SilkS")
		)
		(fp_rect
			(start -0.508 0.9398)
			(end 0.508 -0.9398)
			(stroke
				(width 0)
				(type default)
			)
			(fill no)
			(layer "F.CrtYd")
		)
		(fp_rect
			(start -0.508 0.9398)
			(end 0.508 -0.9398)
			(stroke
				(width 0)
				(type default)
			)
			(fill no)
			(layer "F.Fab")
		)
		(pad "1" smd custom
			(at 0 -0.4445 270)
			(size 0.1397 0.1397)
			(layers "F.Cu" "F.Mask" "F.Paste")
			(net "GND")
			(options
				(clearance outline)
				(anchor circle)
			)
			(primitives
				(gr_poly
					(pts
						(arc
							(start -0.1778 -0.2794)
							(mid -0.249642 -0.249642)
							(end -0.2794 -0.1778)
						)
						(arc
							(start -0.2794 0.1778)
							(mid -0.249642 0.249642)
							(end -0.1778 0.2794)
						)
						(arc
							(start 0.1778 0.2794)
							(mid 0.249642 0.249642)
							(end 0.2794 0.1778)
						)
						(arc
							(start 0.2794 -0.1778)
							(mid 0.249642 -0.249642)
							(end 0.1778 -0.2794)
						)
					)
					(width 0)
					(fill yes)
				)
			)
		)
		(pad "2" smd custom
			(at 0 0.4445 270)
			(size 0.1397 0.1397)
			(layers "F.Cu" "F.Mask" "F.Paste")
			(net "FM_SLT_CFG0")
			(options
				(clearance outline)
				(anchor circle)
			)
			(primitives
				(gr_poly
					(pts
						(arc
							(start -0.1778 -0.2794)
							(mid -0.249642 -0.249642)
							(end -0.2794 -0.1778)
						)
						(arc
							(start -0.2794 0.1778)
							(mid -0.249642 0.249642)
							(end -0.1778 0.2794)
						)
						(arc
							(start 0.1778 0.2794)
							(mid 0.249642 0.249642)
							(end 0.2794 0.1778)
						)
						(arc
							(start 0.2794 -0.1778)
							(mid 0.249642 -0.249642)
							(end 0.1778 -0.2794)
						)
					)
					(width 0)
					(fill yes)
				)
			)
		)
	)
	(footprint ""
		(layer "F.Cu")
		(at 129.286 -29.3624 90)
		(property "Reference" "CU10"
			(at 0 0 90)
			(layer "F.SilkS")
			(hide yes)
			(effects
				(font
					(size 1.27 1.27)
				)
			)
		)
		(property "Value" "SC1U10V2KX-4-GP"
			(at 1.1811 -2.7051 90)
			(unlocked yes)
			(layer "F.Fab")
			(hide yes)
			(effects
				(font
					(size 1.016 1.016)
					(thickness 0.1524)
				)
			)
		)
		(property "Device Type" "C402H22"
			(at 1.1811 -4.2291 90)
			(unlocked yes)
			(layer "F.Fab")
			(hide yes)
			(effects
				(font
					(size 1.016 1.016)
					(thickness 0.1524)
				)
			)
		)
		(duplicate_pad_numbers_are_jumpers no)
		(fp_rect
			(start -0.4318 0.9525)
			(end 0.4318 -0.9525)
			(stroke
				(width 0)
				(type default)
			)
			(fill no)
			(layer "F.CrtYd")
		)
		(fp_rect
			(start -0.4318 0.9525)
			(end 0.4318 -0.9525)
			(stroke
				(width 0)
				(type default)
			)
			(fill no)
			(layer "F.Fab")
		)
		(pad "1" smd custom
			(at 0 -0.4445 90)
			(size 0.1524 0.1524)
			(layers "F.Cu" "F.Mask" "F.Paste")
			(net "PLLFILT")
			(options
				(clearance outline)
				(anchor circle)
			)
			(primitives
				(gr_poly
					(pts
						(arc
							(start 0.3048 -0.2032)
							(mid 0.275042 -0.275042)
							(end 0.2032 -0.3048)
						)
						(arc
							(start -0.2032 -0.3048)
							(mid -0.275042 -0.275042)
							(end -0.3048 -0.2032)
						)
						(arc
							(start -0.3048 0.2032)
							(mid -0.275042 0.275042)
							(end -0.2032 0.3048)
						)
						(arc
							(start 0.2032 0.3048)
							(mid 0.275042 0.275042)
							(end 0.3048 0.2032)
						)
					)
					(width 0)
					(fill yes)
				)
			)
		)
		(pad "2" smd custom
			(at 0 0.4445 90)
			(size 0.1524 0.1524)
			(layers "F.Cu" "F.Mask" "F.Paste")
			(net "GND")
			(options
				(clearance outline)
				(anchor circle)
			)
			(primitives
				(gr_poly
					(pts
						(arc
							(start 0.3048 -0.2032)
							(mid 0.275042 -0.275042)
							(end 0.2032 -0.3048)
						)
						(arc
							(start -0.2032 -0.3048)
							(mid -0.275042 -0.275042)
							(end -0.3048 -0.2032)
						)
						(arc
							(start -0.3048 0.2032)
							(mid -0.275042 0.275042)
							(end -0.2032 0.3048)
						)
						(arc
							(start 0.2032 0.3048)
							(mid 0.275042 0.275042)
							(end 0.3048 0.2032)
						)
					)
					(width 0)
					(fill yes)
				)
			)
		)
	)
	(footprint ""
		(layer "F.Cu")
		(at 38.6588 -3.7719 90)
		(property "Reference" "C796"
			(at 0 0 90)
			(layer "F.SilkS")
			(hide yes)
			(effects
				(font
					(size 1.27 1.27)
				)
			)
		)
		(property "Value" "SC22U6D3V5MX-5-GP"
			(at -0.0762 -6.1214 90)
			(unlocked yes)
			(layer "F.Fab")
			(hide yes)
			(effects
				(font
					(size 1.016 1.016)
					(thickness 0.1524)
				)
			)
		)
		(property "Device Type" "C805H56"
			(at -0.0762 -8.1534 90)
			(unlocked yes)
			(layer "F.Fab")
			(hide yes)
			(effects
				(font
					(size 1.016 1.016)
					(thickness 0.1524)
				)
			)
		)
		(duplicate_pad_numbers_are_jumpers no)
		(fp_line
			(start 0.635 0)
			(end -0.635 0)
			(stroke
				(width 0.508)
				(type default)
			)
			(layer "F.SilkS")
		)
		(fp_rect
			(start -0.9652 1.778)
			(end 0.9652 -1.778)
			(stroke
				(width 0)
				(type default)
			)
			(fill no)
			(layer "F.CrtYd")
		)
		(fp_poly
			(pts
				(xy -0.9652 -1.778) (xy 0.9652 -1.778) (xy 0.9652 1.778) (xy -0.9652 1.778)
			)
			(stroke
				(width 0)
				(type default)
			)
			(fill no)
			(layer "F.Fab")
		)
		(pad "1" smd rect
			(at 0 -0.9652 90)
			(size 1.397 1.143)
			(layers "F.Cu" "F.Mask" "F.Paste")
			(net "P3V3")
		)
		(pad "2" smd rect
			(at 0 0.9652 90)
			(size 1.397 1.143)
			(layers "F.Cu" "F.Mask" "F.Paste")
			(net "GND")
		)
	)
	(footprint ""
		(layer "F.Cu")
		(at 132.207 -6.7564 -90)
		(property "Reference" "R147"
			(at 0 0 270)
			(layer "F.SilkS")
			(hide yes)
			(effects
				(font
					(size 1.27 1.27)
				)
			)
		)
		(property "Value" "10KR2F-2-GP"
			(at 0.064008 -3.993896 270)
			(unlocked yes)
			(layer "F.Fab")
			(hide yes)
			(effects
				(font
					(size 1.016 1.016)
					(thickness 0.1524)
				)
			)
		)
		(property "Device Type" "R402H16"
			(at 0.064008 -5.517896 270)
			(unlocked yes)
			(layer "F.Fab")
			(hide yes)
			(effects
				(font
					(size 1.016 1.016)
					(thickness 0.1524)
				)
			)
		)
		(duplicate_pad_numbers_are_jumpers no)
		(fp_line
			(start -0.508 -0.9398)
			(end -0.508 0.9398)
			(stroke
				(width 0.1524)
				(type default)
			)
			(layer "F.SilkS")
		)
		(fp_line
			(start 0.508 -0.9398)
			(end -0.508 -0.9398)
			(stroke
				(width 0.1524)
				(type default)
			)
			(layer "F.SilkS")
		)
		(fp_rect
			(start -0.508 0.9398)
			(end 0.508 -0.9398)
			(stroke
				(width 0)
				(type default)
			)
			(fill no)
			(layer "F.CrtYd")
		)
		(fp_rect
			(start -0.508 0.9398)
			(end 0.508 -0.9398)
			(stroke
				(width 0)
				(type default)
			)
			(fill no)
			(layer "F.Fab")
		)
		(pad "1" smd custom
			(at 0 -0.4445 270)
			(size 0.1397 0.1397)
			(layers "F.Cu" "F.Mask" "F.Paste")
			(net "P3V3_STBY")
			(options
				(clearance outline)
				(anchor circle)
			)
			(primitives
				(gr_poly
					(pts
						(arc
							(start -0.1778 -0.2794)
							(mid -0.249642 -0.249642)
							(end -0.2794 -0.1778)
						)
						(arc
							(start -0.2794 0.1778)
							(mid -0.249642 0.249642)
							(end -0.1778 0.2794)
						)
						(arc
							(start 0.1778 0.2794)
							(mid 0.249642 0.249642)
							(end 0.2794 0.1778)
						)
						(arc
							(start 0.2794 -0.1778)
							(mid 0.249642 -0.249642)
							(end 0.1778 -0.2794)
						)
					)
					(width 0)
					(fill yes)
				)
			)
		)
		(pad "2" smd custom
			(at 0 0.4445 270)
			(size 0.1397 0.1397)
			(layers "F.Cu" "F.Mask" "F.Paste")
			(net "GPIO_P_EXP_A1")
			(options
				(clearance outline)
				(anchor circle)
			)
			(primitives
				(gr_poly
					(pts
						(arc
							(start -0.1778 -0.2794)
							(mid -0.249642 -0.249642)
							(end -0.2794 -0.1778)
						)
						(arc
							(start -0.2794 0.1778)
							(mid -0.249642 0.249642)
							(end -0.1778 0.2794)
						)
						(arc
							(start 0.1778 0.2794)
							(mid 0.249642 0.249642)
							(end 0.2794 0.1778)
						)
						(arc
							(start 0.2794 -0.1778)
							(mid 0.249642 -0.249642)
							(end 0.1778 -0.2794)
						)
					)
					(width 0)
					(fill yes)
				)
			)
		)
	)
	(footprint ""
		(layer "F.Cu")
		(at 31.9659 0.6477 90)
		(property "Reference" "R204"
			(at 0 0 90)
			(layer "F.SilkS")
			(hide yes)
			(effects
				(font
					(size 1.27 1.27)
				)
			)
		)
		(property "Value" "0R6J-3-GP"
			(at -0.0508 -4.8514 90)
			(unlocked yes)
			(layer "F.Fab")
			(hide yes)
			(effects
				(font
					(size 1.016 1.016)
					(thickness 0.1524)
				)
			)
		)
		(property "Device Type" "R1206H28"
			(at 0 -6.3754 90)
			(unlocked yes)
			(layer "F.Fab")
			(hide yes)
			(effects
				(font
					(size 1.016 1.016)
					(thickness 0.1524)
				)
			)
		)
		(duplicate_pad_numbers_are_jumpers no)
		(fp_line
			(start 1.016 -2.2352)
			(end 1.016 2.2352)
			(stroke
				(width 0.1524)
				(type default)
			)
			(layer "F.SilkS")
		)
		(fp_line
			(start -1.016 -2.2352)
			(end 1.016 -2.2352)
			(stroke
				(width 0.1524)
				(type default)
			)
			(layer "F.SilkS")
		)
		(fp_line
			(start 1.016 2.2352)
			(end -1.016 2.2352)
			(stroke
				(width 0.1524)
				(type default)
			)
			(layer "F.SilkS")
		)
		(fp_line
			(start -1.016 2.2352)
			(end -1.016 -2.2352)
			(stroke
				(width 0.1524)
				(type default)
			)
			(layer "F.SilkS")
		)
		(fp_rect
			(start -1.0922 2.3114)
			(end 1.0922 -2.3114)
			(stroke
				(width 0)
				(type default)
			)
			(fill no)
			(layer "F.CrtYd")
		)
		(fp_poly
			(pts
				(xy -1.0922 -2.3114) (xy 1.0922 -2.3114) (xy 1.0922 2.3114) (xy -1.0922 2.3114)
			)
			(stroke
				(width 0)
				(type default)
			)
			(fill no)
			(layer "F.Fab")
		)
		(pad "1" smd rect
			(at 0 -1.397 90)
			(size 1.651 1.27)
			(layers "F.Cu" "F.Mask" "F.Paste")
			(net "P3V3_VR")
		)
		(pad "2" smd rect
			(at 0 1.397 90)
			(size 1.651 1.27)
			(layers "F.Cu" "F.Mask" "F.Paste")
			(net "P3V3")
		)
	)
	(footprint ""
		(layer "F.Cu")
		(at 119.1768 -14.5542 90)
		(property "Reference" "R42"
			(at 0 0 90)
			(layer "F.SilkS")
			(hide yes)
			(effects
				(font
					(size 1.27 1.27)
				)
			)
		)
		(property "Value" "4K7R2F-GP"
			(at 0.064008 -3.993896 90)
			(unlocked yes)
			(layer "F.Fab")
			(hide yes)
			(effects
				(font
					(size 1.016 1.016)
					(thickness 0.1524)
				)
			)
		)
		(property "Device Type" "R402H16"
			(at 0.064008 -5.517896 90)
			(unlocked yes)
			(layer "F.Fab")
			(hide yes)
			(effects
				(font
					(size 1.016 1.016)
					(thickness 0.1524)
				)
			)
		)
		(duplicate_pad_numbers_are_jumpers no)
		(fp_line
			(start 0.508 -0.9398)
			(end -0.508 -0.9398)
			(stroke
				(width 0.1524)
				(type default)
			)
			(layer "F.SilkS")
		)
		(fp_line
			(start -0.508 -0.9398)
			(end -0.508 0.9398)
			(stroke
				(width 0.1524)
				(type default)
			)
			(layer "F.SilkS")
		)
		(fp_rect
			(start -0.508 0.9398)
			(end 0.508 -0.9398)
			(stroke
				(width 0)
				(type default)
			)
			(fill no)
			(layer "F.CrtYd")
		)
		(fp_rect
			(start -0.508 0.9398)
			(end 0.508 -0.9398)
			(stroke
				(width 0)
				(type default)
			)
			(fill no)
			(layer "F.Fab")
		)
		(pad "1" smd custom
			(at 0 -0.4445 90)
			(size 0.1397 0.1397)
			(layers "F.Cu" "F.Mask" "F.Paste")
			(net "P3V3_STBY")
			(options
				(clearance outline)
				(anchor circle)
			)
			(primitives
				(gr_poly
					(pts
						(arc
							(start -0.1778 -0.2794)
							(mid -0.249642 -0.249642)
							(end -0.2794 -0.1778)
						)
						(arc
							(start -0.2794 0.1778)
							(mid -0.249642 0.249642)
							(end -0.1778 0.2794)
						)
						(arc
							(start 0.1778 0.2794)
							(mid 0.249642 0.249642)
							(end 0.2794 0.1778)
						)
						(arc
							(start 0.2794 -0.1778)
							(mid 0.249642 -0.249642)
							(end 0.1778 -0.2794)
						)
					)
					(width 0)
					(fill yes)
				)
			)
		)
		(pad "2" smd custom
			(at 0 0.4445 90)
			(size 0.1397 0.1397)
			(layers "F.Cu" "F.Mask" "F.Paste")
			(net "PCIE_SLOT3_PRSNT2_1_N")
			(options
				(clearance outline)
				(anchor circle)
			)
			(primitives
				(gr_poly
					(pts
						(arc
							(start -0.1778 -0.2794)
							(mid -0.249642 -0.249642)
							(end -0.2794 -0.1778)
						)
						(arc
							(start -0.2794 0.1778)
							(mid -0.249642 0.249642)
							(end -0.1778 0.2794)
						)
						(arc
							(start 0.1778 0.2794)
							(mid 0.249642 0.249642)
							(end 0.2794 0.1778)
						)
						(arc
							(start 0.2794 -0.1778)
							(mid 0.249642 -0.249642)
							(end 0.1778 -0.2794)
						)
					)
					(width 0)
					(fill yes)
				)
			)
		)
	)
	(footprint ""
		(layer "F.Cu")
		(at 106.5784 0.3048)
		(property "Reference" "R16"
			(at 0 0 0)
			(layer "F.SilkS")
			(hide yes)
			(effects
				(font
					(size 1.27 1.27)
				)
			)
		)
		(property "Value" "10KR2F-2-GP"
			(at 0.064008 -3.993896 0)
			(unlocked yes)
			(layer "F.Fab")
			(hide yes)
			(effects
				(font
					(size 1.016 1.016)
					(thickness 0.1524)
				)
			)
		)
		(property "Device Type" "R402H16"
			(at 0.064008 -5.517896 0)
			(unlocked yes)
			(layer "F.Fab")
			(hide yes)
			(effects
				(font
					(size 1.016 1.016)
					(thickness 0.1524)
				)
			)
		)
		(duplicate_pad_numbers_are_jumpers no)
		(fp_line
			(start -0.508 -0.9398)
			(end -0.508 0.9398)
			(stroke
				(width 0.1524)
				(type default)
			)
			(layer "F.SilkS")
		)
		(fp_line
			(start 0.508 -0.9398)
			(end -0.508 -0.9398)
			(stroke
				(width 0.1524)
				(type default)
			)
			(layer "F.SilkS")
		)
		(fp_rect
			(start -0.508 0.9398)
			(end 0.508 -0.9398)
			(stroke
				(width 0)
				(type default)
			)
			(fill no)
			(layer "F.CrtYd")
		)
		(fp_rect
			(start -0.508 0.9398)
			(end 0.508 -0.9398)
			(stroke
				(width 0)
				(type default)
			)
			(fill no)
			(layer "F.Fab")
		)
		(pad "1" smd custom
			(at 0 -0.4445)
			(size 0.1397 0.1397)
			(layers "F.Cu" "F.Mask" "F.Paste")
			(net "P3V3_STBY")
			(options
				(clearance outline)
				(anchor circle)
			)
			(primitives
				(gr_poly
					(pts
						(arc
							(start -0.1778 -0.2794)
							(mid -0.249642 -0.249642)
							(end -0.2794 -0.1778)
						)
						(arc
							(start -0.2794 0.1778)
							(mid -0.249642 0.249642)
							(end -0.1778 0.2794)
						)
						(arc
							(start 0.1778 0.2794)
							(mid 0.249642 0.249642)
							(end 0.2794 0.1778)
						)
						(arc
							(start 0.2794 -0.1778)
							(mid 0.249642 -0.249642)
							(end 0.1778 -0.2794)
						)
					)
					(width 0)
					(fill yes)
				)
			)
		)
		(pad "2" smd custom
			(at 0 0.4445)
			(size 0.1397 0.1397)
			(layers "F.Cu" "F.Mask" "F.Paste")
			(net "SMB_B_HUB_A2")
			(options
				(clearance outline)
				(anchor circle)
			)
			(primitives
				(gr_poly
					(pts
						(arc
							(start -0.1778 -0.2794)
							(mid -0.249642 -0.249642)
							(end -0.2794 -0.1778)
						)
						(arc
							(start -0.2794 0.1778)
							(mid -0.249642 0.249642)
							(end -0.1778 0.2794)
						)
						(arc
							(start 0.1778 0.2794)
							(mid 0.249642 0.249642)
							(end 0.2794 0.1778)
						)
						(arc
							(start 0.2794 -0.1778)
							(mid 0.249642 -0.249642)
							(end 0.1778 -0.2794)
						)
					)
					(width 0)
					(fill yes)
				)
			)
		)
	)
	(footprint ""
		(layer "F.Cu")
		(at 120.57507 13.530072)
		(property "Reference" "GF1"
			(at 0 0 0)
			(layer "F.SilkS")
			(hide yes)
			(effects
				(font
					(size 1.27 1.27)
				)
			)
		)
		(property "Value" "GF-HSEC8-60P-5-GP"
			(at -15.0622 -0.8382 0)
			(unlocked yes)
			(layer "F.Fab")
			(hide yes)
			(effects
				(font
					(size 1.016 1.016)
					(thickness 0.1524)
				)
			)
		)
		(property "Device Type" "GF-HSEC8-60P"
			(at -15.0622 -2.3622 0)
			(unlocked yes)
			(layer "F.Fab")
			(hide yes)
			(effects
				(font
					(size 1.016 1.016)
					(thickness 0.1524)
				)
			)
		)
		(duplicate_pad_numbers_are_jumpers no)
		(fp_rect
			(start -13.9192 2.032)
			(end 13.9192 -4.6228)
			(stroke
				(width 0)
				(type default)
			)
			(fill no)
			(layer "B.CrtYd")
		)
		(fp_rect
			(start -13.9192 2.032)
			(end 13.9192 -4.6228)
			(stroke
				(width 0)
				(type default)
			)
			(fill no)
			(layer "F.CrtYd")
		)
		(fp_rect
			(start -13.9192 2.032)
			(end 13.9192 -4.6228)
			(stroke
				(width 0)
				(type default)
			)
			(fill no)
			(layer "B.Fab")
		)
		(fp_rect
			(start -13.9192 2.032)
			(end 13.9192 -4.6228)
			(stroke
				(width 0)
				(type default)
			)
			(fill no)
			(layer "F.Fab")
		)
		(fp_text user "02 Do not mirror"
			(at -7.62 4.1148 0)
			(unlocked yes)
			(layer "F.Fab")
			(effects
				(font
					(size 1.016 1.016)
					(thickness 0.1524)
				)
				(justify left)
			)
		)
		(pad "1" smd rect
			(at -11.599926 -1.2954)
			(size 0.5588 2.5908)
			(layers "F.Cu" "F.Mask" "F.Paste")
			(net "GND")
		)
		(pad "2" smd rect
			(at -11.599926 -0.9144)
			(size 0.5588 2.5908)
			(drill
				(offset 0 -0.381)
			)
			(layers "F.Cu" "F.Mask" "F.Paste")
			(net "Net_361")
		)
		(pad "3" smd rect
			(at -10.80008 -1.2954)
			(size 0.5588 2.5908)
			(layers "F.Cu" "F.Mask" "F.Paste")
			(net "P3E_CPU0_PE2_SS_C_TXP<8>")
		)
		(pad "4" smd rect
			(at -10.80008 -0.9144)
			(size 0.5588 2.5908)
			(drill
				(offset 0 -0.381)
			)
			(layers "F.Cu" "F.Mask" "F.Paste")
			(net "GND")
		)
		(pad "5" smd rect
			(at -9.99998 -1.2954)
			(size 0.5588 2.5908)
			(layers "F.Cu" "F.Mask" "F.Paste")
			(net "P3E_CPU0_PE2_SS_C_TXN<8>")
		)
		(pad "6" smd rect
			(at -9.99998 -0.9144)
			(size 0.5588 2.5908)
			(drill
				(offset 0 -0.381)
			)
			(layers "F.Cu" "F.Mask" "F.Paste")
			(net "P3E_CPU0_PE2_SS_RXP<8>")
		)
		(pad "7" smd rect
			(at -9.19988 -1.2954)
			(size 0.5588 2.5908)
			(layers "F.Cu" "F.Mask" "F.Paste")
			(net "GND")
		)
		(pad "8" smd rect
			(at -9.19988 -0.9144)
			(size 0.5588 2.5908)
			(drill
				(offset 0 -0.381)
			)
			(layers "F.Cu" "F.Mask" "F.Paste")
			(net "P3E_CPU0_PE2_SS_RXN<8>")
		)
		(pad "9" smd rect
			(at -8.400034 -1.2954)
			(size 0.5588 2.5908)
			(layers "F.Cu" "F.Mask" "F.Paste")
			(net "P3E_CPU0_PE2_SS_C_TXP<9>")
		)
		(pad "10" smd rect
			(at -8.400034 -0.9144)
			(size 0.5588 2.5908)
			(drill
				(offset 0 -0.381)
			)
			(layers "F.Cu" "F.Mask" "F.Paste")
			(net "GND")
		)
		(pad "11" smd rect
			(at -7.599934 -1.2954)
			(size 0.5588 2.5908)
			(layers "F.Cu" "F.Mask" "F.Paste")
			(net "P3E_CPU0_PE2_SS_C_TXN<9>")
		)
		(pad "12" smd rect
			(at -7.599934 -0.9144)
			(size 0.5588 2.5908)
			(drill
				(offset 0 -0.381)
			)
			(layers "F.Cu" "F.Mask" "F.Paste")
			(net "P3E_CPU0_PE2_SS_RXP<9>")
		)
		(pad "13" smd rect
			(at -6.800088 -1.2954)
			(size 0.5588 2.5908)
			(layers "F.Cu" "F.Mask" "F.Paste")
			(net "GND")
		)
		(pad "14" smd rect
			(at -6.800088 -0.9144)
			(size 0.5588 2.5908)
			(drill
				(offset 0 -0.381)
			)
			(layers "F.Cu" "F.Mask" "F.Paste")
			(net "P3E_CPU0_PE2_SS_RXN<9>")
		)
		(pad "15" smd rect
			(at -5.999988 -1.2954)
			(size 0.5588 2.5908)
			(layers "F.Cu" "F.Mask" "F.Paste")
			(net "P3E_CPU0_PE2_SS_C_TXP<10>")
		)
		(pad "16" smd rect
			(at -5.999988 -0.9144)
			(size 0.5588 2.5908)
			(drill
				(offset 0 -0.381)
			)
			(layers "F.Cu" "F.Mask" "F.Paste")
			(net "GND")
		)
		(pad "17" smd rect
			(at -5.199888 -1.2954)
			(size 0.5588 2.5908)
			(layers "F.Cu" "F.Mask" "F.Paste")
			(net "P3E_CPU0_PE2_SS_C_TXN<10>")
		)
		(pad "18" smd rect
			(at -5.199888 -0.9144)
			(size 0.5588 2.5908)
			(drill
				(offset 0 -0.381)
			)
			(layers "F.Cu" "F.Mask" "F.Paste")
			(net "P3E_CPU0_PE2_SS_RXP<10>")
		)
		(pad "19" smd rect
			(at -4.400042 -1.2954)
			(size 0.5588 2.5908)
			(layers "F.Cu" "F.Mask" "F.Paste")
			(net "GND")
		)
		(pad "20" smd rect
			(at -4.400042 -0.9144)
			(size 0.5588 2.5908)
			(drill
				(offset 0 -0.381)
			)
			(layers "F.Cu" "F.Mask" "F.Paste")
			(net "P3E_CPU0_PE2_SS_RXN<10>")
		)
		(pad "21" smd rect
			(at -3.599942 -1.2954)
			(size 0.5588 2.5908)
			(layers "F.Cu" "F.Mask" "F.Paste")
			(net "P3E_CPU0_PE2_SS_C_TXP<11>")
		)
		(pad "22" smd rect
			(at -3.599942 -0.9144)
			(size 0.5588 2.5908)
			(drill
				(offset 0 -0.381)
			)
			(layers "F.Cu" "F.Mask" "F.Paste")
			(net "GND")
		)
		(pad "23" smd rect
			(at -2.800096 -1.2954)
			(size 0.5588 2.5908)
			(layers "F.Cu" "F.Mask" "F.Paste")
			(net "P3E_CPU0_PE2_SS_C_TXN<11>")
		)
		(pad "24" smd rect
			(at -2.800096 -0.9144)
			(size 0.5588 2.5908)
			(drill
				(offset 0 -0.381)
			)
			(layers "F.Cu" "F.Mask" "F.Paste")
			(net "P3E_CPU0_PE2_SS_RXP<11>")
		)
		(pad "25" smd rect
			(at -1.999996 -1.2954)
			(size 0.5588 2.5908)
			(layers "F.Cu" "F.Mask" "F.Paste")
			(net "GND")
		)
		(pad "26" smd rect
			(at -1.999996 -0.9144)
			(size 0.5588 2.5908)
			(drill
				(offset 0 -0.381)
			)
			(layers "F.Cu" "F.Mask" "F.Paste")
			(net "P3E_CPU0_PE2_SS_RXN<11>")
		)
		(pad "27" smd rect
			(at -1.199896 -1.2954)
			(size 0.5588 2.5908)
			(layers "F.Cu" "F.Mask" "F.Paste")
			(net "P3E_CPU0_PE2_SS_C_TXP<12>")
		)
		(pad "28" smd rect
			(at -1.199896 -0.9144)
			(size 0.5588 2.5908)
			(drill
				(offset 0 -0.381)
			)
			(layers "F.Cu" "F.Mask" "F.Paste")
			(net "GND")
		)
		(pad "29" smd rect
			(at -0.40005 -1.2954)
			(size 0.5588 2.5908)
			(layers "F.Cu" "F.Mask" "F.Paste")
			(net "P3E_CPU0_PE2_SS_C_TXN<12>")
		)
		(pad "30" smd rect
			(at -0.40005 -0.9144)
			(size 0.5588 2.5908)
			(drill
				(offset 0 -0.381)
			)
			(layers "F.Cu" "F.Mask" "F.Paste")
			(net "P3E_CPU0_PE2_SS_RXP<12>")
		)
		(pad "31" smd rect
			(at 0.40005 -1.2954)
			(size 0.5588 2.5908)
			(layers "F.Cu" "F.Mask" "F.Paste")
			(net "GND")
		)
		(pad "32" smd rect
			(at 0.40005 -0.9144)
			(size 0.5588 2.5908)
			(drill
				(offset 0 -0.381)
			)
			(layers "F.Cu" "F.Mask" "F.Paste")
			(net "P3E_CPU0_PE2_SS_RXN<12>")
		)
		(pad "33" smd rect
			(at 1.199896 -1.2954)
			(size 0.5588 2.5908)
			(layers "F.Cu" "F.Mask" "F.Paste")
			(net "P3E_CPU0_PE2_SS_C_TXP<13>")
		)
		(pad "34" smd rect
			(at 1.199896 -0.9144)
			(size 0.5588 2.5908)
			(drill
				(offset 0 -0.381)
			)
			(layers "F.Cu" "F.Mask" "F.Paste")
			(net "GND")
		)
		(pad "35" smd rect
			(at 1.999996 -1.2954)
			(size 0.5588 2.5908)
			(layers "F.Cu" "F.Mask" "F.Paste")
			(net "P3E_CPU0_PE2_SS_C_TXN<13>")
		)
		(pad "36" smd rect
			(at 1.999996 -0.9144)
			(size 0.5588 2.5908)
			(drill
				(offset 0 -0.381)
			)
			(layers "F.Cu" "F.Mask" "F.Paste")
			(net "P3E_CPU0_PE2_SS_RXP<13>")
		)
		(pad "37" smd rect
			(at 2.800096 -1.2954)
			(size 0.5588 2.5908)
			(layers "F.Cu" "F.Mask" "F.Paste")
			(net "GND")
		)
		(pad "38" smd rect
			(at 2.800096 -0.9144)
			(size 0.5588 2.5908)
			(drill
				(offset 0 -0.381)
			)
			(layers "F.Cu" "F.Mask" "F.Paste")
			(net "P3E_CPU0_PE2_SS_RXN<13>")
		)
		(pad "39" smd rect
			(at 3.599942 -1.2954)
			(size 0.5588 2.5908)
			(layers "F.Cu" "F.Mask" "F.Paste")
			(net "P3E_CPU0_PE2_SS_C_TXP<14>")
		)
		(pad "40" smd rect
			(at 3.599942 -0.9144)
			(size 0.5588 2.5908)
			(drill
				(offset 0 -0.381)
			)
			(layers "F.Cu" "F.Mask" "F.Paste")
			(net "GND")
		)
		(pad "41" smd rect
			(at 4.400042 -1.2954)
			(size 0.5588 2.5908)
			(layers "F.Cu" "F.Mask" "F.Paste")
			(net "P3E_CPU0_PE2_SS_C_TXN<14>")
		)
		(pad "42" smd rect
			(at 4.400042 -0.9144)
			(size 0.5588 2.5908)
			(drill
				(offset 0 -0.381)
			)
			(layers "F.Cu" "F.Mask" "F.Paste")
			(net "P3E_CPU0_PE2_SS_RXP<14>")
		)
		(pad "43" smd rect
			(at 5.199888 -1.2954)
			(size 0.5588 2.5908)
			(layers "F.Cu" "F.Mask" "F.Paste")
			(net "GND")
		)
		(pad "44" smd rect
			(at 5.199888 -0.9144)
			(size 0.5588 2.5908)
			(drill
				(offset 0 -0.381)
			)
			(layers "F.Cu" "F.Mask" "F.Paste")
			(net "P3E_CPU0_PE2_SS_RXN<14>")
		)
		(pad "45" smd rect
			(at 5.999988 -1.2954)
			(size 0.5588 2.5908)
			(layers "F.Cu" "F.Mask" "F.Paste")
			(net "P3E_CPU0_PE2_SS_C_TXP<15>")
		)
		(pad "46" smd rect
			(at 5.999988 -0.9144)
			(size 0.5588 2.5908)
			(drill
				(offset 0 -0.381)
			)
			(layers "F.Cu" "F.Mask" "F.Paste")
			(net "GND")
		)
		(pad "47" smd rect
			(at 6.800088 -1.2954)
			(size 0.5588 2.5908)
			(layers "F.Cu" "F.Mask" "F.Paste")
			(net "P3E_CPU0_PE2_SS_C_TXN<15>")
		)
		(pad "48" smd rect
			(at 6.800088 -0.9144)
			(size 0.5588 2.5908)
			(drill
				(offset 0 -0.381)
			)
			(layers "F.Cu" "F.Mask" "F.Paste")
			(net "P3E_CPU0_PE2_SS_RXP<15>")
		)
		(pad "49" smd rect
			(at 7.599934 -1.2954)
			(size 0.5588 2.5908)
			(layers "F.Cu" "F.Mask" "F.Paste")
			(net "GND")
		)
		(pad "50" smd rect
			(at 7.599934 -0.9144)
			(size 0.5588 2.5908)
			(drill
				(offset 0 -0.381)
			)
			(layers "F.Cu" "F.Mask" "F.Paste")
			(net "P3E_CPU0_PE2_SS_RXN<15>")
		)
		(pad "51" smd rect
			(at 8.400034 -1.2954)
			(size 0.5588 2.5908)
			(layers "F.Cu" "F.Mask" "F.Paste")
			(net "Net_115")
		)
		(pad "52" smd rect
			(at 8.400034 -0.9144)
			(size 0.5588 2.5908)
			(drill
				(offset 0 -0.381)
			)
			(layers "F.Cu" "F.Mask" "F.Paste")
			(net "GND")
		)
		(pad "53" smd rect
			(at 9.19988 -1.2954)
			(size 0.5588 2.5908)
			(layers "F.Cu" "F.Mask" "F.Paste")
			(net "Net_114")
		)
		(pad "54" smd rect
			(at 9.19988 -0.9144)
			(size 0.5588 2.5908)
			(drill
				(offset 0 -0.381)
			)
			(layers "F.Cu" "F.Mask" "F.Paste")
			(net "Net_105")
		)
		(pad "55" smd rect
			(at 9.99998 -1.2954)
			(size 0.5588 2.5908)
			(layers "F.Cu" "F.Mask" "F.Paste")
			(net "GND")
		)
		(pad "56" smd rect
			(at 9.99998 -0.9144)
			(size 0.5588 2.5908)
			(drill
				(offset 0 -0.381)
			)
			(layers "F.Cu" "F.Mask" "F.Paste")
			(net "Net_104")
		)
		(pad "57" smd rect
			(at 10.80008 -1.2954)
			(size 0.5588 2.5908)
			(layers "F.Cu" "F.Mask" "F.Paste")
			(net "USB2_P02_DN")
		)
		(pad "58" smd rect
			(at 10.80008 -0.9144)
			(size 0.5588 2.5908)
			(drill
				(offset 0 -0.381)
			)
			(layers "F.Cu" "F.Mask" "F.Paste")
			(net "GND")
		)
		(pad "59" smd rect
			(at 11.599926 -1.2954)
			(size 0.5588 2.5908)
			(layers "F.Cu" "F.Mask" "F.Paste")
			(net "USB2_P02_DP")
		)
		(pad "60" smd rect
			(at 11.599926 -0.9144)
			(size 0.5588 2.5908)
			(drill
				(offset 0 -0.381)
			)
			(layers "F.Cu" "F.Mask" "F.Paste")
			(net "Net_360")
		)
		(zone
			(layer "F.Cu")
			(hatch none 0.5)
			(connect_pads
				(clearance 0)
			)
			(min_thickness 0.25)
			(keepout
				(tracks allowed)
				(vias not_allowed)
				(pads allowed)
				(copperpour not_allowed)
				(footprints allowed)
			)
			(placement
				(enabled no)
				(sheetname "")
			)
			(fill
				(thermal_gap 0.5)
				(thermal_bridge_width 0.5)
				(island_removal_mode 0)
			)
			(polygon
				(pts
					(xy 107.67187 14.546072) (xy 133.47827 14.546072) (xy 133.47827 9.923272) (xy 107.67187 9.923272)
				)
			)
		)
		(zone
			(layer "F.Cu")
			(hatch none 0.5)
			(connect_pads
				(clearance 0)
			)
			(min_thickness 0.25)
			(keepout
				(tracks not_allowed)
				(vias allowed)
				(pads allowed)
				(copperpour not_allowed)
				(footprints allowed)
			)
			(placement
				(enabled no)
				(sheetname "")
			)
			(fill
				(thermal_gap 0.5)
				(thermal_bridge_width 0.5)
				(island_removal_mode 0)
			)
			(polygon
				(pts
					(xy 107.67187 14.546072) (xy 133.47827 14.546072) (xy 133.47827 13.530072) (xy 107.67187 13.530072)
				)
			)
		)
		(zone
			(layer "B.Cu")
			(hatch none 0.5)
			(connect_pads
				(clearance 0)
			)
			(min_thickness 0.25)
			(keepout
				(tracks allowed)
				(vias not_allowed)
				(pads allowed)
				(copperpour not_allowed)
				(footprints allowed)
			)
			(placement
				(enabled no)
				(sheetname "")
			)
			(fill
				(thermal_gap 0.5)
				(thermal_bridge_width 0.5)
				(island_removal_mode 0)
			)
			(polygon
				(pts
					(xy 107.67187 14.546072) (xy 133.47827 14.546072) (xy 133.47827 9.923272) (xy 107.67187 9.923272)
				)
			)
		)
		(zone
			(layer "B.Cu")
			(hatch none 0.5)
			(connect_pads
				(clearance 0)
			)
			(min_thickness 0.25)
			(keepout
				(tracks not_allowed)
				(vias allowed)
				(pads allowed)
				(copperpour not_allowed)
				(footprints allowed)
			)
			(placement
				(enabled no)
				(sheetname "")
			)
			(fill
				(thermal_gap 0.5)
				(thermal_bridge_width 0.5)
				(island_removal_mode 0)
			)
			(polygon
				(pts
					(xy 107.67187 14.546072) (xy 133.47827 14.546072) (xy 133.47827 13.530072) (xy 107.67187 13.530072)
				)
			)
		)
	)
	(footprint ""
		(layer "F.Cu")
		(at 33.0581 -1.6129 -90)
		(property "Reference" "C798"
			(at 0 0 270)
			(layer "F.SilkS")
			(hide yes)
			(effects
				(font
					(size 1.27 1.27)
				)
			)
		)
		(property "Value" "SC22U6D3V5MX-5-GP"
			(at -0.0762 -6.1214 270)
			(unlocked yes)
			(layer "F.Fab")
			(hide yes)
			(effects
				(font
					(size 1.016 1.016)
					(thickness 0.1524)
				)
			)
		)
		(property "Device Type" "C805H56"
			(at -0.0762 -8.1534 270)
			(unlocked yes)
			(layer "F.Fab")
			(hide yes)
			(effects
				(font
					(size 1.016 1.016)
					(thickness 0.1524)
				)
			)
		)
		(duplicate_pad_numbers_are_jumpers no)
		(fp_line
			(start 0.635 0)
			(end -0.635 0)
			(stroke
				(width 0.508)
				(type default)
			)
			(layer "F.SilkS")
		)
		(fp_rect
			(start -0.9652 1.778)
			(end 0.9652 -1.778)
			(stroke
				(width 0)
				(type default)
			)
			(fill no)
			(layer "F.CrtYd")
		)
		(fp_poly
			(pts
				(xy -0.9652 -1.778) (xy 0.9652 -1.778) (xy 0.9652 1.778) (xy -0.9652 1.778)
			)
			(stroke
				(width 0)
				(type default)
			)
			(fill no)
			(layer "F.Fab")
		)
		(pad "1" smd rect
			(at 0 -0.9652 270)
			(size 1.397 1.143)
			(layers "F.Cu" "F.Mask" "F.Paste")
			(net "P3V3")
		)
		(pad "2" smd rect
			(at 0 0.9652 270)
			(size 1.397 1.143)
			(layers "F.Cu" "F.Mask" "F.Paste")
			(net "GND")
		)
	)
	(footprint ""
		(layer "F.Cu")
		(at 119.1514 -20.193 90)
		(property "Reference" "R120"
			(at 0 0 90)
			(layer "F.SilkS")
			(hide yes)
			(effects
				(font
					(size 1.27 1.27)
				)
			)
		)
		(property "Value" "10KR2F-2-GP"
			(at 0.064008 -3.993896 90)
			(unlocked yes)
			(layer "F.Fab")
			(hide yes)
			(effects
				(font
					(size 1.016 1.016)
					(thickness 0.1524)
				)
			)
		)
		(property "Device Type" "R402H16"
			(at 0.064008 -5.517896 90)
			(unlocked yes)
			(layer "F.Fab")
			(hide yes)
			(effects
				(font
					(size 1.016 1.016)
					(thickness 0.1524)
				)
			)
		)
		(duplicate_pad_numbers_are_jumpers no)
		(fp_line
			(start 0.508 -0.9398)
			(end -0.508 -0.9398)
			(stroke
				(width 0.1524)
				(type default)
			)
			(layer "F.SilkS")
		)
		(fp_line
			(start -0.508 -0.9398)
			(end -0.508 0.9398)
			(stroke
				(width 0.1524)
				(type default)
			)
			(layer "F.SilkS")
		)
		(fp_rect
			(start -0.508 0.9398)
			(end 0.508 -0.9398)
			(stroke
				(width 0)
				(type default)
			)
			(fill no)
			(layer "F.CrtYd")
		)
		(fp_rect
			(start -0.508 0.9398)
			(end 0.508 -0.9398)
			(stroke
				(width 0)
				(type default)
			)
			(fill no)
			(layer "F.Fab")
		)
		(pad "1" smd custom
			(at 0 -0.4445 90)
			(size 0.1397 0.1397)
			(layers "F.Cu" "F.Mask" "F.Paste")
			(net "P3V3_STBY")
			(options
				(clearance outline)
				(anchor circle)
			)
			(primitives
				(gr_poly
					(pts
						(arc
							(start -0.1778 -0.2794)
							(mid -0.249642 -0.249642)
							(end -0.2794 -0.1778)
						)
						(arc
							(start -0.2794 0.1778)
							(mid -0.249642 0.249642)
							(end -0.1778 0.2794)
						)
						(arc
							(start 0.1778 0.2794)
							(mid 0.249642 0.249642)
							(end 0.2794 0.1778)
						)
						(arc
							(start 0.2794 -0.1778)
							(mid 0.249642 -0.249642)
							(end 0.1778 -0.2794)
						)
					)
					(width 0)
					(fill yes)
				)
			)
		)
		(pad "2" smd custom
			(at 0 0.4445 90)
			(size 0.1397 0.1397)
			(layers "F.Cu" "F.Mask" "F.Paste")
			(net "GPIO_B_EXP_A1")
			(options
				(clearance outline)
				(anchor circle)
			)
			(primitives
				(gr_poly
					(pts
						(arc
							(start -0.1778 -0.2794)
							(mid -0.249642 -0.249642)
							(end -0.2794 -0.1778)
						)
						(arc
							(start -0.2794 0.1778)
							(mid -0.249642 0.249642)
							(end -0.1778 0.2794)
						)
						(arc
							(start 0.1778 0.2794)
							(mid 0.249642 0.249642)
							(end 0.2794 0.1778)
						)
						(arc
							(start 0.2794 -0.1778)
							(mid 0.249642 -0.249642)
							(end 0.1778 -0.2794)
						)
					)
					(width 0)
					(fill yes)
				)
			)
		)
	)
	(footprint ""
		(layer "F.Cu")
		(at 118.8466 -27.6098 -90)
		(property "Reference" "CU9"
			(at 0 0 270)
			(layer "F.SilkS")
			(hide yes)
			(effects
				(font
					(size 1.27 1.27)
				)
			)
		)
		(property "Value" "SC1U10V2KX-4-GP"
			(at 1.1811 -2.7051 270)
			(unlocked yes)
			(layer "F.Fab")
			(hide yes)
			(effects
				(font
					(size 1.016 1.016)
					(thickness 0.1524)
				)
			)
		)
		(property "Device Type" "C402H22"
			(at 1.1811 -4.2291 270)
			(unlocked yes)
			(layer "F.Fab")
			(hide yes)
			(effects
				(font
					(size 1.016 1.016)
					(thickness 0.1524)
				)
			)
		)
		(duplicate_pad_numbers_are_jumpers no)
		(fp_rect
			(start -0.4318 0.9525)
			(end 0.4318 -0.9525)
			(stroke
				(width 0)
				(type default)
			)
			(fill no)
			(layer "F.CrtYd")
		)
		(fp_rect
			(start -0.4318 0.9525)
			(end 0.4318 -0.9525)
			(stroke
				(width 0)
				(type default)
			)
			(fill no)
			(layer "F.Fab")
		)
		(pad "1" smd custom
			(at 0 -0.4445 270)
			(size 0.1524 0.1524)
			(layers "F.Cu" "F.Mask" "F.Paste")
			(net "CRFILT")
			(options
				(clearance outline)
				(anchor circle)
			)
			(primitives
				(gr_poly
					(pts
						(arc
							(start 0.3048 -0.2032)
							(mid 0.275042 -0.275042)
							(end 0.2032 -0.3048)
						)
						(arc
							(start -0.2032 -0.3048)
							(mid -0.275042 -0.275042)
							(end -0.3048 -0.2032)
						)
						(arc
							(start -0.3048 0.2032)
							(mid -0.275042 0.275042)
							(end -0.2032 0.3048)
						)
						(arc
							(start 0.2032 0.3048)
							(mid 0.275042 0.275042)
							(end 0.3048 0.2032)
						)
					)
					(width 0)
					(fill yes)
				)
			)
		)
		(pad "2" smd custom
			(at 0 0.4445 270)
			(size 0.1524 0.1524)
			(layers "F.Cu" "F.Mask" "F.Paste")
			(net "GND")
			(options
				(clearance outline)
				(anchor circle)
			)
			(primitives
				(gr_poly
					(pts
						(arc
							(start 0.3048 -0.2032)
							(mid 0.275042 -0.275042)
							(end 0.2032 -0.3048)
						)
						(arc
							(start -0.2032 -0.3048)
							(mid -0.275042 -0.275042)
							(end -0.3048 -0.2032)
						)
						(arc
							(start -0.3048 0.2032)
							(mid -0.275042 0.275042)
							(end -0.2032 0.3048)
						)
						(arc
							(start 0.2032 0.3048)
							(mid 0.275042 0.275042)
							(end 0.3048 0.2032)
						)
					)
					(width 0)
					(fill yes)
				)
			)
		)
	)
	(footprint ""
		(layer "F.Cu")
		(at 124.27458 -28.11653)
		(property "Reference" "U22"
			(at 0 0 0)
			(layer "F.SilkS")
			(hide yes)
			(effects
				(font
					(size 1.27 1.27)
				)
			)
		)
		(property "Value" "USB2513BT-M2-GP"
			(at -6.0198 -6.3246 0)
			(unlocked yes)
			(layer "F.Fab")
			(hide yes)
			(effects
				(font
					(size 1.016 1.016)
					(thickness 0.1524)
				)
			)
		)
		(property "Device Type" "QFN36-G3D8H40"
			(at -6.0198 -7.8486 0)
			(unlocked yes)
			(layer "F.Fab")
			(hide yes)
			(effects
				(font
					(size 1.016 1.016)
					(thickness 0.1524)
				)
			)
		)
		(duplicate_pad_numbers_are_jumpers no)
		(fp_line
			(start -4.5466 -2.0066)
			(end -3.7846 -2.0066)
			(stroke
				(width 0.1524)
				(type default)
			)
			(layer "F.SilkS")
		)
		(fp_line
			(start -4.2926 0.508)
			(end -3.7846 0.508)
			(stroke
				(width 0.1524)
				(type default)
			)
			(layer "F.SilkS")
		)
		(fp_line
			(start -4.0132 -4.0132)
			(end -4.0132 -2.7432)
			(stroke
				(width 0.1524)
				(type default)
			)
			(layer "F.SilkS")
		)
		(fp_line
			(start -4.0132 2.7432)
			(end -4.0132 4.0132)
			(stroke
				(width 0.1524)
				(type default)
			)
			(layer "F.SilkS")
		)
		(fp_line
			(start -4.0132 4.0132)
			(end -2.7432 4.0132)
			(stroke
				(width 0.1524)
				(type default)
			)
			(layer "F.SilkS")
		)
		(fp_line
			(start -2.7432 -4.0132)
			(end -4.0132 -4.0132)
			(stroke
				(width 0.1524)
				(type default)
			)
			(layer "F.SilkS")
		)
		(fp_line
			(start -1.4986 3.7846)
			(end -1.4986 4.5466)
			(stroke
				(width 0.1524)
				(type default)
			)
			(layer "F.SilkS")
		)
		(fp_line
			(start 0 -4.2926)
			(end 0 -3.7846)
			(stroke
				(width 0.1524)
				(type default)
			)
			(layer "F.SilkS")
		)
		(fp_line
			(start 0.9906 3.7846)
			(end 0.9906 4.2926)
			(stroke
				(width 0.1524)
				(type default)
			)
			(layer "F.SilkS")
		)
		(fp_line
			(start 2.7432 4.0132)
			(end 4.0132 4.0132)
			(stroke
				(width 0.1524)
				(type default)
			)
			(layer "F.SilkS")
		)
		(fp_line
			(start 3.7846 -1.4986)
			(end 4.2926 -1.4986)
			(stroke
				(width 0.1524)
				(type default)
			)
			(layer "F.SilkS")
		)
		(fp_line
			(start 3.7846 0.9906)
			(end 4.5466 0.9906)
			(stroke
				(width 0.1524)
				(type default)
			)
			(layer "F.SilkS")
		)
		(fp_line
			(start 4.0132 4.0132)
			(end 4.0132 2.7432)
			(stroke
				(width 0.1524)
				(type default)
			)
			(layer "F.SilkS")
		)
		(fp_poly
			(pts
				(xy 2.7432 -4.0132) (xy 4.0132 -4.0132) (xy 4.0132 -2.7432)
			)
			(stroke
				(width 0)
				(type default)
			)
			(fill yes)
			(layer "F.SilkS")
		)
		(fp_rect
			(start -2.9972 2.9972)
			(end 2.9972 -2.9972)
			(stroke
				(width 0)
				(type default)
			)
			(fill no)
			(layer "F.CrtYd")
		)
		(fp_poly
			(pts
				(xy -4.0132 4.0132) (xy -4.0132 -4.0132) (xy -2.9972 -4.0132) (xy -2.9972 2.9972) (xy 2.9972 2.9972)
				(xy 2.9972 -2.9972) (xy -2.99212 -2.9972) (xy -2.99212 -4.0132) (xy 4.0132 -4.0132) (xy 4.0132 4.0132)
			)
			(stroke
				(width 0)
				(type default)
			)
			(fill no)
			(layer "F.CrtYd")
		)
		(fp_rect
			(start -4.0132 4.0132)
			(end 4.0132 -4.0132)
			(stroke
				(width 0)
				(type default)
			)
			(fill no)
			(layer "F.Fab")
		)
		(pad "1" smd rect
			(at 1.999996 -2.921)
			(size 0.3048 1.1684)
			(layers "F.Cu" "F.Mask" "F.Paste")
			(net "USB_HUB_PCIE_DN0")
		)
		(pad "2" smd rect
			(at 1.500124 -2.8448)
			(size 0.3048 1.3208)
			(layers "F.Cu" "F.Mask" "F.Paste")
			(net "USB_HUB_PCIE_DP0")
		)
		(pad "3" smd rect
			(at 0.999998 -2.8448)
			(size 0.3048 1.3208)
			(layers "F.Cu" "F.Mask" "F.Paste")
			(net "USB_HUB_PCIE_DN1")
		)
		(pad "4" smd rect
			(at 0.500126 -2.8448)
			(size 0.3048 1.3208)
			(layers "F.Cu" "F.Mask" "F.Paste")
			(net "USB_HUB_PCIE_DP1")
		)
		(pad "5" smd rect
			(at 0 -2.8448)
			(size 0.3048 1.3208)
			(layers "F.Cu" "F.Mask" "F.Paste")
			(net "P3V3_USB_HUB")
		)
		(pad "6" smd rect
			(at -0.500126 -2.8448)
			(size 0.3048 1.3208)
			(layers "F.Cu" "F.Mask" "F.Paste")
			(net "USB_DN2")
		)
		(pad "7" smd rect
			(at -0.999998 -2.8448)
			(size 0.3048 1.3208)
			(layers "F.Cu" "F.Mask" "F.Paste")
			(net "USB_DP2")
		)
		(pad "8" smd rect
			(at -1.500124 -2.8448)
			(size 0.3048 1.3208)
			(layers "F.Cu" "F.Mask" "F.Paste")
			(net "TP_USB_DN3")
		)
		(pad "9" smd rect
			(at -1.999996 -2.921)
			(size 0.3048 1.1684)
			(layers "F.Cu" "F.Mask" "F.Paste")
			(net "TP_USB_DP3")
		)
		(pad "10" smd rect
			(at -2.921 -1.999996)
			(size 1.1684 0.3048)
			(layers "F.Cu" "F.Mask" "F.Paste")
			(net "P3V3_USB_HUB")
		)
		(pad "11" smd rect
			(at -2.8448 -1.500124)
			(size 1.3208 0.3048)
			(layers "F.Cu" "F.Mask" "F.Paste")
			(net "GND")
		)
		(pad "12" smd rect
			(at -2.8448 -0.999998)
			(size 1.3208 0.3048)
			(layers "F.Cu" "F.Mask" "F.Paste")
			(net "Net_311")
		)
		(pad "13" smd rect
			(at -2.8448 -0.500126)
			(size 1.3208 0.3048)
			(layers "F.Cu" "F.Mask" "F.Paste")
			(net "TP_USB_OCS_N1")
		)
		(pad "14" smd rect
			(at -2.8448 0)
			(size 1.3208 0.3048)
			(layers "F.Cu" "F.Mask" "F.Paste")
			(net "CRFILT")
		)
		(pad "15" smd rect
			(at -2.8448 0.500126)
			(size 1.3208 0.3048)
			(layers "F.Cu" "F.Mask" "F.Paste")
			(net "P3V3_USB_HUB")
		)
		(pad "16" smd rect
			(at -2.8448 0.999998)
			(size 1.3208 0.3048)
			(layers "F.Cu" "F.Mask" "F.Paste")
			(net "Net_312")
		)
		(pad "17" smd rect
			(at -2.8448 1.500124)
			(size 1.3208 0.3048)
			(layers "F.Cu" "F.Mask" "F.Paste")
			(net "TP_USB_OCS_N2")
		)
		(pad "18" smd rect
			(at -2.921 1.999996)
			(size 1.1684 0.3048)
			(layers "F.Cu" "F.Mask" "F.Paste")
			(net "Net_313")
		)
		(pad "19" smd rect
			(at -1.999996 2.921)
			(size 0.3048 1.1684)
			(layers "F.Cu" "F.Mask" "F.Paste")
			(net "TP_USB_OCS_N3")
		)
		(pad "20" smd rect
			(at -1.500124 2.8448)
			(size 0.3048 1.3208)
			(layers "F.Cu" "F.Mask" "F.Paste")
			(net "Net_310")
		)
		(pad "21" smd rect
			(at -0.999998 2.8448)
			(size 0.3048 1.3208)
			(layers "F.Cu" "F.Mask" "F.Paste")
			(net "TP_USB_OCS_N4")
		)
		(pad "22" smd rect
			(at -0.500126 2.8448)
			(size 0.3048 1.3208)
			(layers "F.Cu" "F.Mask" "F.Paste")
			(net "SMDAT_USB_HUB_R")
		)
		(pad "23" smd rect
			(at 0 2.8448)
			(size 0.3048 1.3208)
			(layers "F.Cu" "F.Mask" "F.Paste")
			(net "P3V3_USB_HUB")
		)
		(pad "24" smd rect
			(at 0.500126 2.8448)
			(size 0.3048 1.3208)
			(layers "F.Cu" "F.Mask" "F.Paste")
			(net "SMCLK_USB_HUB_R")
		)
		(pad "25" smd rect
			(at 0.999998 2.8448)
			(size 0.3048 1.3208)
			(layers "F.Cu" "F.Mask" "F.Paste")
			(net "CFG_SEL1")
		)
		(pad "26" smd rect
			(at 1.500124 2.8448)
			(size 0.3048 1.3208)
			(layers "F.Cu" "F.Mask" "F.Paste")
			(net "USB_RESET_N")
		)
		(pad "27" smd rect
			(at 1.999996 2.921)
			(size 0.3048 1.1684)
			(layers "F.Cu" "F.Mask" "F.Paste")
			(net "VBUS_DET")
		)
		(pad "28" smd rect
			(at 2.921 1.999996)
			(size 1.1684 0.3048)
			(layers "F.Cu" "F.Mask" "F.Paste")
			(net "NON_REM0")
		)
		(pad "29" smd rect
			(at 2.8448 1.500124)
			(size 1.3208 0.3048)
			(layers "F.Cu" "F.Mask" "F.Paste")
			(net "P3V3_USB_HUB")
		)
		(pad "30" smd rect
			(at 2.8448 0.999998)
			(size 1.3208 0.3048)
			(layers "F.Cu" "F.Mask" "F.Paste")
			(net "USB2_P02_DN")
		)
		(pad "31" smd rect
			(at 2.8448 0.500126)
			(size 1.3208 0.3048)
			(layers "F.Cu" "F.Mask" "F.Paste")
			(net "USB2_P02_DP")
		)
		(pad "32" smd rect
			(at 2.8448 0)
			(size 1.3208 0.3048)
			(layers "F.Cu" "F.Mask" "F.Paste")
			(net "USB_HUB_XTAL_OUT")
		)
		(pad "33" smd rect
			(at 2.8448 -0.500126)
			(size 1.3208 0.3048)
			(layers "F.Cu" "F.Mask" "F.Paste")
			(net "USB_HUB_XTAL_IN")
		)
		(pad "34" smd rect
			(at 2.8448 -0.999998)
			(size 1.3208 0.3048)
			(layers "F.Cu" "F.Mask" "F.Paste")
			(net "PLLFILT")
		)
		(pad "35" smd rect
			(at 2.8448 -1.500124)
			(size 1.3208 0.3048)
			(layers "F.Cu" "F.Mask" "F.Paste")
			(net "RBIAS")
		)
		(pad "36" smd rect
			(at 2.921 -1.999996)
			(size 1.1684 0.3048)
			(layers "F.Cu" "F.Mask" "F.Paste")
			(net "P3V3_USB_HUB")
		)
		(pad "37" smd rect
			(at 0 0)
			(size 3.81 3.81)
			(layers "F.Cu" "F.Mask" "F.Paste")
			(net "GND")
		)
	)
	(footprint ""
		(layer "F.Cu")
		(at 128.7018 -22.479 90)
		(property "Reference" "CU13"
			(at 0 0 90)
			(layer "F.SilkS")
			(hide yes)
			(effects
				(font
					(size 1.27 1.27)
				)
			)
		)
		(property "Value" "SCD1U16V2KX-3GP"
			(at 1.1811 -2.7051 90)
			(unlocked yes)
			(layer "F.Fab")
			(hide yes)
			(effects
				(font
					(size 1.016 1.016)
					(thickness 0.1524)
				)
			)
		)
		(property "Device Type" "C402H22"
			(at 1.1811 -4.2291 90)
			(unlocked yes)
			(layer "F.Fab")
			(hide yes)
			(effects
				(font
					(size 1.016 1.016)
					(thickness 0.1524)
				)
			)
		)
		(duplicate_pad_numbers_are_jumpers no)
		(fp_rect
			(start -0.4318 0.9525)
			(end 0.4318 -0.9525)
			(stroke
				(width 0)
				(type default)
			)
			(fill no)
			(layer "F.CrtYd")
		)
		(fp_rect
			(start -0.4318 0.9525)
			(end 0.4318 -0.9525)
			(stroke
				(width 0)
				(type default)
			)
			(fill no)
			(layer "F.Fab")
		)
		(pad "1" smd custom
			(at 0 -0.4445 90)
			(size 0.1524 0.1524)
			(layers "F.Cu" "F.Mask" "F.Paste")
			(net "VBUS_DET")
			(options
				(clearance outline)
				(anchor circle)
			)
			(primitives
				(gr_poly
					(pts
						(arc
							(start 0.3048 -0.2032)
							(mid 0.275042 -0.275042)
							(end 0.2032 -0.3048)
						)
						(arc
							(start -0.2032 -0.3048)
							(mid -0.275042 -0.275042)
							(end -0.3048 -0.2032)
						)
						(arc
							(start -0.3048 0.2032)
							(mid -0.275042 0.275042)
							(end -0.2032 0.3048)
						)
						(arc
							(start 0.2032 0.3048)
							(mid 0.275042 0.275042)
							(end 0.3048 0.2032)
						)
					)
					(width 0)
					(fill yes)
				)
			)
		)
		(pad "2" smd custom
			(at 0 0.4445 90)
			(size 0.1524 0.1524)
			(layers "F.Cu" "F.Mask" "F.Paste")
			(net "GND")
			(options
				(clearance outline)
				(anchor circle)
			)
			(primitives
				(gr_poly
					(pts
						(arc
							(start 0.3048 -0.2032)
							(mid 0.275042 -0.275042)
							(end 0.2032 -0.3048)
						)
						(arc
							(start -0.2032 -0.3048)
							(mid -0.275042 -0.275042)
							(end -0.3048 -0.2032)
						)
						(arc
							(start -0.3048 0.2032)
							(mid -0.275042 0.275042)
							(end -0.2032 0.3048)
						)
						(arc
							(start 0.2032 0.3048)
							(mid 0.275042 0.275042)
							(end 0.3048 0.2032)
						)
					)
					(width 0)
					(fill yes)
				)
			)
		)
	)
	(footprint ""
		(layer "F.Cu")
		(at 119.634 -11.2522 90)
		(property "Reference" "R171"
			(at 0 0 90)
			(layer "F.SilkS")
			(hide yes)
			(effects
				(font
					(size 1.27 1.27)
				)
			)
		)
		(property "Value" "4K7R2F-GP"
			(at 0.064008 -3.993896 90)
			(unlocked yes)
			(layer "F.Fab")
			(hide yes)
			(effects
				(font
					(size 1.016 1.016)
					(thickness 0.1524)
				)
			)
		)
		(property "Device Type" "R402H16"
			(at 0.064008 -5.517896 90)
			(unlocked yes)
			(layer "F.Fab")
			(hide yes)
			(effects
				(font
					(size 1.016 1.016)
					(thickness 0.1524)
				)
			)
		)
		(duplicate_pad_numbers_are_jumpers no)
		(fp_line
			(start 0.508 -0.9398)
			(end -0.508 -0.9398)
			(stroke
				(width 0.1524)
				(type default)
			)
			(layer "F.SilkS")
		)
		(fp_line
			(start -0.508 -0.9398)
			(end -0.508 0.9398)
			(stroke
				(width 0.1524)
				(type default)
			)
			(layer "F.SilkS")
		)
		(fp_rect
			(start -0.508 0.9398)
			(end 0.508 -0.9398)
			(stroke
				(width 0)
				(type default)
			)
			(fill no)
			(layer "F.CrtYd")
		)
		(fp_rect
			(start -0.508 0.9398)
			(end 0.508 -0.9398)
			(stroke
				(width 0)
				(type default)
			)
			(fill no)
			(layer "F.Fab")
		)
		(pad "1" smd custom
			(at 0 -0.4445 90)
			(size 0.1397 0.1397)
			(layers "F.Cu" "F.Mask" "F.Paste")
			(net "P3V3_STBY")
			(options
				(clearance outline)
				(anchor circle)
			)
			(primitives
				(gr_poly
					(pts
						(arc
							(start -0.1778 -0.2794)
							(mid -0.249642 -0.249642)
							(end -0.2794 -0.1778)
						)
						(arc
							(start -0.2794 0.1778)
							(mid -0.249642 0.249642)
							(end -0.1778 0.2794)
						)
						(arc
							(start 0.1778 0.2794)
							(mid 0.249642 0.249642)
							(end 0.2794 0.1778)
						)
						(arc
							(start 0.2794 -0.1778)
							(mid 0.249642 -0.249642)
							(end 0.1778 -0.2794)
						)
					)
					(width 0)
					(fill yes)
				)
			)
		)
		(pad "2" smd custom
			(at 0 0.4445 90)
			(size 0.1397 0.1397)
			(layers "F.Cu" "F.Mask" "F.Paste")
			(net "PCIE_SLOT3_PRSNT2_4_N")
			(options
				(clearance outline)
				(anchor circle)
			)
			(primitives
				(gr_poly
					(pts
						(arc
							(start -0.1778 -0.2794)
							(mid -0.249642 -0.249642)
							(end -0.2794 -0.1778)
						)
						(arc
							(start -0.2794 0.1778)
							(mid -0.249642 0.249642)
							(end -0.1778 0.2794)
						)
						(arc
							(start 0.1778 0.2794)
							(mid 0.249642 0.249642)
							(end 0.2794 0.1778)
						)
						(arc
							(start 0.2794 -0.1778)
							(mid 0.249642 -0.249642)
							(end 0.1778 -0.2794)
						)
					)
					(width 0)
					(fill yes)
				)
			)
		)
	)
	(footprint ""
		(layer "F.Cu")
		(at 18.5928 -23.4696 180)
		(property "Reference" "C49"
			(at 0 0 180)
			(layer "F.SilkS")
			(hide yes)
			(effects
				(font
					(size 1.27 1.27)
				)
			)
		)
		(property "Value" "SCD1U25V2KX-2-GP"
			(at 1.1811 -2.7051 180)
			(unlocked yes)
			(layer "F.Fab")
			(hide yes)
			(effects
				(font
					(size 1.016 1.016)
					(thickness 0.1524)
				)
			)
		)
		(property "Device Type" "C402H22"
			(at 1.1811 -4.2291 180)
			(unlocked yes)
			(layer "F.Fab")
			(hide yes)
			(effects
				(font
					(size 1.016 1.016)
					(thickness 0.1524)
				)
			)
		)
		(duplicate_pad_numbers_are_jumpers no)
		(fp_rect
			(start -0.4318 0.9525)
			(end 0.4318 -0.9525)
			(stroke
				(width 0)
				(type default)
			)
			(fill no)
			(layer "F.CrtYd")
		)
		(fp_rect
			(start -0.4318 0.9525)
			(end 0.4318 -0.9525)
			(stroke
				(width 0)
				(type default)
			)
			(fill no)
			(layer "F.Fab")
		)
		(pad "1" smd custom
			(at 0 -0.4445 180)
			(size 0.1524 0.1524)
			(layers "F.Cu" "F.Mask" "F.Paste")
			(net "SLOT3_P12V_SENSE_VP_R")
			(options
				(clearance outline)
				(anchor circle)
			)
			(primitives
				(gr_poly
					(pts
						(arc
							(start 0.3048 -0.2032)
							(mid 0.275042 -0.275042)
							(end 0.2032 -0.3048)
						)
						(arc
							(start -0.2032 -0.3048)
							(mid -0.275042 -0.275042)
							(end -0.3048 -0.2032)
						)
						(arc
							(start -0.3048 0.2032)
							(mid -0.275042 0.275042)
							(end -0.2032 0.3048)
						)
						(arc
							(start 0.2032 0.3048)
							(mid 0.275042 0.275042)
							(end 0.3048 0.2032)
						)
					)
					(width 0)
					(fill yes)
				)
			)
		)
		(pad "2" smd custom
			(at 0 0.4445 180)
			(size 0.1524 0.1524)
			(layers "F.Cu" "F.Mask" "F.Paste")
			(net "SLOT3_P12V_SENSE_VN_R")
			(options
				(clearance outline)
				(anchor circle)
			)
			(primitives
				(gr_poly
					(pts
						(arc
							(start 0.3048 -0.2032)
							(mid 0.275042 -0.275042)
							(end 0.2032 -0.3048)
						)
						(arc
							(start -0.2032 -0.3048)
							(mid -0.275042 -0.275042)
							(end -0.3048 -0.2032)
						)
						(arc
							(start -0.3048 0.2032)
							(mid -0.275042 0.275042)
							(end -0.2032 0.3048)
						)
						(arc
							(start 0.2032 0.3048)
							(mid 0.275042 0.275042)
							(end 0.3048 0.2032)
						)
					)
					(width 0)
					(fill yes)
				)
			)
		)
	)
	(footprint ""
		(layer "B.Cu")
		(at 15.1257 -27.3177 -45)
		(property "Reference" "R103"
			(at 0 0 135)
			(layer "B.SilkS")
			(hide yes)
			(effects
				(font
					(size 1.27 1.27)
				)
				(justify mirror)
			)
		)
		(property "Value" "10R2F-L-GP"
			(at -0.06376 -3.993804 315)
			(unlocked yes)
			(layer "B.Fab")
			(hide yes)
			(effects
				(font
					(size 1.016 1.016)
					(thickness 0.1524)
				)
				(justify mirror)
			)
		)
		(property "Device Type" "R402H14"
			(at -0.064119 -5.517933 315)
			(unlocked yes)
			(layer "B.Fab")
			(hide yes)
			(effects
				(font
					(size 1.016 1.016)
					(thickness 0.1524)
				)
				(justify mirror)
			)
		)
		(duplicate_pad_numbers_are_jumpers no)
		(fp_line
			(start -0.508103 -0.939874)
			(end 0.508282 -0.939694)
			(stroke
				(width 0.1524)
				(type default)
			)
			(layer "B.SilkS")
		)
		(fp_line
			(start 0.508282 -0.939694)
			(end 0.508282 0.940053)
			(stroke
				(width 0.1524)
				(type default)
			)
			(layer "B.SilkS")
		)
		(fp_poly
			(pts
				(xy -0.507717 0.940053) (xy -0.507718 -0.939546) (xy 0.508282 -0.939547) (xy 0.508282 0.940053)
			)
			(stroke
				(width 0)
				(type default)
			)
			(fill no)
			(layer "B.CrtYd")
		)
		(fp_poly
			(pts
				(xy -0.507717 0.940053) (xy -0.507718 -0.939546) (xy 0.508282 -0.939547) (xy 0.508282 0.940053)
			)
			(stroke
				(width 0)
				(type default)
			)
			(fill no)
			(layer "B.Fab")
		)
		(pad "1" smd custom
			(at 0 -0.4445 135)
			(size 0.1397 0.1397)
			(layers "B.Cu" "B.Mask" "B.Paste")
			(net "P12V_ATX")
			(options
				(clearance outline)
				(anchor circle)
			)
			(primitives
				(gr_poly
					(pts
						(arc
							(start -0.1778 0.2794)
							(mid -0.249642 0.249642)
							(end -0.2794 0.1778)
						)
						(arc
							(start -0.2794 -0.1778)
							(mid -0.249642 -0.249642)
							(end -0.1778 -0.2794)
						)
						(arc
							(start 0.1778 -0.2794)
							(mid 0.249642 -0.249642)
							(end 0.2794 -0.1778)
						)
						(arc
							(start 0.2794 0.1778)
							(mid 0.249642 0.249642)
							(end 0.1778 0.2794)
						)
					)
					(width 0)
					(fill yes)
				)
			)
		)
		(pad "2" smd custom
			(at 0 0.4445 135)
			(size 0.1397 0.1397)
			(layers "B.Cu" "B.Mask" "B.Paste")
			(net "ATX_P12V_SENSE_VN_R")
			(options
				(clearance outline)
				(anchor circle)
			)
			(primitives
				(gr_poly
					(pts
						(arc
							(start -0.1778 0.2794)
							(mid -0.249642 0.249642)
							(end -0.2794 0.1778)
						)
						(arc
							(start -0.2794 -0.1778)
							(mid -0.249642 -0.249642)
							(end -0.1778 -0.2794)
						)
						(arc
							(start 0.1778 -0.2794)
							(mid 0.249642 -0.249642)
							(end 0.2794 -0.1778)
						)
						(arc
							(start 0.2794 0.1778)
							(mid 0.249642 0.249642)
							(end 0.1778 0.2794)
						)
					)
					(width 0)
					(fill yes)
				)
			)
		)
	)
	(footprint ""
		(layer "B.Cu")
		(at 26.3652 -25.6032 180)
		(property "Reference" "R148"
			(at 0 0 0)
			(layer "B.SilkS")
			(hide yes)
			(effects
				(font
					(size 1.27 1.27)
				)
				(justify mirror)
			)
		)
		(property "Value" "10KR2F-2-GP"
			(at -0.064008 -3.993896 180)
			(unlocked yes)
			(layer "B.Fab")
			(hide yes)
			(effects
				(font
					(size 1.016 1.016)
					(thickness 0.1524)
				)
				(justify mirror)
			)
		)
		(property "Device Type" "R402H16"
			(at -0.064008 -5.517896 180)
			(unlocked yes)
			(layer "B.Fab")
			(hide yes)
			(effects
				(font
					(size 1.016 1.016)
					(thickness 0.1524)
				)
				(justify mirror)
			)
		)
		(duplicate_pad_numbers_are_jumpers no)
		(fp_line
			(start 0.508 -0.9398)
			(end 0.508 0.9398)
			(stroke
				(width 0.1524)
				(type default)
			)
			(layer "B.SilkS")
		)
		(fp_line
			(start -0.508 -0.9398)
			(end 0.508 -0.9398)
			(stroke
				(width 0.1524)
				(type default)
			)
			(layer "B.SilkS")
		)
		(fp_rect
			(start 0.508 0.9398)
			(end -0.508 -0.9398)
			(stroke
				(width 0)
				(type default)
			)
			(fill no)
			(layer "B.CrtYd")
		)
		(fp_rect
			(start 0.508 0.9398)
			(end -0.508 -0.9398)
			(stroke
				(width 0)
				(type default)
			)
			(fill no)
			(layer "B.Fab")
		)
		(pad "1" smd custom
			(at 0 -0.4445)
			(size 0.1397 0.1397)
			(layers "B.Cu" "B.Mask" "B.Paste")
			(net "P3V3_STBY")
			(options
				(clearance outline)
				(anchor circle)
			)
			(primitives
				(gr_poly
					(pts
						(arc
							(start -0.1778 0.2794)
							(mid -0.249642 0.249642)
							(end -0.2794 0.1778)
						)
						(arc
							(start -0.2794 -0.1778)
							(mid -0.249642 -0.249642)
							(end -0.1778 -0.2794)
						)
						(arc
							(start 0.1778 -0.2794)
							(mid 0.249642 -0.249642)
							(end 0.2794 -0.1778)
						)
						(arc
							(start 0.2794 0.1778)
							(mid 0.249642 0.249642)
							(end 0.1778 0.2794)
						)
					)
					(width 0)
					(fill yes)
				)
			)
		)
		(pad "2" smd custom
			(at 0 0.4445)
			(size 0.1397 0.1397)
			(layers "B.Cu" "B.Mask" "B.Paste")
			(net "ATX_VMONITOR_A1")
			(options
				(clearance outline)
				(anchor circle)
			)
			(primitives
				(gr_poly
					(pts
						(arc
							(start -0.1778 0.2794)
							(mid -0.249642 0.249642)
							(end -0.2794 0.1778)
						)
						(arc
							(start -0.2794 -0.1778)
							(mid -0.249642 -0.249642)
							(end -0.1778 -0.2794)
						)
						(arc
							(start 0.1778 -0.2794)
							(mid 0.249642 -0.249642)
							(end 0.2794 -0.1778)
						)
						(arc
							(start 0.2794 0.1778)
							(mid 0.249642 0.249642)
							(end 0.1778 0.2794)
						)
					)
					(width 0)
					(fill yes)
				)
			)
		)
	)
	(footprint ""
		(layer "B.Cu")
		(at 117.7925 -2.35712)
		(property "Reference" "R59"
			(at 0 0 0)
			(layer "B.SilkS")
			(hide yes)
			(effects
				(font
					(size 1.27 1.27)
				)
				(justify mirror)
			)
		)
		(property "Value" "10KR2F-2-GP"
			(at -0.064008 -3.993896 0)
			(unlocked yes)
			(layer "B.Fab")
			(hide yes)
			(effects
				(font
					(size 1.016 1.016)
					(thickness 0.1524)
				)
				(justify mirror)
			)
		)
		(property "Device Type" "R402H16"
			(at -0.064008 -5.517896 0)
			(unlocked yes)
			(layer "B.Fab")
			(hide yes)
			(effects
				(font
					(size 1.016 1.016)
					(thickness 0.1524)
				)
				(justify mirror)
			)
		)
		(duplicate_pad_numbers_are_jumpers no)
		(fp_line
			(start -0.508 -0.9398)
			(end 0.508 -0.9398)
			(stroke
				(width 0.1524)
				(type default)
			)
			(layer "B.SilkS")
		)
		(fp_line
			(start 0.508 -0.9398)
			(end 0.508 0.9398)
			(stroke
				(width 0.1524)
				(type default)
			)
			(layer "B.SilkS")
		)
		(fp_rect
			(start 0.508 0.9398)
			(end -0.508 -0.9398)
			(stroke
				(width 0)
				(type default)
			)
			(fill no)
			(layer "B.CrtYd")
		)
		(fp_rect
			(start 0.508 0.9398)
			(end -0.508 -0.9398)
			(stroke
				(width 0)
				(type default)
			)
			(fill no)
			(layer "B.Fab")
		)
		(pad "1" smd custom
			(at 0 -0.4445 180)
			(size 0.1397 0.1397)
			(layers "B.Cu" "B.Mask" "B.Paste")
			(net "SMB_BMC_DEVICE_ALERT_N")
			(options
				(clearance outline)
				(anchor circle)
			)
			(primitives
				(gr_poly
					(pts
						(arc
							(start -0.1778 0.2794)
							(mid -0.249642 0.249642)
							(end -0.2794 0.1778)
						)
						(arc
							(start -0.2794 -0.1778)
							(mid -0.249642 -0.249642)
							(end -0.1778 -0.2794)
						)
						(arc
							(start 0.1778 -0.2794)
							(mid 0.249642 -0.249642)
							(end 0.2794 -0.1778)
						)
						(arc
							(start 0.2794 0.1778)
							(mid 0.249642 0.249642)
							(end 0.1778 0.2794)
						)
					)
					(width 0)
					(fill yes)
				)
			)
		)
		(pad "2" smd custom
			(at 0 0.4445 180)
			(size 0.1397 0.1397)
			(layers "B.Cu" "B.Mask" "B.Paste")
			(net "P3V3_STBY")
			(options
				(clearance outline)
				(anchor circle)
			)
			(primitives
				(gr_poly
					(pts
						(arc
							(start -0.1778 0.2794)
							(mid -0.249642 0.249642)
							(end -0.2794 0.1778)
						)
						(arc
							(start -0.2794 -0.1778)
							(mid -0.249642 -0.249642)
							(end -0.1778 -0.2794)
						)
						(arc
							(start 0.1778 -0.2794)
							(mid 0.249642 -0.249642)
							(end 0.2794 -0.1778)
						)
						(arc
							(start 0.2794 0.1778)
							(mid 0.249642 0.249642)
							(end 0.1778 0.2794)
						)
					)
					(width 0)
					(fill yes)
				)
			)
		)
	)
	(footprint ""
		(layer "B.Cu")
		(at 124.2822 -25.7048 180)
		(property "Reference" "CU7"
			(at 0 0 0)
			(layer "B.SilkS")
			(hide yes)
			(effects
				(font
					(size 1.27 1.27)
				)
				(justify mirror)
			)
		)
		(property "Value" "SC1U10V2KX-4-GP"
			(at -1.1811 -2.7051 180)
			(unlocked yes)
			(layer "B.Fab")
			(hide yes)
			(effects
				(font
					(size 1.016 1.016)
					(thickness 0.1524)
				)
				(justify mirror)
			)
		)
		(property "Device Type" "C402H22"
			(at -1.1811 -4.2291 180)
			(unlocked yes)
			(layer "B.Fab")
			(hide yes)
			(effects
				(font
					(size 1.016 1.016)
					(thickness 0.1524)
				)
				(justify mirror)
			)
		)
		(duplicate_pad_numbers_are_jumpers no)
		(fp_rect
			(start 0.4318 0.9525)
			(end -0.4318 -0.9525)
			(stroke
				(width 0)
				(type default)
			)
			(fill no)
			(layer "B.CrtYd")
		)
		(fp_rect
			(start 0.4318 0.9525)
			(end -0.4318 -0.9525)
			(stroke
				(width 0)
				(type default)
			)
			(fill no)
			(layer "B.Fab")
		)
		(pad "1" smd custom
			(at 0 -0.4445)
			(size 0.1524 0.1524)
			(layers "B.Cu" "B.Mask" "B.Paste")
			(net "P3V3_USB_HUB")
			(options
				(clearance outline)
				(anchor circle)
			)
			(primitives
				(gr_poly
					(pts
						(arc
							(start 0.3048 0.2032)
							(mid 0.275042 0.275042)
							(end 0.2032 0.3048)
						)
						(arc
							(start -0.2032 0.3048)
							(mid -0.275042 0.275042)
							(end -0.3048 0.2032)
						)
						(arc
							(start -0.3048 -0.2032)
							(mid -0.275042 -0.275042)
							(end -0.2032 -0.3048)
						)
						(arc
							(start 0.2032 -0.3048)
							(mid 0.275042 -0.275042)
							(end 0.3048 -0.2032)
						)
					)
					(width 0)
					(fill yes)
				)
			)
		)
		(pad "2" smd custom
			(at 0 0.4445)
			(size 0.1524 0.1524)
			(layers "B.Cu" "B.Mask" "B.Paste")
			(net "GND")
			(options
				(clearance outline)
				(anchor circle)
			)
			(primitives
				(gr_poly
					(pts
						(arc
							(start 0.3048 0.2032)
							(mid 0.275042 0.275042)
							(end 0.2032 0.3048)
						)
						(arc
							(start -0.2032 0.3048)
							(mid -0.275042 0.275042)
							(end -0.3048 0.2032)
						)
						(arc
							(start -0.3048 -0.2032)
							(mid -0.275042 -0.275042)
							(end -0.2032 -0.3048)
						)
						(arc
							(start 0.2032 -0.3048)
							(mid 0.275042 -0.275042)
							(end 0.3048 -0.2032)
						)
					)
					(width 0)
					(fill yes)
				)
			)
		)
	)
	(footprint ""
		(layer "B.Cu")
		(at 120.92178 -4.68122 90)
		(property "Reference" "R20"
			(at 0 0 90)
			(layer "B.SilkS")
			(hide yes)
			(effects
				(font
					(size 1.27 1.27)
				)
				(justify mirror)
			)
		)
		(property "Value" "4K7R2F-GP"
			(at -0.064008 -3.993896 90)
			(unlocked yes)
			(layer "B.Fab")
			(hide yes)
			(effects
				(font
					(size 1.016 1.016)
					(thickness 0.1524)
				)
				(justify mirror)
			)
		)
		(property "Device Type" "R402H16"
			(at -0.064008 -5.517896 90)
			(unlocked yes)
			(layer "B.Fab")
			(hide yes)
			(effects
				(font
					(size 1.016 1.016)
					(thickness 0.1524)
				)
				(justify mirror)
			)
		)
		(duplicate_pad_numbers_are_jumpers no)
		(fp_line
			(start 0.508 -0.9398)
			(end 0.508 0.9398)
			(stroke
				(width 0.1524)
				(type default)
			)
			(layer "B.SilkS")
		)
		(fp_line
			(start -0.508 -0.9398)
			(end 0.508 -0.9398)
			(stroke
				(width 0.1524)
				(type default)
			)
			(layer "B.SilkS")
		)
		(fp_rect
			(start 0.508 0.9398)
			(end -0.508 -0.9398)
			(stroke
				(width 0)
				(type default)
			)
			(fill no)
			(layer "B.CrtYd")
		)
		(fp_rect
			(start 0.508 0.9398)
			(end -0.508 -0.9398)
			(stroke
				(width 0)
				(type default)
			)
			(fill no)
			(layer "B.Fab")
		)
		(pad "1" smd custom
			(at 0 -0.4445 270)
			(size 0.1397 0.1397)
			(layers "B.Cu" "B.Mask" "B.Paste")
			(net "P3V3_STBY")
			(options
				(clearance outline)
				(anchor circle)
			)
			(primitives
				(gr_poly
					(pts
						(arc
							(start -0.1778 0.2794)
							(mid -0.249642 0.249642)
							(end -0.2794 0.1778)
						)
						(arc
							(start -0.2794 -0.1778)
							(mid -0.249642 -0.249642)
							(end -0.1778 -0.2794)
						)
						(arc
							(start 0.1778 -0.2794)
							(mid 0.249642 -0.249642)
							(end 0.2794 -0.1778)
						)
						(arc
							(start 0.2794 0.1778)
							(mid 0.249642 0.249642)
							(end 0.1778 0.2794)
						)
					)
					(width 0)
					(fill yes)
				)
			)
		)
		(pad "2" smd custom
			(at 0 0.4445 270)
			(size 0.1397 0.1397)
			(layers "B.Cu" "B.Mask" "B.Paste")
			(net "SMDAT_PCH_SLOT2")
			(options
				(clearance outline)
				(anchor circle)
			)
			(primitives
				(gr_poly
					(pts
						(arc
							(start -0.1778 0.2794)
							(mid -0.249642 0.249642)
							(end -0.2794 0.1778)
						)
						(arc
							(start -0.2794 -0.1778)
							(mid -0.249642 -0.249642)
							(end -0.1778 -0.2794)
						)
						(arc
							(start 0.1778 -0.2794)
							(mid 0.249642 -0.249642)
							(end 0.2794 -0.1778)
						)
						(arc
							(start 0.2794 0.1778)
							(mid 0.249642 0.249642)
							(end 0.1778 0.2794)
						)
					)
					(width 0)
					(fill yes)
				)
			)
		)
	)
	(footprint ""
		(layer "B.Cu")
		(at 29.9085 -2.0066 180)
		(property "Reference" "PC8"
			(at 0 0 0)
			(layer "B.SilkS")
			(hide yes)
			(effects
				(font
					(size 1.27 1.27)
				)
				(justify mirror)
			)
		)
		(property "Value" "SC22U6D3V5MX-5-GP"
			(at 0.0762 -6.1214 180)
			(unlocked yes)
			(layer "B.Fab")
			(hide yes)
			(effects
				(font
					(size 1.016 1.016)
					(thickness 0.1524)
				)
				(justify mirror)
			)
		)
		(property "Device Type" "C805H56"
			(at 0.0762 -8.1534 180)
			(unlocked yes)
			(layer "B.Fab")
			(hide yes)
			(effects
				(font
					(size 1.016 1.016)
					(thickness 0.1524)
				)
				(justify mirror)
			)
		)
		(duplicate_pad_numbers_are_jumpers no)
		(fp_line
			(start -0.635 0)
			(end 0.635 0)
			(stroke
				(width 0.508)
				(type default)
			)
			(layer "B.SilkS")
		)
		(fp_rect
			(start 0.9652 1.778)
			(end -0.9652 -1.778)
			(stroke
				(width 0)
				(type default)
			)
			(fill no)
			(layer "B.CrtYd")
		)
		(fp_poly
			(pts
				(xy 0.9652 -1.778) (xy -0.9652 -1.778) (xy -0.9652 1.778) (xy 0.9652 1.778)
			)
			(stroke
				(width 0)
				(type default)
			)
			(fill no)
			(layer "B.Fab")
		)
		(pad "1" smd rect
			(at 0 -0.9652)
			(size 1.397 1.143)
			(layers "B.Cu" "B.Mask" "B.Paste")
			(net "P3V3_VR")
		)
		(pad "2" smd rect
			(at 0 0.9652)
			(size 1.397 1.143)
			(layers "B.Cu" "B.Mask" "B.Paste")
			(net "GND")
		)
	)
	(footprint ""
		(layer "B.Cu")
		(at 115.54968 -3.53568)
		(property "Reference" "R55"
			(at 0 0 0)
			(layer "B.SilkS")
			(hide yes)
			(effects
				(font
					(size 1.27 1.27)
				)
				(justify mirror)
			)
		)
		(property "Value" "10KR2F-2-GP"
			(at -0.064008 -3.993896 0)
			(unlocked yes)
			(layer "B.Fab")
			(hide yes)
			(effects
				(font
					(size 1.016 1.016)
					(thickness 0.1524)
				)
				(justify mirror)
			)
		)
		(property "Device Type" "R402H16"
			(at -0.064008 -5.517896 0)
			(unlocked yes)
			(layer "B.Fab")
			(hide yes)
			(effects
				(font
					(size 1.016 1.016)
					(thickness 0.1524)
				)
				(justify mirror)
			)
		)
		(duplicate_pad_numbers_are_jumpers no)
		(fp_line
			(start -0.508 -0.9398)
			(end 0.508 -0.9398)
			(stroke
				(width 0.1524)
				(type default)
			)
			(layer "B.SilkS")
		)
		(fp_line
			(start 0.508 -0.9398)
			(end 0.508 0.9398)
			(stroke
				(width 0.1524)
				(type default)
			)
			(layer "B.SilkS")
		)
		(fp_rect
			(start 0.508 0.9398)
			(end -0.508 -0.9398)
			(stroke
				(width 0)
				(type default)
			)
			(fill no)
			(layer "B.CrtYd")
		)
		(fp_rect
			(start 0.508 0.9398)
			(end -0.508 -0.9398)
			(stroke
				(width 0)
				(type default)
			)
			(fill no)
			(layer "B.Fab")
		)
		(pad "1" smd custom
			(at 0 -0.4445 180)
			(size 0.1397 0.1397)
			(layers "B.Cu" "B.Mask" "B.Paste")
			(net "SMB_PCIE_SLOT3_ALERT_N")
			(options
				(clearance outline)
				(anchor circle)
			)
			(primitives
				(gr_poly
					(pts
						(arc
							(start -0.1778 0.2794)
							(mid -0.249642 0.249642)
							(end -0.2794 0.1778)
						)
						(arc
							(start -0.2794 -0.1778)
							(mid -0.249642 -0.249642)
							(end -0.1778 -0.2794)
						)
						(arc
							(start 0.1778 -0.2794)
							(mid 0.249642 -0.249642)
							(end 0.2794 -0.1778)
						)
						(arc
							(start 0.2794 0.1778)
							(mid 0.249642 0.249642)
							(end 0.1778 0.2794)
						)
					)
					(width 0)
					(fill yes)
				)
			)
		)
		(pad "2" smd custom
			(at 0 0.4445 180)
			(size 0.1397 0.1397)
			(layers "B.Cu" "B.Mask" "B.Paste")
			(net "P3V3_STBY")
			(options
				(clearance outline)
				(anchor circle)
			)
			(primitives
				(gr_poly
					(pts
						(arc
							(start -0.1778 0.2794)
							(mid -0.249642 0.249642)
							(end -0.2794 0.1778)
						)
						(arc
							(start -0.2794 -0.1778)
							(mid -0.249642 -0.249642)
							(end -0.1778 -0.2794)
						)
						(arc
							(start 0.1778 -0.2794)
							(mid 0.249642 -0.249642)
							(end 0.2794 -0.1778)
						)
						(arc
							(start 0.2794 0.1778)
							(mid 0.249642 0.249642)
							(end 0.1778 0.2794)
						)
					)
					(width 0)
					(fill yes)
				)
			)
		)
	)
	(footprint ""
		(layer "B.Cu")
		(at 124.5362 -15.9258 90)
		(property "Reference" "U24"
			(at 0 0 90)
			(layer "B.SilkS")
			(hide yes)
			(effects
				(font
					(size 1.27 1.27)
				)
				(justify mirror)
			)
		)
		(property "Value" "TCA9517DGKR-GP"
			(at 0.1143 -9.1948 90)
			(unlocked yes)
			(layer "B.Fab")
			(hide yes)
			(effects
				(font
					(size 1.016 1.016)
					(thickness 0.1524)
				)
				(justify mirror)
			)
		)
		(property "Device Type" "MSOP8-1H44"
			(at 0.1143 -10.795 90)
			(unlocked yes)
			(layer "B.Fab")
			(hide yes)
			(effects
				(font
					(size 1.016 1.016)
					(thickness 0.1524)
				)
				(justify mirror)
			)
		)
		(duplicate_pad_numbers_are_jumpers no)
		(fp_line
			(start 1.9558 -1.016)
			(end 1.9558 1.016)
			(stroke
				(width 0.1524)
				(type default)
			)
			(layer "B.SilkS")
		)
		(fp_line
			(start -1.0795 -1.016)
			(end 1.9558 -1.016)
			(stroke
				(width 0.1524)
				(type default)
			)
			(layer "B.SilkS")
		)
		(fp_line
			(start 1.9558 -0.5461)
			(end 1.4478 -0.0381)
			(stroke
				(width 0.1524)
				(type default)
			)
			(layer "B.SilkS")
		)
		(fp_line
			(start 1.4478 -0.0381)
			(end 1.9558 0.4699)
			(stroke
				(width 0.1524)
				(type default)
			)
			(layer "B.SilkS")
		)
		(fp_line
			(start 1.9558 1.016)
			(end -1.0795 1.016)
			(stroke
				(width 0.1524)
				(type default)
			)
			(layer "B.SilkS")
		)
		(fp_line
			(start -1.0795 1.016)
			(end -1.0795 -1.016)
			(stroke
				(width 0.1524)
				(type default)
			)
			(layer "B.SilkS")
		)
		(fp_line
			(start 1.778 1.0922)
			(end 1.778 3.048)
			(stroke
				(width 0.508)
				(type default)
			)
			(layer "B.SilkS")
		)
		(fp_poly
			(pts
				(xy 1.1557 -1.016) (xy 1.1557 1.016) (xy -1.1557 1.016) (xy -1.1557 -1.016)
			)
			(stroke
				(width 0)
				(type default)
			)
			(fill yes)
			(layer "B.SilkS")
		)
		(fp_rect
			(start 1.4986 2.4511)
			(end -1.4986 -2.4511)
			(stroke
				(width 0)
				(type default)
			)
			(fill no)
			(layer "B.CrtYd")
		)
		(fp_poly
			(pts
				(xy 2.032 3.302) (xy 2.032 -3.302) (xy -2.032 -3.302) (xy -2.032 -2.1209) (xy -1.4986 -2.1209) (xy -1.4986 -2.4511)
				(xy 1.4986 -2.4511) (xy 1.4986 2.4511) (xy -1.4986 2.4511) (xy -1.4986 -2.1082) (xy -2.032 -2.1082)
				(xy -2.032 3.302)
			)
			(stroke
				(width 0)
				(type default)
			)
			(fill no)
			(layer "B.CrtYd")
		)
		(fp_rect
			(start 2.032 3.302)
			(end -2.032 -3.302)
			(stroke
				(width 0)
				(type default)
			)
			(fill no)
			(layer "B.Fab")
		)
		(pad "1" smd rect
			(at 0.97536 2.05486 270)
			(size 0.3556 1.524)
			(layers "B.Cu" "B.Mask" "B.Paste")
			(net "P3V3_STBY")
		)
		(pad "2" smd rect
			(at 0.32512 2.05486 270)
			(size 0.3556 1.524)
			(layers "B.Cu" "B.Mask" "B.Paste")
			(net "SMCLK_USB_HUB")
		)
		(pad "3" smd rect
			(at -0.32512 2.05486 270)
			(size 0.3556 1.524)
			(layers "B.Cu" "B.Mask" "B.Paste")
			(net "SMDAT_USB_HUB")
		)
		(pad "4" smd rect
			(at -0.97536 2.05486 270)
			(size 0.3556 1.524)
			(layers "B.Cu" "B.Mask" "B.Paste")
			(net "GND")
		)
		(pad "5" smd rect
			(at -0.97536 -2.05486 270)
			(size 0.3556 1.524)
			(layers "B.Cu" "B.Mask" "B.Paste")
			(net "SMB_U_REPEATER_EN")
		)
		(pad "6" smd rect
			(at -0.32512 -2.05486 270)
			(size 0.3556 1.524)
			(layers "B.Cu" "B.Mask" "B.Paste")
			(net "SMDAT_USB_HUB_R")
		)
		(pad "7" smd rect
			(at 0.32512 -2.05486 270)
			(size 0.3556 1.524)
			(layers "B.Cu" "B.Mask" "B.Paste")
			(net "SMCLK_USB_HUB_R")
		)
		(pad "8" smd rect
			(at 0.97536 -2.05486 270)
			(size 0.3556 1.524)
			(layers "B.Cu" "B.Mask" "B.Paste")
			(net "P3V3_USB_HUB")
		)
	)
	(footprint ""
		(layer "B.Cu")
		(at 121.9708 -9.8933 90)
		(property "Reference" "R38"
			(at 0 0 90)
			(layer "B.SilkS")
			(hide yes)
			(effects
				(font
					(size 1.27 1.27)
				)
				(justify mirror)
			)
		)
		(property "Value" "10KR2F-2-GP"
			(at -0.064008 -3.993896 90)
			(unlocked yes)
			(layer "B.Fab")
			(hide yes)
			(effects
				(font
					(size 1.016 1.016)
					(thickness 0.1524)
				)
				(justify mirror)
			)
		)
		(property "Device Type" "R402H16"
			(at -0.064008 -5.517896 90)
			(unlocked yes)
			(layer "B.Fab")
			(hide yes)
			(effects
				(font
					(size 1.016 1.016)
					(thickness 0.1524)
				)
				(justify mirror)
			)
		)
		(duplicate_pad_numbers_are_jumpers no)
		(fp_line
			(start 0.508 -0.9398)
			(end 0.508 0.9398)
			(stroke
				(width 0.1524)
				(type default)
			)
			(layer "B.SilkS")
		)
		(fp_line
			(start -0.508 -0.9398)
			(end 0.508 -0.9398)
			(stroke
				(width 0.1524)
				(type default)
			)
			(layer "B.SilkS")
		)
		(fp_rect
			(start 0.508 0.9398)
			(end -0.508 -0.9398)
			(stroke
				(width 0)
				(type default)
			)
			(fill no)
			(layer "B.CrtYd")
		)
		(fp_rect
			(start 0.508 0.9398)
			(end -0.508 -0.9398)
			(stroke
				(width 0)
				(type default)
			)
			(fill no)
			(layer "B.Fab")
		)
		(pad "1" smd custom
			(at 0 -0.4445 270)
			(size 0.1397 0.1397)
			(layers "B.Cu" "B.Mask" "B.Paste")
			(net "P3V3_STBY")
			(options
				(clearance outline)
				(anchor circle)
			)
			(primitives
				(gr_poly
					(pts
						(arc
							(start -0.1778 0.2794)
							(mid -0.249642 0.249642)
							(end -0.2794 0.1778)
						)
						(arc
							(start -0.2794 -0.1778)
							(mid -0.249642 -0.249642)
							(end -0.1778 -0.2794)
						)
						(arc
							(start 0.1778 -0.2794)
							(mid 0.249642 -0.249642)
							(end 0.2794 -0.1778)
						)
						(arc
							(start 0.2794 0.1778)
							(mid 0.249642 0.249642)
							(end 0.1778 0.2794)
						)
					)
					(width 0)
					(fill yes)
				)
			)
		)
		(pad "2" smd custom
			(at 0 0.4445 270)
			(size 0.1397 0.1397)
			(layers "B.Cu" "B.Mask" "B.Paste")
			(net "SMB_P_HUB_A1")
			(options
				(clearance outline)
				(anchor circle)
			)
			(primitives
				(gr_poly
					(pts
						(arc
							(start -0.1778 0.2794)
							(mid -0.249642 0.249642)
							(end -0.2794 0.1778)
						)
						(arc
							(start -0.2794 -0.1778)
							(mid -0.249642 -0.249642)
							(end -0.1778 -0.2794)
						)
						(arc
							(start 0.1778 -0.2794)
							(mid 0.249642 -0.249642)
							(end 0.2794 -0.1778)
						)
						(arc
							(start 0.2794 0.1778)
							(mid 0.249642 0.249642)
							(end 0.1778 0.2794)
						)
					)
					(width 0)
					(fill yes)
				)
			)
		)
	)
	(footprint ""
		(layer "B.Cu")
		(at 25.3238 -25.6032)
		(property "Reference" "R149"
			(at 0 0 0)
			(layer "B.SilkS")
			(hide yes)
			(effects
				(font
					(size 1.27 1.27)
				)
				(justify mirror)
			)
		)
		(property "Value" "10KR2F-2-GP"
			(at -0.064008 -3.993896 0)
			(unlocked yes)
			(layer "B.Fab")
			(hide yes)
			(effects
				(font
					(size 1.016 1.016)
					(thickness 0.1524)
				)
				(justify mirror)
			)
		)
		(property "Device Type" "R402H16"
			(at -0.064008 -5.517896 0)
			(unlocked yes)
			(layer "B.Fab")
			(hide yes)
			(effects
				(font
					(size 1.016 1.016)
					(thickness 0.1524)
				)
				(justify mirror)
			)
		)
		(duplicate_pad_numbers_are_jumpers no)
		(fp_line
			(start -0.508 -0.9398)
			(end 0.508 -0.9398)
			(stroke
				(width 0.1524)
				(type default)
			)
			(layer "B.SilkS")
		)
		(fp_line
			(start 0.508 -0.9398)
			(end 0.508 0.9398)
			(stroke
				(width 0.1524)
				(type default)
			)
			(layer "B.SilkS")
		)
		(fp_rect
			(start 0.508 0.9398)
			(end -0.508 -0.9398)
			(stroke
				(width 0)
				(type default)
			)
			(fill no)
			(layer "B.CrtYd")
		)
		(fp_rect
			(start 0.508 0.9398)
			(end -0.508 -0.9398)
			(stroke
				(width 0)
				(type default)
			)
			(fill no)
			(layer "B.Fab")
		)
		(pad "1" smd custom
			(at 0 -0.4445 180)
			(size 0.1397 0.1397)
			(layers "B.Cu" "B.Mask" "B.Paste")
			(net "ATX_VMONITOR_A1")
			(options
				(clearance outline)
				(anchor circle)
			)
			(primitives
				(gr_poly
					(pts
						(arc
							(start -0.1778 0.2794)
							(mid -0.249642 0.249642)
							(end -0.2794 0.1778)
						)
						(arc
							(start -0.2794 -0.1778)
							(mid -0.249642 -0.249642)
							(end -0.1778 -0.2794)
						)
						(arc
							(start 0.1778 -0.2794)
							(mid 0.249642 -0.249642)
							(end 0.2794 -0.1778)
						)
						(arc
							(start 0.2794 0.1778)
							(mid 0.249642 0.249642)
							(end 0.1778 0.2794)
						)
					)
					(width 0)
					(fill yes)
				)
			)
		)
		(pad "2" smd custom
			(at 0 0.4445 180)
			(size 0.1397 0.1397)
			(layers "B.Cu" "B.Mask" "B.Paste")
			(net "GND")
			(options
				(clearance outline)
				(anchor circle)
			)
			(primitives
				(gr_poly
					(pts
						(arc
							(start -0.1778 0.2794)
							(mid -0.249642 0.249642)
							(end -0.2794 0.1778)
						)
						(arc
							(start -0.2794 -0.1778)
							(mid -0.249642 -0.249642)
							(end -0.1778 -0.2794)
						)
						(arc
							(start 0.1778 -0.2794)
							(mid 0.249642 -0.249642)
							(end 0.2794 -0.1778)
						)
						(arc
							(start 0.2794 0.1778)
							(mid 0.249642 0.249642)
							(end 0.1778 0.2794)
						)
					)
					(width 0)
					(fill yes)
				)
			)
		)
	)
	(footprint ""
		(layer "B.Cu")
		(at 18.6182 -21.0058 90)
		(property "Reference" "C56"
			(at 0 0 90)
			(layer "B.SilkS")
			(hide yes)
			(effects
				(font
					(size 1.27 1.27)
				)
				(justify mirror)
			)
		)
		(property "Value" "SCD1U25V2KX-2-GP"
			(at -1.1811 -2.7051 90)
			(unlocked yes)
			(layer "B.Fab")
			(hide yes)
			(effects
				(font
					(size 1.016 1.016)
					(thickness 0.1524)
				)
				(justify mirror)
			)
		)
		(property "Device Type" "C402H22"
			(at -1.1811 -4.2291 90)
			(unlocked yes)
			(layer "B.Fab")
			(hide yes)
			(effects
				(font
					(size 1.016 1.016)
					(thickness 0.1524)
				)
				(justify mirror)
			)
		)
		(duplicate_pad_numbers_are_jumpers no)
		(fp_rect
			(start 0.4318 0.9525)
			(end -0.4318 -0.9525)
			(stroke
				(width 0)
				(type default)
			)
			(fill no)
			(layer "B.CrtYd")
		)
		(fp_rect
			(start 0.4318 0.9525)
			(end -0.4318 -0.9525)
			(stroke
				(width 0)
				(type default)
			)
			(fill no)
			(layer "B.Fab")
		)
		(pad "1" smd custom
			(at 0 -0.4445 270)
			(size 0.1524 0.1524)
			(layers "B.Cu" "B.Mask" "B.Paste")
			(net "P12V")
			(options
				(clearance outline)
				(anchor circle)
			)
			(primitives
				(gr_poly
					(pts
						(arc
							(start 0.3048 0.2032)
							(mid 0.275042 0.275042)
							(end 0.2032 0.3048)
						)
						(arc
							(start -0.2032 0.3048)
							(mid -0.275042 0.275042)
							(end -0.3048 0.2032)
						)
						(arc
							(start -0.3048 -0.2032)
							(mid -0.275042 -0.275042)
							(end -0.2032 -0.3048)
						)
						(arc
							(start 0.2032 -0.3048)
							(mid 0.275042 -0.275042)
							(end 0.3048 -0.2032)
						)
					)
					(width 0)
					(fill yes)
				)
			)
		)
		(pad "2" smd custom
			(at 0 0.4445 270)
			(size 0.1524 0.1524)
			(layers "B.Cu" "B.Mask" "B.Paste")
			(net "GND")
			(options
				(clearance outline)
				(anchor circle)
			)
			(primitives
				(gr_poly
					(pts
						(arc
							(start 0.3048 0.2032)
							(mid 0.275042 0.275042)
							(end 0.2032 0.3048)
						)
						(arc
							(start -0.2032 0.3048)
							(mid -0.275042 0.275042)
							(end -0.3048 0.2032)
						)
						(arc
							(start -0.3048 -0.2032)
							(mid -0.275042 -0.275042)
							(end -0.2032 -0.3048)
						)
						(arc
							(start 0.2032 -0.3048)
							(mid 0.275042 -0.275042)
							(end 0.3048 -0.2032)
						)
					)
					(width 0)
					(fill yes)
				)
			)
		)
	)
	(footprint ""
		(layer "B.Cu")
		(at 121.5898 -30.099 90)
		(property "Reference" "CU3"
			(at 0 0 90)
			(layer "B.SilkS")
			(hide yes)
			(effects
				(font
					(size 1.27 1.27)
				)
				(justify mirror)
			)
		)
		(property "Value" "SC1U10V2KX-4-GP"
			(at -1.1811 -2.7051 90)
			(unlocked yes)
			(layer "B.Fab")
			(hide yes)
			(effects
				(font
					(size 1.016 1.016)
					(thickness 0.1524)
				)
				(justify mirror)
			)
		)
		(property "Device Type" "C402H22"
			(at -1.1811 -4.2291 90)
			(unlocked yes)
			(layer "B.Fab")
			(hide yes)
			(effects
				(font
					(size 1.016 1.016)
					(thickness 0.1524)
				)
				(justify mirror)
			)
		)
		(duplicate_pad_numbers_are_jumpers no)
		(fp_rect
			(start 0.4318 0.9525)
			(end -0.4318 -0.9525)
			(stroke
				(width 0)
				(type default)
			)
			(fill no)
			(layer "B.CrtYd")
		)
		(fp_rect
			(start 0.4318 0.9525)
			(end -0.4318 -0.9525)
			(stroke
				(width 0)
				(type default)
			)
			(fill no)
			(layer "B.Fab")
		)
		(pad "1" smd custom
			(at 0 -0.4445 270)
			(size 0.1524 0.1524)
			(layers "B.Cu" "B.Mask" "B.Paste")
			(net "P3V3_USB_HUB")
			(options
				(clearance outline)
				(anchor circle)
			)
			(primitives
				(gr_poly
					(pts
						(arc
							(start 0.3048 0.2032)
							(mid 0.275042 0.275042)
							(end 0.2032 0.3048)
						)
						(arc
							(start -0.2032 0.3048)
							(mid -0.275042 0.275042)
							(end -0.3048 0.2032)
						)
						(arc
							(start -0.3048 -0.2032)
							(mid -0.275042 -0.275042)
							(end -0.2032 -0.3048)
						)
						(arc
							(start 0.2032 -0.3048)
							(mid 0.275042 -0.275042)
							(end 0.3048 -0.2032)
						)
					)
					(width 0)
					(fill yes)
				)
			)
		)
		(pad "2" smd custom
			(at 0 0.4445 270)
			(size 0.1524 0.1524)
			(layers "B.Cu" "B.Mask" "B.Paste")
			(net "GND")
			(options
				(clearance outline)
				(anchor circle)
			)
			(primitives
				(gr_poly
					(pts
						(arc
							(start 0.3048 0.2032)
							(mid 0.275042 0.275042)
							(end 0.2032 0.3048)
						)
						(arc
							(start -0.2032 0.3048)
							(mid -0.275042 0.275042)
							(end -0.3048 0.2032)
						)
						(arc
							(start -0.3048 -0.2032)
							(mid -0.275042 -0.275042)
							(end -0.2032 -0.3048)
						)
						(arc
							(start 0.2032 -0.3048)
							(mid 0.275042 -0.275042)
							(end 0.3048 -0.2032)
						)
					)
					(width 0)
					(fill yes)
				)
			)
		)
	)
	(footprint ""
		(layer "B.Cu")
		(at 18.3896 -5.5626)
		(property "Reference" "PC4"
			(at 0 0 0)
			(layer "B.SilkS")
			(hide yes)
			(effects
				(font
					(size 1.27 1.27)
				)
				(justify mirror)
			)
		)
		(property "Value" "SCD1U50V3KX-GP"
			(at 0 -2.8194 0)
			(unlocked yes)
			(layer "B.Fab")
			(hide yes)
			(effects
				(font
					(size 1.016 1.016)
					(thickness 0.1524)
				)
				(justify mirror)
			)
		)
		(property "Device Type" "C603H36"
			(at 0 -4.3434 0)
			(unlocked yes)
			(layer "B.Fab")
			(hide yes)
			(effects
				(font
					(size 1.016 1.016)
					(thickness 0.1524)
				)
				(justify mirror)
			)
		)
		(duplicate_pad_numbers_are_jumpers no)
		(fp_line
			(start -0.508 0)
			(end 0.508 0)
			(stroke
				(width 0.2032)
				(type default)
			)
			(layer "B.SilkS")
		)
		(fp_rect
			(start 0.5842 1.3335)
			(end -0.5842 -1.3335)
			(stroke
				(width 0)
				(type default)
			)
			(fill no)
			(layer "B.CrtYd")
		)
		(fp_rect
			(start 0.5842 1.3335)
			(end -0.5842 -1.3335)
			(stroke
				(width 0)
				(type default)
			)
			(fill no)
			(layer "B.Fab")
		)
		(pad "1" smd custom
			(at 0 -0.762 180)
			(size 0.2159 0.2159)
			(layers "B.Cu" "B.Mask" "B.Paste")
			(net "P3V3_BST")
			(options
				(clearance outline)
				(anchor circle)
			)
			(primitives
				(gr_poly
					(pts
						(arc
							(start -0.3302 0.4318)
							(mid -0.402042 0.402042)
							(end -0.4318 0.3302)
						)
						(arc
							(start -0.4318 -0.3302)
							(mid -0.402042 -0.402042)
							(end -0.3302 -0.4318)
						)
						(arc
							(start 0.3302 -0.4318)
							(mid 0.402042 -0.402042)
							(end 0.4318 -0.3302)
						)
						(arc
							(start 0.4318 0.3302)
							(mid 0.402042 0.402042)
							(end 0.3302 0.4318)
						)
					)
					(width 0)
					(fill yes)
				)
			)
		)
		(pad "2" smd custom
			(at 0 0.762 180)
			(size 0.2159 0.2159)
			(layers "B.Cu" "B.Mask" "B.Paste")
			(net "P3V3_SW")
			(options
				(clearance outline)
				(anchor circle)
			)
			(primitives
				(gr_poly
					(pts
						(arc
							(start -0.3302 0.4318)
							(mid -0.402042 0.402042)
							(end -0.4318 0.3302)
						)
						(arc
							(start -0.4318 -0.3302)
							(mid -0.402042 -0.402042)
							(end -0.3302 -0.4318)
						)
						(arc
							(start 0.3302 -0.4318)
							(mid 0.402042 -0.402042)
							(end 0.4318 -0.3302)
						)
						(arc
							(start 0.4318 0.3302)
							(mid 0.402042 0.402042)
							(end 0.3302 0.4318)
						)
					)
					(width 0)
					(fill yes)
				)
			)
		)
	)
	(footprint ""
		(layer "B.Cu")
		(at 117.4496 -0.3302)
		(property "Reference" "R7"
			(at 0 0 0)
			(layer "B.SilkS")
			(hide yes)
			(effects
				(font
					(size 1.27 1.27)
				)
				(justify mirror)
			)
		)
		(property "Value" "4K7R2F-GP"
			(at -0.064008 -3.993896 0)
			(unlocked yes)
			(layer "B.Fab")
			(hide yes)
			(effects
				(font
					(size 1.016 1.016)
					(thickness 0.1524)
				)
				(justify mirror)
			)
		)
		(property "Device Type" "R402H16"
			(at -0.064008 -5.517896 0)
			(unlocked yes)
			(layer "B.Fab")
			(hide yes)
			(effects
				(font
					(size 1.016 1.016)
					(thickness 0.1524)
				)
				(justify mirror)
			)
		)
		(duplicate_pad_numbers_are_jumpers no)
		(fp_line
			(start -0.508 -0.9398)
			(end 0.508 -0.9398)
			(stroke
				(width 0.1524)
				(type default)
			)
			(layer "B.SilkS")
		)
		(fp_line
			(start 0.508 -0.9398)
			(end 0.508 0.9398)
			(stroke
				(width 0.1524)
				(type default)
			)
			(layer "B.SilkS")
		)
		(fp_rect
			(start 0.508 0.9398)
			(end -0.508 -0.9398)
			(stroke
				(width 0)
				(type default)
			)
			(fill no)
			(layer "B.CrtYd")
		)
		(fp_rect
			(start 0.508 0.9398)
			(end -0.508 -0.9398)
			(stroke
				(width 0)
				(type default)
			)
			(fill no)
			(layer "B.Fab")
		)
		(pad "1" smd custom
			(at 0 -0.4445 180)
			(size 0.1397 0.1397)
			(layers "B.Cu" "B.Mask" "B.Paste")
			(net "P3V3_STBY")
			(options
				(clearance outline)
				(anchor circle)
			)
			(primitives
				(gr_poly
					(pts
						(arc
							(start -0.1778 0.2794)
							(mid -0.249642 0.249642)
							(end -0.2794 0.1778)
						)
						(arc
							(start -0.2794 -0.1778)
							(mid -0.249642 -0.249642)
							(end -0.1778 -0.2794)
						)
						(arc
							(start 0.1778 -0.2794)
							(mid 0.249642 -0.249642)
							(end 0.2794 -0.1778)
						)
						(arc
							(start 0.2794 0.1778)
							(mid 0.249642 0.249642)
							(end 0.1778 0.2794)
						)
					)
					(width 0)
					(fill yes)
				)
			)
		)
		(pad "2" smd custom
			(at 0 0.4445 180)
			(size 0.1397 0.1397)
			(layers "B.Cu" "B.Mask" "B.Paste")
			(net "SMDAT_BMC_DEVICE")
			(options
				(clearance outline)
				(anchor circle)
			)
			(primitives
				(gr_poly
					(pts
						(arc
							(start -0.1778 0.2794)
							(mid -0.249642 0.249642)
							(end -0.2794 0.1778)
						)
						(arc
							(start -0.2794 -0.1778)
							(mid -0.249642 -0.249642)
							(end -0.1778 -0.2794)
						)
						(arc
							(start 0.1778 -0.2794)
							(mid 0.249642 -0.249642)
							(end 0.2794 -0.1778)
						)
						(arc
							(start 0.2794 0.1778)
							(mid 0.249642 0.249642)
							(end 0.1778 0.2794)
						)
					)
					(width 0)
					(fill yes)
				)
			)
		)
	)
	(footprint ""
		(layer "B.Cu")
		(at 122.9614 -25.0825)
		(property "Reference" "TP86"
			(at 0 0 0)
			(layer "B.SilkS")
			(hide yes)
			(effects
				(font
					(size 1.27 1.27)
				)
				(justify mirror)
			)
		)
		(property "Value" "TPAD24"
			(at 0 -1.6129 0)
			(unlocked yes)
			(layer "B.Fab")
			(hide yes)
			(effects
				(font
					(size 1.016 1.016)
					(thickness 0.1524)
				)
				(justify mirror)
			)
		)
		(property "Device Type" "TPAD24"
			(at 0 -3.1369 0)
			(unlocked yes)
			(layer "B.Fab")
			(hide yes)
			(effects
				(font
					(size 1.016 1.016)
					(thickness 0.1524)
				)
				(justify mirror)
			)
		)
		(duplicate_pad_numbers_are_jumpers no)
		(fp_poly
			(pts
				(arc
					(start 0.3048 0)
					(mid -0.3048 0)
					(end 0.3048 0)
				)
			)
			(stroke
				(width 0)
				(type default)
			)
			(fill no)
			(layer "B.CrtYd")
		)
		(fp_poly
			(pts
				(arc
					(start 0.6096 0)
					(mid -0.6096 0)
					(end 0.6096 0)
				)
			)
			(stroke
				(width 0)
				(type default)
			)
			(fill no)
			(layer "B.Fab")
		)
		(pad "1" smd circle
			(at 0 0 180)
			(size 0.6096 0.6096)
			(layers "B.Cu" "B.Mask" "B.Paste")
			(net "TP_USB_OCS_N4")
		)
	)
	(footprint ""
		(layer "B.Cu")
		(at 24.6253 -19.7993 90)
		(property "Reference" "R104"
			(at 0 0 90)
			(layer "B.SilkS")
			(hide yes)
			(effects
				(font
					(size 1.27 1.27)
				)
				(justify mirror)
			)
		)
		(property "Value" "0R2F-1-GP"
			(at -0.064008 -3.993896 90)
			(unlocked yes)
			(layer "B.Fab")
			(hide yes)
			(effects
				(font
					(size 1.016 1.016)
					(thickness 0.1524)
				)
				(justify mirror)
			)
		)
		(property "Device Type" "R402H16"
			(at -0.064008 -5.517896 90)
			(unlocked yes)
			(layer "B.Fab")
			(hide yes)
			(effects
				(font
					(size 1.016 1.016)
					(thickness 0.1524)
				)
				(justify mirror)
			)
		)
		(duplicate_pad_numbers_are_jumpers no)
		(fp_line
			(start 0.508 -0.9398)
			(end 0.508 0.9398)
			(stroke
				(width 0.1524)
				(type default)
			)
			(layer "B.SilkS")
		)
		(fp_line
			(start -0.508 -0.9398)
			(end 0.508 -0.9398)
			(stroke
				(width 0.1524)
				(type default)
			)
			(layer "B.SilkS")
		)
		(fp_rect
			(start 0.508 0.9398)
			(end -0.508 -0.9398)
			(stroke
				(width 0)
				(type default)
			)
			(fill no)
			(layer "B.CrtYd")
		)
		(fp_rect
			(start 0.508 0.9398)
			(end -0.508 -0.9398)
			(stroke
				(width 0)
				(type default)
			)
			(fill no)
			(layer "B.Fab")
		)
		(pad "1" smd custom
			(at 0 -0.4445 270)
			(size 0.1397 0.1397)
			(layers "B.Cu" "B.Mask" "B.Paste")
			(net "SMB_VMONITOR_ATX_MUX_SDA")
			(options
				(clearance outline)
				(anchor circle)
			)
			(primitives
				(gr_poly
					(pts
						(arc
							(start -0.1778 0.2794)
							(mid -0.249642 0.249642)
							(end -0.2794 0.1778)
						)
						(arc
							(start -0.2794 -0.1778)
							(mid -0.249642 -0.249642)
							(end -0.1778 -0.2794)
						)
						(arc
							(start 0.1778 -0.2794)
							(mid 0.249642 -0.249642)
							(end 0.2794 -0.1778)
						)
						(arc
							(start 0.2794 0.1778)
							(mid 0.249642 0.249642)
							(end 0.1778 0.2794)
						)
					)
					(width 0)
					(fill yes)
				)
			)
		)
		(pad "2" smd custom
			(at 0 0.4445 270)
			(size 0.1397 0.1397)
			(layers "B.Cu" "B.Mask" "B.Paste")
			(net "SMDAT_BMC_DEVICE")
			(options
				(clearance outline)
				(anchor circle)
			)
			(primitives
				(gr_poly
					(pts
						(arc
							(start -0.1778 0.2794)
							(mid -0.249642 0.249642)
							(end -0.2794 0.1778)
						)
						(arc
							(start -0.2794 -0.1778)
							(mid -0.249642 -0.249642)
							(end -0.1778 -0.2794)
						)
						(arc
							(start 0.1778 -0.2794)
							(mid 0.249642 -0.249642)
							(end 0.2794 -0.1778)
						)
						(arc
							(start 0.2794 0.1778)
							(mid 0.249642 0.249642)
							(end 0.1778 0.2794)
						)
					)
					(width 0)
					(fill yes)
				)
			)
		)
	)
	(footprint ""
		(layer "B.Cu")
		(at 18.3261 -11.0236)
		(property "Reference" "PR5"
			(at 0 0 0)
			(layer "B.SilkS")
			(hide yes)
			(effects
				(font
					(size 1.27 1.27)
				)
				(justify mirror)
			)
		)
		(property "Value" "2K2R2F-GP"
			(at -0.064008 -3.993896 0)
			(unlocked yes)
			(layer "B.Fab")
			(hide yes)
			(effects
				(font
					(size 1.016 1.016)
					(thickness 0.1524)
				)
				(justify mirror)
			)
		)
		(property "Device Type" "R402H16"
			(at -0.064008 -5.517896 0)
			(unlocked yes)
			(layer "B.Fab")
			(hide yes)
			(effects
				(font
					(size 1.016 1.016)
					(thickness 0.1524)
				)
				(justify mirror)
			)
		)
		(duplicate_pad_numbers_are_jumpers no)
		(fp_line
			(start -0.508 -0.9398)
			(end 0.508 -0.9398)
			(stroke
				(width 0.1524)
				(type default)
			)
			(layer "B.SilkS")
		)
		(fp_line
			(start 0.508 -0.9398)
			(end 0.508 0.9398)
			(stroke
				(width 0.1524)
				(type default)
			)
			(layer "B.SilkS")
		)
		(fp_rect
			(start 0.508 0.9398)
			(end -0.508 -0.9398)
			(stroke
				(width 0)
				(type default)
			)
			(fill no)
			(layer "B.CrtYd")
		)
		(fp_rect
			(start 0.508 0.9398)
			(end -0.508 -0.9398)
			(stroke
				(width 0)
				(type default)
			)
			(fill no)
			(layer "B.Fab")
		)
		(pad "1" smd custom
			(at 0 -0.4445 180)
			(size 0.1397 0.1397)
			(layers "B.Cu" "B.Mask" "B.Paste")
			(net "P3V3_FB")
			(options
				(clearance outline)
				(anchor circle)
			)
			(primitives
				(gr_poly
					(pts
						(arc
							(start -0.1778 0.2794)
							(mid -0.249642 0.249642)
							(end -0.2794 0.1778)
						)
						(arc
							(start -0.2794 -0.1778)
							(mid -0.249642 -0.249642)
							(end -0.1778 -0.2794)
						)
						(arc
							(start 0.1778 -0.2794)
							(mid 0.249642 -0.249642)
							(end 0.2794 -0.1778)
						)
						(arc
							(start 0.2794 0.1778)
							(mid 0.249642 0.249642)
							(end 0.1778 0.2794)
						)
					)
					(width 0)
					(fill yes)
				)
			)
		)
		(pad "2" smd custom
			(at 0 0.4445 180)
			(size 0.1397 0.1397)
			(layers "B.Cu" "B.Mask" "B.Paste")
			(net "GND")
			(options
				(clearance outline)
				(anchor circle)
			)
			(primitives
				(gr_poly
					(pts
						(arc
							(start -0.1778 0.2794)
							(mid -0.249642 0.249642)
							(end -0.2794 0.1778)
						)
						(arc
							(start -0.2794 -0.1778)
							(mid -0.249642 -0.249642)
							(end -0.1778 -0.2794)
						)
						(arc
							(start 0.1778 -0.2794)
							(mid 0.249642 -0.249642)
							(end 0.2794 -0.1778)
						)
						(arc
							(start 0.2794 0.1778)
							(mid 0.249642 0.249642)
							(end 0.1778 0.2794)
						)
					)
					(width 0)
					(fill yes)
				)
			)
		)
	)
	(footprint ""
		(layer "B.Cu")
		(at 124.3838 -0.1016)
		(property "Reference" "R18"
			(at 0 0 0)
			(layer "B.SilkS")
			(hide yes)
			(effects
				(font
					(size 1.27 1.27)
				)
				(justify mirror)
			)
		)
		(property "Value" "10KR2F-2-GP"
			(at -0.064008 -3.993896 0)
			(unlocked yes)
			(layer "B.Fab")
			(hide yes)
			(effects
				(font
					(size 1.016 1.016)
					(thickness 0.1524)
				)
				(justify mirror)
			)
		)
		(property "Device Type" "R402H16"
			(at -0.064008 -5.517896 0)
			(unlocked yes)
			(layer "B.Fab")
			(hide yes)
			(effects
				(font
					(size 1.016 1.016)
					(thickness 0.1524)
				)
				(justify mirror)
			)
		)
		(duplicate_pad_numbers_are_jumpers no)
		(fp_line
			(start -0.508 -0.9398)
			(end 0.508 -0.9398)
			(stroke
				(width 0.1524)
				(type default)
			)
			(layer "B.SilkS")
		)
		(fp_line
			(start 0.508 -0.9398)
			(end 0.508 0.9398)
			(stroke
				(width 0.1524)
				(type default)
			)
			(layer "B.SilkS")
		)
		(fp_rect
			(start 0.508 0.9398)
			(end -0.508 -0.9398)
			(stroke
				(width 0)
				(type default)
			)
			(fill no)
			(layer "B.CrtYd")
		)
		(fp_rect
			(start 0.508 0.9398)
			(end -0.508 -0.9398)
			(stroke
				(width 0)
				(type default)
			)
			(fill no)
			(layer "B.Fab")
		)
		(pad "1" smd custom
			(at 0 -0.4445 180)
			(size 0.1397 0.1397)
			(layers "B.Cu" "B.Mask" "B.Paste")
			(net "SMB_PCH_ALERT_N")
			(options
				(clearance outline)
				(anchor circle)
			)
			(primitives
				(gr_poly
					(pts
						(arc
							(start -0.1778 0.2794)
							(mid -0.249642 0.249642)
							(end -0.2794 0.1778)
						)
						(arc
							(start -0.2794 -0.1778)
							(mid -0.249642 -0.249642)
							(end -0.1778 -0.2794)
						)
						(arc
							(start 0.1778 -0.2794)
							(mid 0.249642 -0.249642)
							(end 0.2794 -0.1778)
						)
						(arc
							(start 0.2794 0.1778)
							(mid 0.249642 0.249642)
							(end 0.1778 0.2794)
						)
					)
					(width 0)
					(fill yes)
				)
			)
		)
		(pad "2" smd custom
			(at 0 0.4445 180)
			(size 0.1397 0.1397)
			(layers "B.Cu" "B.Mask" "B.Paste")
			(net "P3V3_STBY")
			(options
				(clearance outline)
				(anchor circle)
			)
			(primitives
				(gr_poly
					(pts
						(arc
							(start -0.1778 0.2794)
							(mid -0.249642 0.249642)
							(end -0.2794 0.1778)
						)
						(arc
							(start -0.2794 -0.1778)
							(mid -0.249642 -0.249642)
							(end -0.1778 -0.2794)
						)
						(arc
							(start 0.1778 -0.2794)
							(mid 0.249642 -0.249642)
							(end 0.2794 -0.1778)
						)
						(arc
							(start 0.2794 0.1778)
							(mid 0.249642 0.249642)
							(end 0.1778 0.2794)
						)
					)
					(width 0)
					(fill yes)
				)
			)
		)
	)
	(footprint ""
		(layer "B.Cu")
		(at 16.2306 -8.5217 -90)
		(property "Reference" "PR6"
			(at 0 0 90)
			(layer "B.SilkS")
			(hide yes)
			(effects
				(font
					(size 1.27 1.27)
				)
				(justify mirror)
			)
		)
		(property "Value" "30K1R2F-L-GP"
			(at -0.064008 -3.993896 270)
			(unlocked yes)
			(layer "B.Fab")
			(hide yes)
			(effects
				(font
					(size 1.016 1.016)
					(thickness 0.1524)
				)
				(justify mirror)
			)
		)
		(property "Device Type" "R402H16"
			(at -0.064008 -5.517896 270)
			(unlocked yes)
			(layer "B.Fab")
			(hide yes)
			(effects
				(font
					(size 1.016 1.016)
					(thickness 0.1524)
				)
				(justify mirror)
			)
		)
		(duplicate_pad_numbers_are_jumpers no)
		(fp_line
			(start -0.508 -0.9398)
			(end 0.508 -0.9398)
			(stroke
				(width 0.1524)
				(type default)
			)
			(layer "B.SilkS")
		)
		(fp_line
			(start 0.508 -0.9398)
			(end 0.508 0.9398)
			(stroke
				(width 0.1524)
				(type default)
			)
			(layer "B.SilkS")
		)
		(fp_rect
			(start 0.508 0.9398)
			(end -0.508 -0.9398)
			(stroke
				(width 0)
				(type default)
			)
			(fill no)
			(layer "B.CrtYd")
		)
		(fp_rect
			(start 0.508 0.9398)
			(end -0.508 -0.9398)
			(stroke
				(width 0)
				(type default)
			)
			(fill no)
			(layer "B.Fab")
		)
		(pad "1" smd custom
			(at 0 -0.4445 90)
			(size 0.1397 0.1397)
			(layers "B.Cu" "B.Mask" "B.Paste")
			(net "P3V3_MODE")
			(options
				(clearance outline)
				(anchor circle)
			)
			(primitives
				(gr_poly
					(pts
						(arc
							(start -0.1778 0.2794)
							(mid -0.249642 0.249642)
							(end -0.2794 0.1778)
						)
						(arc
							(start -0.2794 -0.1778)
							(mid -0.249642 -0.249642)
							(end -0.1778 -0.2794)
						)
						(arc
							(start 0.1778 -0.2794)
							(mid 0.249642 -0.249642)
							(end 0.2794 -0.1778)
						)
						(arc
							(start 0.2794 0.1778)
							(mid 0.249642 0.249642)
							(end 0.1778 0.2794)
						)
					)
					(width 0)
					(fill yes)
				)
			)
		)
		(pad "2" smd custom
			(at 0 0.4445 90)
			(size 0.1397 0.1397)
			(layers "B.Cu" "B.Mask" "B.Paste")
			(net "AGND_P3V3")
			(options
				(clearance outline)
				(anchor circle)
			)
			(primitives
				(gr_poly
					(pts
						(arc
							(start -0.1778 0.2794)
							(mid -0.249642 0.249642)
							(end -0.2794 0.1778)
						)
						(arc
							(start -0.2794 -0.1778)
							(mid -0.249642 -0.249642)
							(end -0.1778 -0.2794)
						)
						(arc
							(start 0.1778 -0.2794)
							(mid 0.249642 -0.249642)
							(end 0.2794 -0.1778)
						)
						(arc
							(start 0.2794 0.1778)
							(mid 0.249642 0.249642)
							(end 0.1778 0.2794)
						)
					)
					(width 0)
					(fill yes)
				)
			)
		)
	)
	(footprint ""
		(layer "B.Cu")
		(at 129.7686 -29.464 90)
		(property "Reference" "C61"
			(at 0 0 90)
			(layer "B.SilkS")
			(hide yes)
			(effects
				(font
					(size 1.27 1.27)
				)
				(justify mirror)
			)
		)
		(property "Value" "SC2D2U10V3KX-2GP-U1"
			(at 0 -2.8194 90)
			(unlocked yes)
			(layer "B.Fab")
			(hide yes)
			(effects
				(font
					(size 1.016 1.016)
					(thickness 0.1524)
				)
				(justify mirror)
			)
		)
		(property "Device Type" "C603H40"
			(at 0 -4.3434 90)
			(unlocked yes)
			(layer "B.Fab")
			(hide yes)
			(effects
				(font
					(size 1.016 1.016)
					(thickness 0.1524)
				)
				(justify mirror)
			)
		)
		(duplicate_pad_numbers_are_jumpers no)
		(fp_line
			(start -0.508 0)
			(end 0.508 0)
			(stroke
				(width 0.2032)
				(type default)
			)
			(layer "B.SilkS")
		)
		(fp_rect
			(start 0.5842 1.3335)
			(end -0.5842 -1.3335)
			(stroke
				(width 0)
				(type default)
			)
			(fill no)
			(layer "B.CrtYd")
		)
		(fp_rect
			(start 0.5842 1.3335)
			(end -0.5842 -1.3335)
			(stroke
				(width 0)
				(type default)
			)
			(fill no)
			(layer "B.Fab")
		)
		(pad "1" smd custom
			(at 0 -0.762 270)
			(size 0.2159 0.2159)
			(layers "B.Cu" "B.Mask" "B.Paste")
			(net "P3V3_USB_HUB")
			(options
				(clearance outline)
				(anchor circle)
			)
			(primitives
				(gr_poly
					(pts
						(arc
							(start -0.3302 0.4318)
							(mid -0.402042 0.402042)
							(end -0.4318 0.3302)
						)
						(arc
							(start -0.4318 -0.3302)
							(mid -0.402042 -0.402042)
							(end -0.3302 -0.4318)
						)
						(arc
							(start 0.3302 -0.4318)
							(mid 0.402042 -0.402042)
							(end 0.4318 -0.3302)
						)
						(arc
							(start 0.4318 0.3302)
							(mid 0.402042 0.402042)
							(end 0.3302 0.4318)
						)
					)
					(width 0)
					(fill yes)
				)
			)
		)
		(pad "2" smd custom
			(at 0 0.762 270)
			(size 0.2159 0.2159)
			(layers "B.Cu" "B.Mask" "B.Paste")
			(net "GND")
			(options
				(clearance outline)
				(anchor circle)
			)
			(primitives
				(gr_poly
					(pts
						(arc
							(start -0.3302 0.4318)
							(mid -0.402042 0.402042)
							(end -0.4318 0.3302)
						)
						(arc
							(start -0.4318 -0.3302)
							(mid -0.402042 -0.402042)
							(end -0.3302 -0.4318)
						)
						(arc
							(start 0.3302 -0.4318)
							(mid 0.402042 -0.402042)
							(end 0.4318 -0.3302)
						)
						(arc
							(start 0.4318 0.3302)
							(mid 0.402042 0.402042)
							(end 0.3302 0.4318)
						)
					)
					(width 0)
					(fill yes)
				)
			)
		)
	)
	(footprint ""
		(layer "B.Cu")
		(at 120.0912 -18.796 90)
		(property "Reference" "RU152"
			(at 0 0 90)
			(layer "B.SilkS")
			(hide yes)
			(effects
				(font
					(size 1.27 1.27)
				)
				(justify mirror)
			)
		)
		(property "Value" "4K7R2F-GP"
			(at -0.064008 -3.993896 90)
			(unlocked yes)
			(layer "B.Fab")
			(hide yes)
			(effects
				(font
					(size 1.016 1.016)
					(thickness 0.1524)
				)
				(justify mirror)
			)
		)
		(property "Device Type" "R402H16"
			(at -0.064008 -5.517896 90)
			(unlocked yes)
			(layer "B.Fab")
			(hide yes)
			(effects
				(font
					(size 1.016 1.016)
					(thickness 0.1524)
				)
				(justify mirror)
			)
		)
		(duplicate_pad_numbers_are_jumpers no)
		(fp_line
			(start 0.508 -0.9398)
			(end 0.508 0.9398)
			(stroke
				(width 0.1524)
				(type default)
			)
			(layer "B.SilkS")
		)
		(fp_line
			(start -0.508 -0.9398)
			(end 0.508 -0.9398)
			(stroke
				(width 0.1524)
				(type default)
			)
			(layer "B.SilkS")
		)
		(fp_rect
			(start 0.508 0.9398)
			(end -0.508 -0.9398)
			(stroke
				(width 0)
				(type default)
			)
			(fill no)
			(layer "B.CrtYd")
		)
		(fp_rect
			(start 0.508 0.9398)
			(end -0.508 -0.9398)
			(stroke
				(width 0)
				(type default)
			)
			(fill no)
			(layer "B.Fab")
		)
		(pad "1" smd custom
			(at 0 -0.4445 270)
			(size 0.1397 0.1397)
			(layers "B.Cu" "B.Mask" "B.Paste")
			(net "SMCLK_USB_HUB_R")
			(options
				(clearance outline)
				(anchor circle)
			)
			(primitives
				(gr_poly
					(pts
						(arc
							(start -0.1778 0.2794)
							(mid -0.249642 0.249642)
							(end -0.2794 0.1778)
						)
						(arc
							(start -0.2794 -0.1778)
							(mid -0.249642 -0.249642)
							(end -0.1778 -0.2794)
						)
						(arc
							(start 0.1778 -0.2794)
							(mid 0.249642 -0.249642)
							(end 0.2794 -0.1778)
						)
						(arc
							(start 0.2794 0.1778)
							(mid 0.249642 0.249642)
							(end 0.1778 0.2794)
						)
					)
					(width 0)
					(fill yes)
				)
			)
		)
		(pad "2" smd custom
			(at 0 0.4445 270)
			(size 0.1397 0.1397)
			(layers "B.Cu" "B.Mask" "B.Paste")
			(net "P3V3_USB_HUB")
			(options
				(clearance outline)
				(anchor circle)
			)
			(primitives
				(gr_poly
					(pts
						(arc
							(start -0.1778 0.2794)
							(mid -0.249642 0.249642)
							(end -0.2794 0.1778)
						)
						(arc
							(start -0.2794 -0.1778)
							(mid -0.249642 -0.249642)
							(end -0.1778 -0.2794)
						)
						(arc
							(start 0.1778 -0.2794)
							(mid 0.249642 -0.249642)
							(end 0.2794 -0.1778)
						)
						(arc
							(start 0.2794 0.1778)
							(mid 0.249642 0.249642)
							(end 0.1778 0.2794)
						)
					)
					(width 0)
					(fill yes)
				)
			)
		)
	)
	(footprint ""
		(layer "B.Cu")
		(at 21.1836 -31.9532 180)
		(property "Reference" "C54"
			(at 0 0 0)
			(layer "B.SilkS")
			(hide yes)
			(effects
				(font
					(size 1.27 1.27)
				)
				(justify mirror)
			)
		)
		(property "Value" "SC22U16V5MX-4-GP"
			(at 0.0762 -6.1214 180)
			(unlocked yes)
			(layer "B.Fab")
			(hide yes)
			(effects
				(font
					(size 1.016 1.016)
					(thickness 0.1524)
				)
				(justify mirror)
			)
		)
		(property "Device Type" "C805H58"
			(at 0.0762 -8.1534 180)
			(unlocked yes)
			(layer "B.Fab")
			(hide yes)
			(effects
				(font
					(size 1.016 1.016)
					(thickness 0.1524)
				)
				(justify mirror)
			)
		)
		(duplicate_pad_numbers_are_jumpers no)
		(fp_line
			(start -0.635 0)
			(end 0.635 0)
			(stroke
				(width 0.508)
				(type default)
			)
			(layer "B.SilkS")
		)
		(fp_rect
			(start 0.9652 1.778)
			(end -0.9652 -1.778)
			(stroke
				(width 0)
				(type default)
			)
			(fill no)
			(layer "B.CrtYd")
		)
		(fp_poly
			(pts
				(xy 0.9652 -1.778) (xy -0.9652 -1.778) (xy -0.9652 1.778) (xy 0.9652 1.778)
			)
			(stroke
				(width 0)
				(type default)
			)
			(fill no)
			(layer "B.Fab")
		)
		(pad "1" smd rect
			(at 0 -0.9652)
			(size 1.397 1.143)
			(layers "B.Cu" "B.Mask" "B.Paste")
			(net "P12V_ATX")
		)
		(pad "2" smd rect
			(at 0 0.9652)
			(size 1.397 1.143)
			(layers "B.Cu" "B.Mask" "B.Paste")
			(net "GND")
		)
	)
	(footprint ""
		(layer "B.Cu")
		(at 116.60124 -3.50774)
		(property "Reference" "R54"
			(at 0 0 0)
			(layer "B.SilkS")
			(hide yes)
			(effects
				(font
					(size 1.27 1.27)
				)
				(justify mirror)
			)
		)
		(property "Value" "10KR2F-2-GP"
			(at -0.064008 -3.993896 0)
			(unlocked yes)
			(layer "B.Fab")
			(hide yes)
			(effects
				(font
					(size 1.016 1.016)
					(thickness 0.1524)
				)
				(justify mirror)
			)
		)
		(property "Device Type" "R402H16"
			(at -0.064008 -5.517896 0)
			(unlocked yes)
			(layer "B.Fab")
			(hide yes)
			(effects
				(font
					(size 1.016 1.016)
					(thickness 0.1524)
				)
				(justify mirror)
			)
		)
		(duplicate_pad_numbers_are_jumpers no)
		(fp_line
			(start -0.508 -0.9398)
			(end 0.508 -0.9398)
			(stroke
				(width 0.1524)
				(type default)
			)
			(layer "B.SilkS")
		)
		(fp_line
			(start 0.508 -0.9398)
			(end 0.508 0.9398)
			(stroke
				(width 0.1524)
				(type default)
			)
			(layer "B.SilkS")
		)
		(fp_rect
			(start 0.508 0.9398)
			(end -0.508 -0.9398)
			(stroke
				(width 0)
				(type default)
			)
			(fill no)
			(layer "B.CrtYd")
		)
		(fp_rect
			(start 0.508 0.9398)
			(end -0.508 -0.9398)
			(stroke
				(width 0)
				(type default)
			)
			(fill no)
			(layer "B.Fab")
		)
		(pad "1" smd custom
			(at 0 -0.4445 180)
			(size 0.1397 0.1397)
			(layers "B.Cu" "B.Mask" "B.Paste")
			(net "SMB_PCIE_SLOT2_ALERT_N")
			(options
				(clearance outline)
				(anchor circle)
			)
			(primitives
				(gr_poly
					(pts
						(arc
							(start -0.1778 0.2794)
							(mid -0.249642 0.249642)
							(end -0.2794 0.1778)
						)
						(arc
							(start -0.2794 -0.1778)
							(mid -0.249642 -0.249642)
							(end -0.1778 -0.2794)
						)
						(arc
							(start 0.1778 -0.2794)
							(mid 0.249642 -0.249642)
							(end 0.2794 -0.1778)
						)
						(arc
							(start 0.2794 0.1778)
							(mid 0.249642 0.249642)
							(end 0.1778 0.2794)
						)
					)
					(width 0)
					(fill yes)
				)
			)
		)
		(pad "2" smd custom
			(at 0 0.4445 180)
			(size 0.1397 0.1397)
			(layers "B.Cu" "B.Mask" "B.Paste")
			(net "P3V3_STBY")
			(options
				(clearance outline)
				(anchor circle)
			)
			(primitives
				(gr_poly
					(pts
						(arc
							(start -0.1778 0.2794)
							(mid -0.249642 0.249642)
							(end -0.2794 0.1778)
						)
						(arc
							(start -0.2794 -0.1778)
							(mid -0.249642 -0.249642)
							(end -0.1778 -0.2794)
						)
						(arc
							(start 0.1778 -0.2794)
							(mid 0.249642 -0.249642)
							(end 0.2794 -0.1778)
						)
						(arc
							(start 0.2794 0.1778)
							(mid 0.249642 0.249642)
							(end 0.1778 0.2794)
						)
					)
					(width 0)
					(fill yes)
				)
			)
		)
	)
	(footprint ""
		(layer "B.Cu")
		(at 37.1475 2.8956 90)
		(property "Reference" "U23"
			(at 0 0 90)
			(layer "B.SilkS")
			(hide yes)
			(effects
				(font
					(size 1.27 1.27)
				)
				(justify mirror)
			)
		)
		(property "Value" "TCA9517DGKR-GP"
			(at 0.1143 -9.1948 90)
			(unlocked yes)
			(layer "B.Fab")
			(hide yes)
			(effects
				(font
					(size 1.016 1.016)
					(thickness 0.1524)
				)
				(justify mirror)
			)
		)
		(property "Device Type" "MSOP8-1H44"
			(at 0.1143 -10.795 90)
			(unlocked yes)
			(layer "B.Fab")
			(hide yes)
			(effects
				(font
					(size 1.016 1.016)
					(thickness 0.1524)
				)
				(justify mirror)
			)
		)
		(duplicate_pad_numbers_are_jumpers no)
		(fp_line
			(start 1.9558 -1.016)
			(end 1.9558 1.016)
			(stroke
				(width 0.1524)
				(type default)
			)
			(layer "B.SilkS")
		)
		(fp_line
			(start -1.0795 -1.016)
			(end 1.9558 -1.016)
			(stroke
				(width 0.1524)
				(type default)
			)
			(layer "B.SilkS")
		)
		(fp_line
			(start 1.9558 -0.5461)
			(end 1.4478 -0.0381)
			(stroke
				(width 0.1524)
				(type default)
			)
			(layer "B.SilkS")
		)
		(fp_line
			(start 1.4478 -0.0381)
			(end 1.9558 0.4699)
			(stroke
				(width 0.1524)
				(type default)
			)
			(layer "B.SilkS")
		)
		(fp_line
			(start 1.9558 1.016)
			(end -1.0795 1.016)
			(stroke
				(width 0.1524)
				(type default)
			)
			(layer "B.SilkS")
		)
		(fp_line
			(start -1.0795 1.016)
			(end -1.0795 -1.016)
			(stroke
				(width 0.1524)
				(type default)
			)
			(layer "B.SilkS")
		)
		(fp_line
			(start 1.778 1.0922)
			(end 1.778 3.048)
			(stroke
				(width 0.508)
				(type default)
			)
			(layer "B.SilkS")
		)
		(fp_poly
			(pts
				(xy 1.1557 -1.016) (xy 1.1557 1.016) (xy -1.1557 1.016) (xy -1.1557 -1.016)
			)
			(stroke
				(width 0)
				(type default)
			)
			(fill yes)
			(layer "B.SilkS")
		)
		(fp_rect
			(start 1.4986 2.4511)
			(end -1.4986 -2.4511)
			(stroke
				(width 0)
				(type default)
			)
			(fill no)
			(layer "B.CrtYd")
		)
		(fp_poly
			(pts
				(xy 2.032 3.302) (xy 2.032 -3.302) (xy -2.032 -3.302) (xy -2.032 -2.1209) (xy -1.4986 -2.1209) (xy -1.4986 -2.4511)
				(xy 1.4986 -2.4511) (xy 1.4986 2.4511) (xy -1.4986 2.4511) (xy -1.4986 -2.1082) (xy -2.032 -2.1082)
				(xy -2.032 3.302)
			)
			(stroke
				(width 0)
				(type default)
			)
			(fill no)
			(layer "B.CrtYd")
		)
		(fp_rect
			(start 2.032 3.302)
			(end -2.032 -3.302)
			(stroke
				(width 0)
				(type default)
			)
			(fill no)
			(layer "B.Fab")
		)
		(pad "1" smd rect
			(at 0.97536 2.05486 270)
			(size 0.3556 1.524)
			(layers "B.Cu" "B.Mask" "B.Paste")
			(net "P3V3_STBY")
		)
		(pad "2" smd rect
			(at 0.32512 2.05486 270)
			(size 0.3556 1.524)
			(layers "B.Cu" "B.Mask" "B.Paste")
			(net "SMB_HOST_STBY_LVC3_SCL_R5")
		)
		(pad "3" smd rect
			(at -0.32512 2.05486 270)
			(size 0.3556 1.524)
			(layers "B.Cu" "B.Mask" "B.Paste")
			(net "SMB_HOST_STBY_LVC3_SDA_R5")
		)
		(pad "4" smd rect
			(at -0.97536 2.05486 270)
			(size 0.3556 1.524)
			(layers "B.Cu" "B.Mask" "B.Paste")
			(net "GND")
		)
		(pad "5" smd rect
			(at -0.97536 -2.05486 270)
			(size 0.3556 1.524)
			(layers "B.Cu" "B.Mask" "B.Paste")
			(net "SMB_P_REPEATER_EN")
		)
		(pad "6" smd rect
			(at -0.32512 -2.05486 270)
			(size 0.3556 1.524)
			(layers "B.Cu" "B.Mask" "B.Paste")
			(net "SMDAT_PCH_R")
		)
		(pad "7" smd rect
			(at 0.32512 -2.05486 270)
			(size 0.3556 1.524)
			(layers "B.Cu" "B.Mask" "B.Paste")
			(net "SMCLK_PCH_R")
		)
		(pad "8" smd rect
			(at 0.97536 -2.05486 270)
			(size 0.3556 1.524)
			(layers "B.Cu" "B.Mask" "B.Paste")
			(net "P3V3_STBY")
		)
	)
	(footprint ""
		(layer "B.Cu")
		(at 107.1626 5.207 -90)
		(property "Reference" "R49"
			(at 0 0 90)
			(layer "B.SilkS")
			(hide yes)
			(effects
				(font
					(size 1.27 1.27)
				)
				(justify mirror)
			)
		)
		(property "Value" "0R2F-1-GP"
			(at -0.064008 -3.993896 270)
			(unlocked yes)
			(layer "B.Fab")
			(hide yes)
			(effects
				(font
					(size 1.016 1.016)
					(thickness 0.1524)
				)
				(justify mirror)
			)
		)
		(property "Device Type" "R402H16"
			(at -0.064008 -5.517896 270)
			(unlocked yes)
			(layer "B.Fab")
			(hide yes)
			(effects
				(font
					(size 1.016 1.016)
					(thickness 0.1524)
				)
				(justify mirror)
			)
		)
		(duplicate_pad_numbers_are_jumpers no)
		(fp_line
			(start -0.508 -0.9398)
			(end 0.508 -0.9398)
			(stroke
				(width 0.1524)
				(type default)
			)
			(layer "B.SilkS")
		)
		(fp_line
			(start 0.508 -0.9398)
			(end 0.508 0.9398)
			(stroke
				(width 0.1524)
				(type default)
			)
			(layer "B.SilkS")
		)
		(fp_rect
			(start 0.508 0.9398)
			(end -0.508 -0.9398)
			(stroke
				(width 0)
				(type default)
			)
			(fill no)
			(layer "B.CrtYd")
		)
		(fp_rect
			(start 0.508 0.9398)
			(end -0.508 -0.9398)
			(stroke
				(width 0)
				(type default)
			)
			(fill no)
			(layer "B.Fab")
		)
		(pad "1" smd custom
			(at 0 -0.4445 90)
			(size 0.1397 0.1397)
			(layers "B.Cu" "B.Mask" "B.Paste")
			(net "SMDAT_BMC_R")
			(options
				(clearance outline)
				(anchor circle)
			)
			(primitives
				(gr_poly
					(pts
						(arc
							(start -0.1778 0.2794)
							(mid -0.249642 0.249642)
							(end -0.2794 0.1778)
						)
						(arc
							(start -0.2794 -0.1778)
							(mid -0.249642 -0.249642)
							(end -0.1778 -0.2794)
						)
						(arc
							(start 0.1778 -0.2794)
							(mid 0.249642 -0.249642)
							(end 0.2794 -0.1778)
						)
						(arc
							(start 0.2794 0.1778)
							(mid 0.249642 0.249642)
							(end 0.1778 0.2794)
						)
					)
					(width 0)
					(fill yes)
				)
			)
		)
		(pad "2" smd custom
			(at 0 0.4445 90)
			(size 0.1397 0.1397)
			(layers "B.Cu" "B.Mask" "B.Paste")
			(net "SMB_SLOTX24_STBY_LVC3_SDA_R2")
			(options
				(clearance outline)
				(anchor circle)
			)
			(primitives
				(gr_poly
					(pts
						(arc
							(start -0.1778 0.2794)
							(mid -0.249642 0.249642)
							(end -0.2794 0.1778)
						)
						(arc
							(start -0.2794 -0.1778)
							(mid -0.249642 -0.249642)
							(end -0.1778 -0.2794)
						)
						(arc
							(start 0.1778 -0.2794)
							(mid 0.249642 -0.249642)
							(end 0.2794 -0.1778)
						)
						(arc
							(start 0.2794 0.1778)
							(mid 0.249642 0.249642)
							(end 0.1778 0.2794)
						)
					)
					(width 0)
					(fill yes)
				)
			)
		)
	)
	(footprint ""
		(layer "B.Cu")
		(at 23.1394 -31.9532 180)
		(property "Reference" "C88"
			(at 0 0 0)
			(layer "B.SilkS")
			(hide yes)
			(effects
				(font
					(size 1.27 1.27)
				)
				(justify mirror)
			)
		)
		(property "Value" "SC22U16V5MX-4-GP"
			(at 0.0762 -6.1214 180)
			(unlocked yes)
			(layer "B.Fab")
			(hide yes)
			(effects
				(font
					(size 1.016 1.016)
					(thickness 0.1524)
				)
				(justify mirror)
			)
		)
		(property "Device Type" "C805H58"
			(at 0.0762 -8.1534 180)
			(unlocked yes)
			(layer "B.Fab")
			(hide yes)
			(effects
				(font
					(size 1.016 1.016)
					(thickness 0.1524)
				)
				(justify mirror)
			)
		)
		(duplicate_pad_numbers_are_jumpers no)
		(fp_line
			(start -0.635 0)
			(end 0.635 0)
			(stroke
				(width 0.508)
				(type default)
			)
			(layer "B.SilkS")
		)
		(fp_rect
			(start 0.9652 1.778)
			(end -0.9652 -1.778)
			(stroke
				(width 0)
				(type default)
			)
			(fill no)
			(layer "B.CrtYd")
		)
		(fp_poly
			(pts
				(xy 0.9652 -1.778) (xy -0.9652 -1.778) (xy -0.9652 1.778) (xy 0.9652 1.778)
			)
			(stroke
				(width 0)
				(type default)
			)
			(fill no)
			(layer "B.Fab")
		)
		(pad "1" smd rect
			(at 0 -0.9652)
			(size 1.397 1.143)
			(layers "B.Cu" "B.Mask" "B.Paste")
			(net "P12V_ATX")
		)
		(pad "2" smd rect
			(at 0 0.9652)
			(size 1.397 1.143)
			(layers "B.Cu" "B.Mask" "B.Paste")
			(net "GND")
		)
	)
	(footprint ""
		(layer "B.Cu")
		(at 23.1394 -18.0594 180)
		(property "Reference" "R89"
			(at 0 0 0)
			(layer "B.SilkS")
			(hide yes)
			(effects
				(font
					(size 1.27 1.27)
				)
				(justify mirror)
			)
		)
		(property "Value" "0R2F-1-GP"
			(at -0.064008 -3.993896 180)
			(unlocked yes)
			(layer "B.Fab")
			(hide yes)
			(effects
				(font
					(size 1.016 1.016)
					(thickness 0.1524)
				)
				(justify mirror)
			)
		)
		(property "Device Type" "R402H16"
			(at -0.064008 -5.517896 180)
			(unlocked yes)
			(layer "B.Fab")
			(hide yes)
			(effects
				(font
					(size 1.016 1.016)
					(thickness 0.1524)
				)
				(justify mirror)
			)
		)
		(duplicate_pad_numbers_are_jumpers no)
		(fp_line
			(start 0.508 -0.9398)
			(end 0.508 0.9398)
			(stroke
				(width 0.1524)
				(type default)
			)
			(layer "B.SilkS")
		)
		(fp_line
			(start -0.508 -0.9398)
			(end 0.508 -0.9398)
			(stroke
				(width 0.1524)
				(type default)
			)
			(layer "B.SilkS")
		)
		(fp_rect
			(start 0.508 0.9398)
			(end -0.508 -0.9398)
			(stroke
				(width 0)
				(type default)
			)
			(fill no)
			(layer "B.CrtYd")
		)
		(fp_rect
			(start 0.508 0.9398)
			(end -0.508 -0.9398)
			(stroke
				(width 0)
				(type default)
			)
			(fill no)
			(layer "B.Fab")
		)
		(pad "1" smd custom
			(at 0 -0.4445)
			(size 0.1397 0.1397)
			(layers "B.Cu" "B.Mask" "B.Paste")
			(net "SMB_VMONITOR_SLOT3_MUX_SCL")
			(options
				(clearance outline)
				(anchor circle)
			)
			(primitives
				(gr_poly
					(pts
						(arc
							(start -0.1778 0.2794)
							(mid -0.249642 0.249642)
							(end -0.2794 0.1778)
						)
						(arc
							(start -0.2794 -0.1778)
							(mid -0.249642 -0.249642)
							(end -0.1778 -0.2794)
						)
						(arc
							(start 0.1778 -0.2794)
							(mid 0.249642 -0.249642)
							(end 0.2794 -0.1778)
						)
						(arc
							(start 0.2794 0.1778)
							(mid 0.249642 0.249642)
							(end 0.1778 0.2794)
						)
					)
					(width 0)
					(fill yes)
				)
			)
		)
		(pad "2" smd custom
			(at 0 0.4445)
			(size 0.1397 0.1397)
			(layers "B.Cu" "B.Mask" "B.Paste")
			(net "SMCLK_BMC_DEVICE")
			(options
				(clearance outline)
				(anchor circle)
			)
			(primitives
				(gr_poly
					(pts
						(arc
							(start -0.1778 0.2794)
							(mid -0.249642 0.249642)
							(end -0.2794 0.1778)
						)
						(arc
							(start -0.2794 -0.1778)
							(mid -0.249642 -0.249642)
							(end -0.1778 -0.2794)
						)
						(arc
							(start 0.1778 -0.2794)
							(mid 0.249642 -0.249642)
							(end 0.2794 -0.1778)
						)
						(arc
							(start 0.2794 0.1778)
							(mid 0.249642 0.249642)
							(end 0.1778 0.2794)
						)
					)
					(width 0)
					(fill yes)
				)
			)
		)
	)
	(footprint ""
		(layer "B.Cu")
		(at 130.2766 -22.4028)
		(property "Reference" "R174"
			(at 0 0 0)
			(layer "B.SilkS")
			(hide yes)
			(effects
				(font
					(size 1.27 1.27)
				)
				(justify mirror)
			)
		)
		(property "Value" "0R2F-1-GP"
			(at -0.064008 -3.993896 0)
			(unlocked yes)
			(layer "B.Fab")
			(hide yes)
			(effects
				(font
					(size 1.016 1.016)
					(thickness 0.1524)
				)
				(justify mirror)
			)
		)
		(property "Device Type" "R402H16"
			(at -0.064008 -5.517896 0)
			(unlocked yes)
			(layer "B.Fab")
			(hide yes)
			(effects
				(font
					(size 1.016 1.016)
					(thickness 0.1524)
				)
				(justify mirror)
			)
		)
		(duplicate_pad_numbers_are_jumpers no)
		(fp_line
			(start -0.508 -0.9398)
			(end 0.508 -0.9398)
			(stroke
				(width 0.1524)
				(type default)
			)
			(layer "B.SilkS")
		)
		(fp_line
			(start 0.508 -0.9398)
			(end 0.508 0.9398)
			(stroke
				(width 0.1524)
				(type default)
			)
			(layer "B.SilkS")
		)
		(fp_rect
			(start 0.508 0.9398)
			(end -0.508 -0.9398)
			(stroke
				(width 0)
				(type default)
			)
			(fill no)
			(layer "B.CrtYd")
		)
		(fp_rect
			(start 0.508 0.9398)
			(end -0.508 -0.9398)
			(stroke
				(width 0)
				(type default)
			)
			(fill no)
			(layer "B.Fab")
		)
		(pad "1" smd custom
			(at 0 -0.4445 180)
			(size 0.1397 0.1397)
			(layers "B.Cu" "B.Mask" "B.Paste")
			(net "SMCLK_USB_HUB")
			(options
				(clearance outline)
				(anchor circle)
			)
			(primitives
				(gr_poly
					(pts
						(arc
							(start -0.1778 0.2794)
							(mid -0.249642 0.249642)
							(end -0.2794 0.1778)
						)
						(arc
							(start -0.2794 -0.1778)
							(mid -0.249642 -0.249642)
							(end -0.1778 -0.2794)
						)
						(arc
							(start 0.1778 -0.2794)
							(mid 0.249642 -0.249642)
							(end 0.2794 -0.1778)
						)
						(arc
							(start 0.2794 0.1778)
							(mid 0.249642 0.249642)
							(end 0.1778 0.2794)
						)
					)
					(width 0)
					(fill yes)
				)
			)
		)
		(pad "2" smd custom
			(at 0 0.4445 180)
			(size 0.1397 0.1397)
			(layers "B.Cu" "B.Mask" "B.Paste")
			(net "SMCLK_BMC_DEVICE")
			(options
				(clearance outline)
				(anchor circle)
			)
			(primitives
				(gr_poly
					(pts
						(arc
							(start -0.1778 0.2794)
							(mid -0.249642 0.249642)
							(end -0.2794 0.1778)
						)
						(arc
							(start -0.2794 -0.1778)
							(mid -0.249642 -0.249642)
							(end -0.1778 -0.2794)
						)
						(arc
							(start 0.1778 -0.2794)
							(mid 0.249642 -0.249642)
							(end 0.2794 -0.1778)
						)
						(arc
							(start 0.2794 0.1778)
							(mid 0.249642 0.249642)
							(end 0.1778 0.2794)
						)
					)
					(width 0)
					(fill yes)
				)
			)
		)
	)
	(footprint ""
		(layer "B.Cu")
		(at 118.1862 -18.796 -90)
		(property "Reference" "RU153"
			(at 0 0 90)
			(layer "B.SilkS")
			(hide yes)
			(effects
				(font
					(size 1.27 1.27)
				)
				(justify mirror)
			)
		)
		(property "Value" "4K7R2F-GP"
			(at -0.064008 -3.993896 270)
			(unlocked yes)
			(layer "B.Fab")
			(hide yes)
			(effects
				(font
					(size 1.016 1.016)
					(thickness 0.1524)
				)
				(justify mirror)
			)
		)
		(property "Device Type" "R402H16"
			(at -0.064008 -5.517896 270)
			(unlocked yes)
			(layer "B.Fab")
			(hide yes)
			(effects
				(font
					(size 1.016 1.016)
					(thickness 0.1524)
				)
				(justify mirror)
			)
		)
		(duplicate_pad_numbers_are_jumpers no)
		(fp_line
			(start -0.508 -0.9398)
			(end 0.508 -0.9398)
			(stroke
				(width 0.1524)
				(type default)
			)
			(layer "B.SilkS")
		)
		(fp_line
			(start 0.508 -0.9398)
			(end 0.508 0.9398)
			(stroke
				(width 0.1524)
				(type default)
			)
			(layer "B.SilkS")
		)
		(fp_rect
			(start 0.508 0.9398)
			(end -0.508 -0.9398)
			(stroke
				(width 0)
				(type default)
			)
			(fill no)
			(layer "B.CrtYd")
		)
		(fp_rect
			(start 0.508 0.9398)
			(end -0.508 -0.9398)
			(stroke
				(width 0)
				(type default)
			)
			(fill no)
			(layer "B.Fab")
		)
		(pad "1" smd custom
			(at 0 -0.4445 90)
			(size 0.1397 0.1397)
			(layers "B.Cu" "B.Mask" "B.Paste")
			(net "SMDAT_USB_HUB_R")
			(options
				(clearance outline)
				(anchor circle)
			)
			(primitives
				(gr_poly
					(pts
						(arc
							(start -0.1778 0.2794)
							(mid -0.249642 0.249642)
							(end -0.2794 0.1778)
						)
						(arc
							(start -0.2794 -0.1778)
							(mid -0.249642 -0.249642)
							(end -0.1778 -0.2794)
						)
						(arc
							(start 0.1778 -0.2794)
							(mid 0.249642 -0.249642)
							(end 0.2794 -0.1778)
						)
						(arc
							(start 0.2794 0.1778)
							(mid 0.249642 0.249642)
							(end 0.1778 0.2794)
						)
					)
					(width 0)
					(fill yes)
				)
			)
		)
		(pad "2" smd custom
			(at 0 0.4445 90)
			(size 0.1397 0.1397)
			(layers "B.Cu" "B.Mask" "B.Paste")
			(net "P3V3_USB_HUB")
			(options
				(clearance outline)
				(anchor circle)
			)
			(primitives
				(gr_poly
					(pts
						(arc
							(start -0.1778 0.2794)
							(mid -0.249642 0.249642)
							(end -0.2794 0.1778)
						)
						(arc
							(start -0.2794 -0.1778)
							(mid -0.249642 -0.249642)
							(end -0.1778 -0.2794)
						)
						(arc
							(start 0.1778 -0.2794)
							(mid 0.249642 -0.249642)
							(end 0.2794 -0.1778)
						)
						(arc
							(start 0.2794 0.1778)
							(mid 0.249642 0.249642)
							(end 0.1778 0.2794)
						)
					)
					(width 0)
					(fill yes)
				)
			)
		)
	)
	(footprint ""
		(layer "B.Cu")
		(at 107.1626 4.1656 -90)
		(property "Reference" "R48"
			(at 0 0 90)
			(layer "B.SilkS")
			(hide yes)
			(effects
				(font
					(size 1.27 1.27)
				)
				(justify mirror)
			)
		)
		(property "Value" "0R2F-1-GP"
			(at -0.064008 -3.993896 270)
			(unlocked yes)
			(layer "B.Fab")
			(hide yes)
			(effects
				(font
					(size 1.016 1.016)
					(thickness 0.1524)
				)
				(justify mirror)
			)
		)
		(property "Device Type" "R402H16"
			(at -0.064008 -5.517896 270)
			(unlocked yes)
			(layer "B.Fab")
			(hide yes)
			(effects
				(font
					(size 1.016 1.016)
					(thickness 0.1524)
				)
				(justify mirror)
			)
		)
		(duplicate_pad_numbers_are_jumpers no)
		(fp_line
			(start -0.508 -0.9398)
			(end 0.508 -0.9398)
			(stroke
				(width 0.1524)
				(type default)
			)
			(layer "B.SilkS")
		)
		(fp_line
			(start 0.508 -0.9398)
			(end 0.508 0.9398)
			(stroke
				(width 0.1524)
				(type default)
			)
			(layer "B.SilkS")
		)
		(fp_rect
			(start 0.508 0.9398)
			(end -0.508 -0.9398)
			(stroke
				(width 0)
				(type default)
			)
			(fill no)
			(layer "B.CrtYd")
		)
		(fp_rect
			(start 0.508 0.9398)
			(end -0.508 -0.9398)
			(stroke
				(width 0)
				(type default)
			)
			(fill no)
			(layer "B.Fab")
		)
		(pad "1" smd custom
			(at 0 -0.4445 90)
			(size 0.1397 0.1397)
			(layers "B.Cu" "B.Mask" "B.Paste")
			(net "SMCLK_BMC_R")
			(options
				(clearance outline)
				(anchor circle)
			)
			(primitives
				(gr_poly
					(pts
						(arc
							(start -0.1778 0.2794)
							(mid -0.249642 0.249642)
							(end -0.2794 0.1778)
						)
						(arc
							(start -0.2794 -0.1778)
							(mid -0.249642 -0.249642)
							(end -0.1778 -0.2794)
						)
						(arc
							(start 0.1778 -0.2794)
							(mid 0.249642 -0.249642)
							(end 0.2794 -0.1778)
						)
						(arc
							(start 0.2794 0.1778)
							(mid 0.249642 0.249642)
							(end 0.1778 0.2794)
						)
					)
					(width 0)
					(fill yes)
				)
			)
		)
		(pad "2" smd custom
			(at 0 0.4445 90)
			(size 0.1397 0.1397)
			(layers "B.Cu" "B.Mask" "B.Paste")
			(net "SMB_SLOTX24_STBY_LVC3_SCL_R2")
			(options
				(clearance outline)
				(anchor circle)
			)
			(primitives
				(gr_poly
					(pts
						(arc
							(start -0.1778 0.2794)
							(mid -0.249642 0.249642)
							(end -0.2794 0.1778)
						)
						(arc
							(start -0.2794 -0.1778)
							(mid -0.249642 -0.249642)
							(end -0.1778 -0.2794)
						)
						(arc
							(start 0.1778 -0.2794)
							(mid 0.249642 -0.249642)
							(end 0.2794 -0.1778)
						)
						(arc
							(start 0.2794 0.1778)
							(mid 0.249642 0.249642)
							(end 0.1778 0.2794)
						)
					)
					(width 0)
					(fill yes)
				)
			)
		)
	)
	(footprint ""
		(layer "B.Cu")
		(at 132.2578 -7.7978 -90)
		(property "Reference" "R67"
			(at 0 0 90)
			(layer "B.SilkS")
			(hide yes)
			(effects
				(font
					(size 1.27 1.27)
				)
				(justify mirror)
			)
		)
		(property "Value" "4K7R2F-GP"
			(at -0.064008 -3.993896 270)
			(unlocked yes)
			(layer "B.Fab")
			(hide yes)
			(effects
				(font
					(size 1.016 1.016)
					(thickness 0.1524)
				)
				(justify mirror)
			)
		)
		(property "Device Type" "R402H16"
			(at -0.064008 -5.517896 270)
			(unlocked yes)
			(layer "B.Fab")
			(hide yes)
			(effects
				(font
					(size 1.016 1.016)
					(thickness 0.1524)
				)
				(justify mirror)
			)
		)
		(duplicate_pad_numbers_are_jumpers no)
		(fp_line
			(start -0.508 -0.9398)
			(end 0.508 -0.9398)
			(stroke
				(width 0.1524)
				(type default)
			)
			(layer "B.SilkS")
		)
		(fp_line
			(start 0.508 -0.9398)
			(end 0.508 0.9398)
			(stroke
				(width 0.1524)
				(type default)
			)
			(layer "B.SilkS")
		)
		(fp_rect
			(start 0.508 0.9398)
			(end -0.508 -0.9398)
			(stroke
				(width 0)
				(type default)
			)
			(fill no)
			(layer "B.CrtYd")
		)
		(fp_rect
			(start 0.508 0.9398)
			(end -0.508 -0.9398)
			(stroke
				(width 0)
				(type default)
			)
			(fill no)
			(layer "B.Fab")
		)
		(pad "1" smd custom
			(at 0 -0.4445 90)
			(size 0.1397 0.1397)
			(layers "B.Cu" "B.Mask" "B.Paste")
			(net "P3V3_STBY")
			(options
				(clearance outline)
				(anchor circle)
			)
			(primitives
				(gr_poly
					(pts
						(arc
							(start -0.1778 0.2794)
							(mid -0.249642 0.249642)
							(end -0.2794 0.1778)
						)
						(arc
							(start -0.2794 -0.1778)
							(mid -0.249642 -0.249642)
							(end -0.1778 -0.2794)
						)
						(arc
							(start 0.1778 -0.2794)
							(mid 0.249642 -0.249642)
							(end 0.2794 -0.1778)
						)
						(arc
							(start 0.2794 0.1778)
							(mid 0.249642 0.249642)
							(end 0.1778 0.2794)
						)
					)
					(width 0)
					(fill yes)
				)
			)
		)
		(pad "2" smd custom
			(at 0 0.4445 90)
			(size 0.1397 0.1397)
			(layers "B.Cu" "B.Mask" "B.Paste")
			(net "GPIO_P_EXP_INT_N")
			(options
				(clearance outline)
				(anchor circle)
			)
			(primitives
				(gr_poly
					(pts
						(arc
							(start -0.1778 0.2794)
							(mid -0.249642 0.249642)
							(end -0.2794 0.1778)
						)
						(arc
							(start -0.2794 -0.1778)
							(mid -0.249642 -0.249642)
							(end -0.1778 -0.2794)
						)
						(arc
							(start 0.1778 -0.2794)
							(mid 0.249642 -0.249642)
							(end 0.2794 -0.1778)
						)
						(arc
							(start 0.2794 0.1778)
							(mid 0.249642 0.249642)
							(end 0.1778 0.2794)
						)
					)
					(width 0)
					(fill yes)
				)
			)
		)
	)
	(footprint ""
		(layer "B.Cu")
		(at 120.8278 -22.86 180)
		(property "Reference" "R111"
			(at 0 0 0)
			(layer "B.SilkS")
			(hide yes)
			(effects
				(font
					(size 1.27 1.27)
				)
				(justify mirror)
			)
		)
		(property "Value" "0R2F-1-GP"
			(at -0.064008 -3.993896 180)
			(unlocked yes)
			(layer "B.Fab")
			(hide yes)
			(effects
				(font
					(size 1.016 1.016)
					(thickness 0.1524)
				)
				(justify mirror)
			)
		)
		(property "Device Type" "R402H16"
			(at -0.064008 -5.517896 180)
			(unlocked yes)
			(layer "B.Fab")
			(hide yes)
			(effects
				(font
					(size 1.016 1.016)
					(thickness 0.1524)
				)
				(justify mirror)
			)
		)
		(duplicate_pad_numbers_are_jumpers no)
		(fp_line
			(start 0.508 -0.9398)
			(end 0.508 0.9398)
			(stroke
				(width 0.1524)
				(type default)
			)
			(layer "B.SilkS")
		)
		(fp_line
			(start -0.508 -0.9398)
			(end 0.508 -0.9398)
			(stroke
				(width 0.1524)
				(type default)
			)
			(layer "B.SilkS")
		)
		(fp_rect
			(start 0.508 0.9398)
			(end -0.508 -0.9398)
			(stroke
				(width 0)
				(type default)
			)
			(fill no)
			(layer "B.CrtYd")
		)
		(fp_rect
			(start 0.508 0.9398)
			(end -0.508 -0.9398)
			(stroke
				(width 0)
				(type default)
			)
			(fill no)
			(layer "B.Fab")
		)
		(pad "1" smd custom
			(at 0 -0.4445)
			(size 0.1397 0.1397)
			(layers "B.Cu" "B.Mask" "B.Paste")
			(net "SMCLK_USB_HUB_R")
			(options
				(clearance outline)
				(anchor circle)
			)
			(primitives
				(gr_poly
					(pts
						(arc
							(start -0.1778 0.2794)
							(mid -0.249642 0.249642)
							(end -0.2794 0.1778)
						)
						(arc
							(start -0.2794 -0.1778)
							(mid -0.249642 -0.249642)
							(end -0.1778 -0.2794)
						)
						(arc
							(start 0.1778 -0.2794)
							(mid 0.249642 -0.249642)
							(end 0.2794 -0.1778)
						)
						(arc
							(start 0.2794 0.1778)
							(mid 0.249642 0.249642)
							(end 0.1778 0.2794)
						)
					)
					(width 0)
					(fill yes)
				)
			)
		)
		(pad "2" smd custom
			(at 0 0.4445)
			(size 0.1397 0.1397)
			(layers "B.Cu" "B.Mask" "B.Paste")
			(net "SMCLK_USB_HUB")
			(options
				(clearance outline)
				(anchor circle)
			)
			(primitives
				(gr_poly
					(pts
						(arc
							(start -0.1778 0.2794)
							(mid -0.249642 0.249642)
							(end -0.2794 0.1778)
						)
						(arc
							(start -0.2794 -0.1778)
							(mid -0.249642 -0.249642)
							(end -0.1778 -0.2794)
						)
						(arc
							(start 0.1778 -0.2794)
							(mid 0.249642 -0.249642)
							(end 0.2794 -0.1778)
						)
						(arc
							(start 0.2794 0.1778)
							(mid 0.249642 0.249642)
							(end 0.1778 0.2794)
						)
					)
					(width 0)
					(fill yes)
				)
			)
		)
	)
	(footprint ""
		(layer "B.Cu")
		(at 28.4607 2.1971)
		(property "Reference" "PC7"
			(at 0 0 0)
			(layer "B.SilkS")
			(hide yes)
			(effects
				(font
					(size 1.27 1.27)
				)
				(justify mirror)
			)
		)
		(property "Value" "SC22U6D3V5MX-5-GP"
			(at 0.0762 -6.1214 0)
			(unlocked yes)
			(layer "B.Fab")
			(hide yes)
			(effects
				(font
					(size 1.016 1.016)
					(thickness 0.1524)
				)
				(justify mirror)
			)
		)
		(property "Device Type" "C805H56"
			(at 0.0762 -8.1534 0)
			(unlocked yes)
			(layer "B.Fab")
			(hide yes)
			(effects
				(font
					(size 1.016 1.016)
					(thickness 0.1524)
				)
				(justify mirror)
			)
		)
		(duplicate_pad_numbers_are_jumpers no)
		(fp_line
			(start -0.635 0)
			(end 0.635 0)
			(stroke
				(width 0.508)
				(type default)
			)
			(layer "B.SilkS")
		)
		(fp_rect
			(start 0.9652 1.778)
			(end -0.9652 -1.778)
			(stroke
				(width 0)
				(type default)
			)
			(fill no)
			(layer "B.CrtYd")
		)
		(fp_poly
			(pts
				(xy 0.9652 -1.778) (xy -0.9652 -1.778) (xy -0.9652 1.778) (xy 0.9652 1.778)
			)
			(stroke
				(width 0)
				(type default)
			)
			(fill no)
			(layer "B.Fab")
		)
		(pad "1" smd rect
			(at 0 -0.9652 180)
			(size 1.397 1.143)
			(layers "B.Cu" "B.Mask" "B.Paste")
			(net "P3V3_VR")
		)
		(pad "2" smd rect
			(at 0 0.9652 180)
			(size 1.397 1.143)
			(layers "B.Cu" "B.Mask" "B.Paste")
			(net "GND")
		)
	)
	(footprint ""
		(layer "B.Cu")
		(at 32.8422 1.1557 -90)
		(property "Reference" "C58"
			(at 0 0 90)
			(layer "B.SilkS")
			(hide yes)
			(effects
				(font
					(size 1.27 1.27)
				)
				(justify mirror)
			)
		)
		(property "Value" "SCD1U16V2KX-3GP"
			(at -1.1811 -2.7051 270)
			(unlocked yes)
			(layer "B.Fab")
			(hide yes)
			(effects
				(font
					(size 1.016 1.016)
					(thickness 0.1524)
				)
				(justify mirror)
			)
		)
		(property "Device Type" "C402H22"
			(at -1.1811 -4.2291 270)
			(unlocked yes)
			(layer "B.Fab")
			(hide yes)
			(effects
				(font
					(size 1.016 1.016)
					(thickness 0.1524)
				)
				(justify mirror)
			)
		)
		(duplicate_pad_numbers_are_jumpers no)
		(fp_rect
			(start 0.4318 0.9525)
			(end -0.4318 -0.9525)
			(stroke
				(width 0)
				(type default)
			)
			(fill no)
			(layer "B.CrtYd")
		)
		(fp_rect
			(start 0.4318 0.9525)
			(end -0.4318 -0.9525)
			(stroke
				(width 0)
				(type default)
			)
			(fill no)
			(layer "B.Fab")
		)
		(pad "1" smd custom
			(at 0 -0.4445 90)
			(size 0.1524 0.1524)
			(layers "B.Cu" "B.Mask" "B.Paste")
			(net "P3V3_STBY")
			(options
				(clearance outline)
				(anchor circle)
			)
			(primitives
				(gr_poly
					(pts
						(arc
							(start 0.3048 0.2032)
							(mid 0.275042 0.275042)
							(end 0.2032 0.3048)
						)
						(arc
							(start -0.2032 0.3048)
							(mid -0.275042 0.275042)
							(end -0.3048 0.2032)
						)
						(arc
							(start -0.3048 -0.2032)
							(mid -0.275042 -0.275042)
							(end -0.2032 -0.3048)
						)
						(arc
							(start 0.2032 -0.3048)
							(mid 0.275042 -0.275042)
							(end 0.3048 -0.2032)
						)
					)
					(width 0)
					(fill yes)
				)
			)
		)
		(pad "2" smd custom
			(at 0 0.4445 90)
			(size 0.1524 0.1524)
			(layers "B.Cu" "B.Mask" "B.Paste")
			(net "GND")
			(options
				(clearance outline)
				(anchor circle)
			)
			(primitives
				(gr_poly
					(pts
						(arc
							(start 0.3048 0.2032)
							(mid 0.275042 0.275042)
							(end 0.2032 0.3048)
						)
						(arc
							(start -0.2032 0.3048)
							(mid -0.275042 0.275042)
							(end -0.3048 0.2032)
						)
						(arc
							(start -0.3048 -0.2032)
							(mid -0.275042 -0.275042)
							(end -0.2032 -0.3048)
						)
						(arc
							(start 0.2032 -0.3048)
							(mid 0.275042 -0.275042)
							(end 0.3048 -0.2032)
						)
					)
					(width 0)
					(fill yes)
				)
			)
		)
	)
	(footprint ""
		(layer "B.Cu")
		(at 18.7706 -19.3802 90)
		(property "Reference" "C53"
			(at 0 0 90)
			(layer "B.SilkS")
			(hide yes)
			(effects
				(font
					(size 1.27 1.27)
				)
				(justify mirror)
			)
		)
		(property "Value" "SCD1U25V2KX-2-GP"
			(at -1.1811 -2.7051 90)
			(unlocked yes)
			(layer "B.Fab")
			(hide yes)
			(effects
				(font
					(size 1.016 1.016)
					(thickness 0.1524)
				)
				(justify mirror)
			)
		)
		(property "Device Type" "C402H22"
			(at -1.1811 -4.2291 90)
			(unlocked yes)
			(layer "B.Fab")
			(hide yes)
			(effects
				(font
					(size 1.016 1.016)
					(thickness 0.1524)
				)
				(justify mirror)
			)
		)
		(duplicate_pad_numbers_are_jumpers no)
		(fp_rect
			(start 0.4318 0.9525)
			(end -0.4318 -0.9525)
			(stroke
				(width 0)
				(type default)
			)
			(fill no)
			(layer "B.CrtYd")
		)
		(fp_rect
			(start 0.4318 0.9525)
			(end -0.4318 -0.9525)
			(stroke
				(width 0)
				(type default)
			)
			(fill no)
			(layer "B.Fab")
		)
		(pad "1" smd custom
			(at 0 -0.4445 270)
			(size 0.1524 0.1524)
			(layers "B.Cu" "B.Mask" "B.Paste")
			(net "P12V")
			(options
				(clearance outline)
				(anchor circle)
			)
			(primitives
				(gr_poly
					(pts
						(arc
							(start 0.3048 0.2032)
							(mid 0.275042 0.275042)
							(end 0.2032 0.3048)
						)
						(arc
							(start -0.2032 0.3048)
							(mid -0.275042 0.275042)
							(end -0.3048 0.2032)
						)
						(arc
							(start -0.3048 -0.2032)
							(mid -0.275042 -0.275042)
							(end -0.2032 -0.3048)
						)
						(arc
							(start 0.2032 -0.3048)
							(mid 0.275042 -0.275042)
							(end 0.3048 -0.2032)
						)
					)
					(width 0)
					(fill yes)
				)
			)
		)
		(pad "2" smd custom
			(at 0 0.4445 270)
			(size 0.1524 0.1524)
			(layers "B.Cu" "B.Mask" "B.Paste")
			(net "GND")
			(options
				(clearance outline)
				(anchor circle)
			)
			(primitives
				(gr_poly
					(pts
						(arc
							(start 0.3048 0.2032)
							(mid 0.275042 0.275042)
							(end 0.2032 0.3048)
						)
						(arc
							(start -0.2032 0.3048)
							(mid -0.275042 0.275042)
							(end -0.3048 0.2032)
						)
						(arc
							(start -0.3048 -0.2032)
							(mid -0.275042 -0.275042)
							(end -0.2032 -0.3048)
						)
						(arc
							(start 0.2032 -0.3048)
							(mid 0.275042 -0.275042)
							(end 0.3048 -0.2032)
						)
					)
					(width 0)
					(fill yes)
				)
			)
		)
	)
	(footprint ""
		(layer "B.Cu")
		(at 126.6952 -11.7094 180)
		(property "Reference" "R52"
			(at 0 0 0)
			(layer "B.SilkS")
			(hide yes)
			(effects
				(font
					(size 1.27 1.27)
				)
				(justify mirror)
			)
		)
		(property "Value" "10KR2F-2-GP"
			(at -0.064008 -3.993896 180)
			(unlocked yes)
			(layer "B.Fab")
			(hide yes)
			(effects
				(font
					(size 1.016 1.016)
					(thickness 0.1524)
				)
				(justify mirror)
			)
		)
		(property "Device Type" "R402H16"
			(at -0.064008 -5.517896 180)
			(unlocked yes)
			(layer "B.Fab")
			(hide yes)
			(effects
				(font
					(size 1.016 1.016)
					(thickness 0.1524)
				)
				(justify mirror)
			)
		)
		(duplicate_pad_numbers_are_jumpers no)
		(fp_line
			(start 0.508 -0.9398)
			(end 0.508 0.9398)
			(stroke
				(width 0.1524)
				(type default)
			)
			(layer "B.SilkS")
		)
		(fp_line
			(start -0.508 -0.9398)
			(end 0.508 -0.9398)
			(stroke
				(width 0.1524)
				(type default)
			)
			(layer "B.SilkS")
		)
		(fp_rect
			(start 0.508 0.9398)
			(end -0.508 -0.9398)
			(stroke
				(width 0)
				(type default)
			)
			(fill no)
			(layer "B.CrtYd")
		)
		(fp_rect
			(start 0.508 0.9398)
			(end -0.508 -0.9398)
			(stroke
				(width 0)
				(type default)
			)
			(fill no)
			(layer "B.Fab")
		)
		(pad "1" smd custom
			(at 0 -0.4445)
			(size 0.1397 0.1397)
			(layers "B.Cu" "B.Mask" "B.Paste")
			(net "SMB_P_HUB_A2")
			(options
				(clearance outline)
				(anchor circle)
			)
			(primitives
				(gr_poly
					(pts
						(arc
							(start -0.1778 0.2794)
							(mid -0.249642 0.249642)
							(end -0.2794 0.1778)
						)
						(arc
							(start -0.2794 -0.1778)
							(mid -0.249642 -0.249642)
							(end -0.1778 -0.2794)
						)
						(arc
							(start 0.1778 -0.2794)
							(mid 0.249642 -0.249642)
							(end 0.2794 -0.1778)
						)
						(arc
							(start 0.2794 0.1778)
							(mid 0.249642 0.249642)
							(end 0.1778 0.2794)
						)
					)
					(width 0)
					(fill yes)
				)
			)
		)
		(pad "2" smd custom
			(at 0 0.4445)
			(size 0.1397 0.1397)
			(layers "B.Cu" "B.Mask" "B.Paste")
			(net "GND")
			(options
				(clearance outline)
				(anchor circle)
			)
			(primitives
				(gr_poly
					(pts
						(arc
							(start -0.1778 0.2794)
							(mid -0.249642 0.249642)
							(end -0.2794 0.1778)
						)
						(arc
							(start -0.2794 -0.1778)
							(mid -0.249642 -0.249642)
							(end -0.1778 -0.2794)
						)
						(arc
							(start 0.1778 -0.2794)
							(mid 0.249642 -0.249642)
							(end 0.2794 -0.1778)
						)
						(arc
							(start 0.2794 0.1778)
							(mid 0.249642 0.249642)
							(end 0.1778 0.2794)
						)
					)
					(width 0)
					(fill yes)
				)
			)
		)
	)
	(footprint ""
		(layer "B.Cu")
		(at 102.2604 2.9718 180)
		(property "Reference" "R4"
			(at 0 0 0)
			(layer "B.SilkS")
			(hide yes)
			(effects
				(font
					(size 1.27 1.27)
				)
				(justify mirror)
			)
		)
		(property "Value" "4K7R2F-GP"
			(at -0.064008 -3.993896 180)
			(unlocked yes)
			(layer "B.Fab")
			(hide yes)
			(effects
				(font
					(size 1.016 1.016)
					(thickness 0.1524)
				)
				(justify mirror)
			)
		)
		(property "Device Type" "R402H16"
			(at -0.064008 -5.517896 180)
			(unlocked yes)
			(layer "B.Fab")
			(hide yes)
			(effects
				(font
					(size 1.016 1.016)
					(thickness 0.1524)
				)
				(justify mirror)
			)
		)
		(duplicate_pad_numbers_are_jumpers no)
		(fp_line
			(start 0.508 -0.9398)
			(end 0.508 0.9398)
			(stroke
				(width 0.1524)
				(type default)
			)
			(layer "B.SilkS")
		)
		(fp_line
			(start -0.508 -0.9398)
			(end 0.508 -0.9398)
			(stroke
				(width 0.1524)
				(type default)
			)
			(layer "B.SilkS")
		)
		(fp_rect
			(start 0.508 0.9398)
			(end -0.508 -0.9398)
			(stroke
				(width 0)
				(type default)
			)
			(fill no)
			(layer "B.CrtYd")
		)
		(fp_rect
			(start 0.508 0.9398)
			(end -0.508 -0.9398)
			(stroke
				(width 0)
				(type default)
			)
			(fill no)
			(layer "B.Fab")
		)
		(pad "1" smd custom
			(at 0 -0.4445)
			(size 0.1397 0.1397)
			(layers "B.Cu" "B.Mask" "B.Paste")
			(net "P3V3_STBY")
			(options
				(clearance outline)
				(anchor circle)
			)
			(primitives
				(gr_poly
					(pts
						(arc
							(start -0.1778 0.2794)
							(mid -0.249642 0.249642)
							(end -0.2794 0.1778)
						)
						(arc
							(start -0.2794 -0.1778)
							(mid -0.249642 -0.249642)
							(end -0.1778 -0.2794)
						)
						(arc
							(start 0.1778 -0.2794)
							(mid 0.249642 -0.249642)
							(end 0.2794 -0.1778)
						)
						(arc
							(start 0.2794 0.1778)
							(mid 0.249642 0.249642)
							(end 0.1778 0.2794)
						)
					)
					(width 0)
					(fill yes)
				)
			)
		)
		(pad "2" smd custom
			(at 0 0.4445)
			(size 0.1397 0.1397)
			(layers "B.Cu" "B.Mask" "B.Paste")
			(net "SMDAT_BMC_SLOT2")
			(options
				(clearance outline)
				(anchor circle)
			)
			(primitives
				(gr_poly
					(pts
						(arc
							(start -0.1778 0.2794)
							(mid -0.249642 0.249642)
							(end -0.2794 0.1778)
						)
						(arc
							(start -0.2794 -0.1778)
							(mid -0.249642 -0.249642)
							(end -0.1778 -0.2794)
						)
						(arc
							(start 0.1778 -0.2794)
							(mid 0.249642 -0.249642)
							(end 0.2794 -0.1778)
						)
						(arc
							(start 0.2794 0.1778)
							(mid 0.249642 0.249642)
							(end 0.1778 0.2794)
						)
					)
					(width 0)
					(fill yes)
				)
			)
		)
	)
	(footprint ""
		(layer "B.Cu")
		(at 125.857 -26.6954 180)
		(property "Reference" "RU25"
			(at 0 0 0)
			(layer "B.SilkS")
			(hide yes)
			(effects
				(font
					(size 1.27 1.27)
				)
				(justify mirror)
			)
		)
		(property "Value" "100KR2F-L1-GP"
			(at -0.064008 -3.993896 180)
			(unlocked yes)
			(layer "B.Fab")
			(hide yes)
			(effects
				(font
					(size 1.016 1.016)
					(thickness 0.1524)
				)
				(justify mirror)
			)
		)
		(property "Device Type" "R402H16"
			(at -0.064008 -5.517896 180)
			(unlocked yes)
			(layer "B.Fab")
			(hide yes)
			(effects
				(font
					(size 1.016 1.016)
					(thickness 0.1524)
				)
				(justify mirror)
			)
		)
		(duplicate_pad_numbers_are_jumpers no)
		(fp_line
			(start 0.508 -0.9398)
			(end 0.508 0.9398)
			(stroke
				(width 0.1524)
				(type default)
			)
			(layer "B.SilkS")
		)
		(fp_line
			(start -0.508 -0.9398)
			(end 0.508 -0.9398)
			(stroke
				(width 0.1524)
				(type default)
			)
			(layer "B.SilkS")
		)
		(fp_rect
			(start 0.508 0.9398)
			(end -0.508 -0.9398)
			(stroke
				(width 0)
				(type default)
			)
			(fill no)
			(layer "B.CrtYd")
		)
		(fp_rect
			(start 0.508 0.9398)
			(end -0.508 -0.9398)
			(stroke
				(width 0)
				(type default)
			)
			(fill no)
			(layer "B.Fab")
		)
		(pad "1" smd custom
			(at 0 -0.4445)
			(size 0.1397 0.1397)
			(layers "B.Cu" "B.Mask" "B.Paste")
			(net "CFG_SEL1")
			(options
				(clearance outline)
				(anchor circle)
			)
			(primitives
				(gr_poly
					(pts
						(arc
							(start -0.1778 0.2794)
							(mid -0.249642 0.249642)
							(end -0.2794 0.1778)
						)
						(arc
							(start -0.2794 -0.1778)
							(mid -0.249642 -0.249642)
							(end -0.1778 -0.2794)
						)
						(arc
							(start 0.1778 -0.2794)
							(mid 0.249642 -0.249642)
							(end 0.2794 -0.1778)
						)
						(arc
							(start 0.2794 0.1778)
							(mid 0.249642 0.249642)
							(end 0.1778 0.2794)
						)
					)
					(width 0)
					(fill yes)
				)
			)
		)
		(pad "2" smd custom
			(at 0 0.4445)
			(size 0.1397 0.1397)
			(layers "B.Cu" "B.Mask" "B.Paste")
			(net "GND")
			(options
				(clearance outline)
				(anchor circle)
			)
			(primitives
				(gr_poly
					(pts
						(arc
							(start -0.1778 0.2794)
							(mid -0.249642 0.249642)
							(end -0.2794 0.1778)
						)
						(arc
							(start -0.2794 -0.1778)
							(mid -0.249642 -0.249642)
							(end -0.1778 -0.2794)
						)
						(arc
							(start 0.1778 -0.2794)
							(mid 0.249642 -0.249642)
							(end 0.2794 -0.1778)
						)
						(arc
							(start 0.2794 0.1778)
							(mid 0.249642 0.249642)
							(end 0.1778 0.2794)
						)
					)
					(width 0)
					(fill yes)
				)
			)
		)
	)
	(footprint ""
		(layer "B.Cu")
		(at 103.886 -0.1778 180)
		(property "Reference" "R6"
			(at 0 0 0)
			(layer "B.SilkS")
			(hide yes)
			(effects
				(font
					(size 1.27 1.27)
				)
				(justify mirror)
			)
		)
		(property "Value" "4K7R2F-GP"
			(at -0.064008 -3.993896 180)
			(unlocked yes)
			(layer "B.Fab")
			(hide yes)
			(effects
				(font
					(size 1.016 1.016)
					(thickness 0.1524)
				)
				(justify mirror)
			)
		)
		(property "Device Type" "R402H16"
			(at -0.064008 -5.517896 180)
			(unlocked yes)
			(layer "B.Fab")
			(hide yes)
			(effects
				(font
					(size 1.016 1.016)
					(thickness 0.1524)
				)
				(justify mirror)
			)
		)
		(duplicate_pad_numbers_are_jumpers no)
		(fp_line
			(start 0.508 -0.9398)
			(end 0.508 0.9398)
			(stroke
				(width 0.1524)
				(type default)
			)
			(layer "B.SilkS")
		)
		(fp_line
			(start -0.508 -0.9398)
			(end 0.508 -0.9398)
			(stroke
				(width 0.1524)
				(type default)
			)
			(layer "B.SilkS")
		)
		(fp_rect
			(start 0.508 0.9398)
			(end -0.508 -0.9398)
			(stroke
				(width 0)
				(type default)
			)
			(fill no)
			(layer "B.CrtYd")
		)
		(fp_rect
			(start 0.508 0.9398)
			(end -0.508 -0.9398)
			(stroke
				(width 0)
				(type default)
			)
			(fill no)
			(layer "B.Fab")
		)
		(pad "1" smd custom
			(at 0 -0.4445)
			(size 0.1397 0.1397)
			(layers "B.Cu" "B.Mask" "B.Paste")
			(net "P3V3_STBY")
			(options
				(clearance outline)
				(anchor circle)
			)
			(primitives
				(gr_poly
					(pts
						(arc
							(start -0.1778 0.2794)
							(mid -0.249642 0.249642)
							(end -0.2794 0.1778)
						)
						(arc
							(start -0.2794 -0.1778)
							(mid -0.249642 -0.249642)
							(end -0.1778 -0.2794)
						)
						(arc
							(start 0.1778 -0.2794)
							(mid 0.249642 -0.249642)
							(end 0.2794 -0.1778)
						)
						(arc
							(start 0.2794 0.1778)
							(mid 0.249642 0.249642)
							(end 0.1778 0.2794)
						)
					)
					(width 0)
					(fill yes)
				)
			)
		)
		(pad "2" smd custom
			(at 0 0.4445)
			(size 0.1397 0.1397)
			(layers "B.Cu" "B.Mask" "B.Paste")
			(net "SMDAT_BMC_SLOT3")
			(options
				(clearance outline)
				(anchor circle)
			)
			(primitives
				(gr_poly
					(pts
						(arc
							(start -0.1778 0.2794)
							(mid -0.249642 0.249642)
							(end -0.2794 0.1778)
						)
						(arc
							(start -0.2794 -0.1778)
							(mid -0.249642 -0.249642)
							(end -0.1778 -0.2794)
						)
						(arc
							(start 0.1778 -0.2794)
							(mid 0.249642 -0.249642)
							(end 0.2794 -0.1778)
						)
						(arc
							(start 0.2794 0.1778)
							(mid 0.249642 0.249642)
							(end 0.1778 0.2794)
						)
					)
					(width 0)
					(fill yes)
				)
			)
		)
	)
	(footprint ""
		(layer "B.Cu")
		(at 131.826 -6.3246 180)
		(property "Reference" "R166"
			(at 0 0 0)
			(layer "B.SilkS")
			(hide yes)
			(effects
				(font
					(size 1.27 1.27)
				)
				(justify mirror)
			)
		)
		(property "Value" "0R2F-1-GP"
			(at -0.064008 -3.993896 180)
			(unlocked yes)
			(layer "B.Fab")
			(hide yes)
			(effects
				(font
					(size 1.016 1.016)
					(thickness 0.1524)
				)
				(justify mirror)
			)
		)
		(property "Device Type" "R402H16"
			(at -0.064008 -5.517896 180)
			(unlocked yes)
			(layer "B.Fab")
			(hide yes)
			(effects
				(font
					(size 1.016 1.016)
					(thickness 0.1524)
				)
				(justify mirror)
			)
		)
		(duplicate_pad_numbers_are_jumpers no)
		(fp_line
			(start 0.508 -0.9398)
			(end 0.508 0.9398)
			(stroke
				(width 0.1524)
				(type default)
			)
			(layer "B.SilkS")
		)
		(fp_line
			(start -0.508 -0.9398)
			(end 0.508 -0.9398)
			(stroke
				(width 0.1524)
				(type default)
			)
			(layer "B.SilkS")
		)
		(fp_rect
			(start 0.508 0.9398)
			(end -0.508 -0.9398)
			(stroke
				(width 0)
				(type default)
			)
			(fill no)
			(layer "B.CrtYd")
		)
		(fp_rect
			(start 0.508 0.9398)
			(end -0.508 -0.9398)
			(stroke
				(width 0)
				(type default)
			)
			(fill no)
			(layer "B.Fab")
		)
		(pad "1" smd custom
			(at 0 -0.4445)
			(size 0.1397 0.1397)
			(layers "B.Cu" "B.Mask" "B.Paste")
			(net "SMB_PCH_DEVICE_ALERT_N")
			(options
				(clearance outline)
				(anchor circle)
			)
			(primitives
				(gr_poly
					(pts
						(arc
							(start -0.1778 0.2794)
							(mid -0.249642 0.249642)
							(end -0.2794 0.1778)
						)
						(arc
							(start -0.2794 -0.1778)
							(mid -0.249642 -0.249642)
							(end -0.1778 -0.2794)
						)
						(arc
							(start 0.1778 -0.2794)
							(mid 0.249642 -0.249642)
							(end 0.2794 -0.1778)
						)
						(arc
							(start 0.2794 0.1778)
							(mid 0.249642 0.249642)
							(end 0.1778 0.2794)
						)
					)
					(width 0)
					(fill yes)
				)
			)
		)
		(pad "2" smd custom
			(at 0 0.4445)
			(size 0.1397 0.1397)
			(layers "B.Cu" "B.Mask" "B.Paste")
			(net "GPIO_P_EXP_INT_N")
			(options
				(clearance outline)
				(anchor circle)
			)
			(primitives
				(gr_poly
					(pts
						(arc
							(start -0.1778 0.2794)
							(mid -0.249642 0.249642)
							(end -0.2794 0.1778)
						)
						(arc
							(start -0.2794 -0.1778)
							(mid -0.249642 -0.249642)
							(end -0.1778 -0.2794)
						)
						(arc
							(start 0.1778 -0.2794)
							(mid 0.249642 -0.249642)
							(end 0.2794 -0.1778)
						)
						(arc
							(start 0.2794 0.1778)
							(mid 0.249642 0.249642)
							(end 0.1778 0.2794)
						)
					)
					(width 0)
					(fill yes)
				)
			)
		)
	)
	(footprint ""
		(layer "B.Cu")
		(at 44.42206 -1.31826 -90)
		(property "Reference" "R36"
			(at 0 0 90)
			(layer "B.SilkS")
			(hide yes)
			(effects
				(font
					(size 1.27 1.27)
				)
				(justify mirror)
			)
		)
		(property "Value" "0R2F-1-GP"
			(at -0.064008 -3.993896 270)
			(unlocked yes)
			(layer "B.Fab")
			(hide yes)
			(effects
				(font
					(size 1.016 1.016)
					(thickness 0.1524)
				)
				(justify mirror)
			)
		)
		(property "Device Type" "R402H16"
			(at -0.064008 -5.517896 270)
			(unlocked yes)
			(layer "B.Fab")
			(hide yes)
			(effects
				(font
					(size 1.016 1.016)
					(thickness 0.1524)
				)
				(justify mirror)
			)
		)
		(duplicate_pad_numbers_are_jumpers no)
		(fp_line
			(start -0.508 -0.9398)
			(end 0.508 -0.9398)
			(stroke
				(width 0.1524)
				(type default)
			)
			(layer "B.SilkS")
		)
		(fp_line
			(start 0.508 -0.9398)
			(end 0.508 0.9398)
			(stroke
				(width 0.1524)
				(type default)
			)
			(layer "B.SilkS")
		)
		(fp_rect
			(start 0.508 0.9398)
			(end -0.508 -0.9398)
			(stroke
				(width 0)
				(type default)
			)
			(fill no)
			(layer "B.CrtYd")
		)
		(fp_rect
			(start 0.508 0.9398)
			(end -0.508 -0.9398)
			(stroke
				(width 0)
				(type default)
			)
			(fill no)
			(layer "B.Fab")
		)
		(pad "1" smd custom
			(at 0 -0.4445 90)
			(size 0.1397 0.1397)
			(layers "B.Cu" "B.Mask" "B.Paste")
			(net "SMCLK_PCH_SLOT2")
			(options
				(clearance outline)
				(anchor circle)
			)
			(primitives
				(gr_poly
					(pts
						(arc
							(start -0.1778 0.2794)
							(mid -0.249642 0.249642)
							(end -0.2794 0.1778)
						)
						(arc
							(start -0.2794 -0.1778)
							(mid -0.249642 -0.249642)
							(end -0.1778 -0.2794)
						)
						(arc
							(start 0.1778 -0.2794)
							(mid 0.249642 -0.249642)
							(end 0.2794 -0.1778)
						)
						(arc
							(start 0.2794 0.1778)
							(mid 0.249642 0.249642)
							(end 0.1778 0.2794)
						)
					)
					(width 0)
					(fill yes)
				)
			)
		)
		(pad "2" smd custom
			(at 0 0.4445 90)
			(size 0.1397 0.1397)
			(layers "B.Cu" "B.Mask" "B.Paste")
			(net "SMCLK_PCH_SLOT2_R")
			(options
				(clearance outline)
				(anchor circle)
			)
			(primitives
				(gr_poly
					(pts
						(arc
							(start -0.1778 0.2794)
							(mid -0.249642 0.249642)
							(end -0.2794 0.1778)
						)
						(arc
							(start -0.2794 -0.1778)
							(mid -0.249642 -0.249642)
							(end -0.1778 -0.2794)
						)
						(arc
							(start 0.1778 -0.2794)
							(mid 0.249642 -0.249642)
							(end 0.2794 -0.1778)
						)
						(arc
							(start 0.2794 0.1778)
							(mid 0.249642 0.249642)
							(end 0.1778 0.2794)
						)
					)
					(width 0)
					(fill yes)
				)
			)
		)
	)
	(footprint ""
		(layer "B.Cu")
		(at 38.8366 -1.5113 90)
		(property "Reference" "C24"
			(at 0 0 90)
			(layer "B.SilkS")
			(hide yes)
			(effects
				(font
					(size 1.27 1.27)
				)
				(justify mirror)
			)
		)
		(property "Value" "SCD1U16V2KX-3GP"
			(at -1.1811 -2.7051 90)
			(unlocked yes)
			(layer "B.Fab")
			(hide yes)
			(effects
				(font
					(size 1.016 1.016)
					(thickness 0.1524)
				)
				(justify mirror)
			)
		)
		(property "Device Type" "C402H22"
			(at -1.1811 -4.2291 90)
			(unlocked yes)
			(layer "B.Fab")
			(hide yes)
			(effects
				(font
					(size 1.016 1.016)
					(thickness 0.1524)
				)
				(justify mirror)
			)
		)
		(duplicate_pad_numbers_are_jumpers no)
		(fp_rect
			(start 0.4318 0.9525)
			(end -0.4318 -0.9525)
			(stroke
				(width 0)
				(type default)
			)
			(fill no)
			(layer "B.CrtYd")
		)
		(fp_rect
			(start 0.4318 0.9525)
			(end -0.4318 -0.9525)
			(stroke
				(width 0)
				(type default)
			)
			(fill no)
			(layer "B.Fab")
		)
		(pad "1" smd custom
			(at 0 -0.4445 270)
			(size 0.1524 0.1524)
			(layers "B.Cu" "B.Mask" "B.Paste")
			(net "P3V3")
			(options
				(clearance outline)
				(anchor circle)
			)
			(primitives
				(gr_poly
					(pts
						(arc
							(start 0.3048 0.2032)
							(mid 0.275042 0.275042)
							(end 0.2032 0.3048)
						)
						(arc
							(start -0.2032 0.3048)
							(mid -0.275042 0.275042)
							(end -0.3048 0.2032)
						)
						(arc
							(start -0.3048 -0.2032)
							(mid -0.275042 -0.275042)
							(end -0.2032 -0.3048)
						)
						(arc
							(start 0.2032 -0.3048)
							(mid 0.275042 -0.275042)
							(end 0.3048 -0.2032)
						)
					)
					(width 0)
					(fill yes)
				)
			)
		)
		(pad "2" smd custom
			(at 0 0.4445 270)
			(size 0.1524 0.1524)
			(layers "B.Cu" "B.Mask" "B.Paste")
			(net "GND")
			(options
				(clearance outline)
				(anchor circle)
			)
			(primitives
				(gr_poly
					(pts
						(arc
							(start 0.3048 0.2032)
							(mid 0.275042 0.275042)
							(end 0.2032 0.3048)
						)
						(arc
							(start -0.2032 0.3048)
							(mid -0.275042 0.275042)
							(end -0.3048 0.2032)
						)
						(arc
							(start -0.3048 -0.2032)
							(mid -0.275042 -0.275042)
							(end -0.2032 -0.3048)
						)
						(arc
							(start 0.2032 -0.3048)
							(mid 0.275042 -0.275042)
							(end 0.3048 -0.2032)
						)
					)
					(width 0)
					(fill yes)
				)
			)
		)
	)
	(footprint ""
		(layer "B.Cu")
		(at 121.9962 -26.3017)
		(property "Reference" "TP83"
			(at 0 0 0)
			(layer "B.SilkS")
			(hide yes)
			(effects
				(font
					(size 1.27 1.27)
				)
				(justify mirror)
			)
		)
		(property "Value" "TPAD24"
			(at 0 -1.6129 0)
			(unlocked yes)
			(layer "B.Fab")
			(hide yes)
			(effects
				(font
					(size 1.016 1.016)
					(thickness 0.1524)
				)
				(justify mirror)
			)
		)
		(property "Device Type" "TPAD24"
			(at 0 -3.1369 0)
			(unlocked yes)
			(layer "B.Fab")
			(hide yes)
			(effects
				(font
					(size 1.016 1.016)
					(thickness 0.1524)
				)
				(justify mirror)
			)
		)
		(duplicate_pad_numbers_are_jumpers no)
		(fp_poly
			(pts
				(arc
					(start 0.3048 0)
					(mid -0.3048 0)
					(end 0.3048 0)
				)
			)
			(stroke
				(width 0)
				(type default)
			)
			(fill no)
			(layer "B.CrtYd")
		)
		(fp_poly
			(pts
				(arc
					(start 0.6096 0)
					(mid -0.6096 0)
					(end 0.6096 0)
				)
			)
			(stroke
				(width 0)
				(type default)
			)
			(fill no)
			(layer "B.Fab")
		)
		(pad "1" smd circle
			(at 0 0 180)
			(size 0.6096 0.6096)
			(layers "B.Cu" "B.Mask" "B.Paste")
			(net "TP_USB_OCS_N3")
		)
	)
	(footprint ""
		(layer "B.Cu")
		(at 20.768818 -6.320028 -90)
		(property "Reference" "PC3"
			(at 0 0 90)
			(layer "B.SilkS")
			(hide yes)
			(effects
				(font
					(size 1.27 1.27)
				)
				(justify mirror)
			)
		)
		(property "Value" "SCD1U16V2KX-3GP"
			(at -1.1811 -2.7051 270)
			(unlocked yes)
			(layer "B.Fab")
			(hide yes)
			(effects
				(font
					(size 1.016 1.016)
					(thickness 0.1524)
				)
				(justify mirror)
			)
		)
		(property "Device Type" "C402H22"
			(at -1.1811 -4.2291 270)
			(unlocked yes)
			(layer "B.Fab")
			(hide yes)
			(effects
				(font
					(size 1.016 1.016)
					(thickness 0.1524)
				)
				(justify mirror)
			)
		)
		(duplicate_pad_numbers_are_jumpers no)
		(fp_rect
			(start 0.4318 0.9525)
			(end -0.4318 -0.9525)
			(stroke
				(width 0)
				(type default)
			)
			(fill no)
			(layer "B.CrtYd")
		)
		(fp_rect
			(start 0.4318 0.9525)
			(end -0.4318 -0.9525)
			(stroke
				(width 0)
				(type default)
			)
			(fill no)
			(layer "B.Fab")
		)
		(pad "1" smd custom
			(at 0 -0.4445 90)
			(size 0.1524 0.1524)
			(layers "B.Cu" "B.Mask" "B.Paste")
			(net "P3V3_VIN")
			(options
				(clearance outline)
				(anchor circle)
			)
			(primitives
				(gr_poly
					(pts
						(arc
							(start 0.3048 0.2032)
							(mid 0.275042 0.275042)
							(end 0.2032 0.3048)
						)
						(arc
							(start -0.2032 0.3048)
							(mid -0.275042 0.275042)
							(end -0.3048 0.2032)
						)
						(arc
							(start -0.3048 -0.2032)
							(mid -0.275042 -0.275042)
							(end -0.2032 -0.3048)
						)
						(arc
							(start 0.2032 -0.3048)
							(mid 0.275042 -0.275042)
							(end 0.3048 -0.2032)
						)
					)
					(width 0)
					(fill yes)
				)
			)
		)
		(pad "2" smd custom
			(at 0 0.4445 90)
			(size 0.1524 0.1524)
			(layers "B.Cu" "B.Mask" "B.Paste")
			(net "GND")
			(options
				(clearance outline)
				(anchor circle)
			)
			(primitives
				(gr_poly
					(pts
						(arc
							(start 0.3048 0.2032)
							(mid 0.275042 0.275042)
							(end 0.2032 0.3048)
						)
						(arc
							(start -0.2032 0.3048)
							(mid -0.275042 0.275042)
							(end -0.3048 0.2032)
						)
						(arc
							(start -0.3048 -0.2032)
							(mid -0.275042 -0.275042)
							(end -0.2032 -0.3048)
						)
						(arc
							(start 0.2032 -0.3048)
							(mid 0.275042 -0.275042)
							(end 0.3048 -0.2032)
						)
					)
					(width 0)
					(fill yes)
				)
			)
		)
	)
	(footprint ""
		(layer "B.Cu")
		(at 121.5644 -27.6098 90)
		(property "Reference" "CU4"
			(at 0 0 90)
			(layer "B.SilkS")
			(hide yes)
			(effects
				(font
					(size 1.27 1.27)
				)
				(justify mirror)
			)
		)
		(property "Value" "SC1U10V2KX-4-GP"
			(at -1.1811 -2.7051 90)
			(unlocked yes)
			(layer "B.Fab")
			(hide yes)
			(effects
				(font
					(size 1.016 1.016)
					(thickness 0.1524)
				)
				(justify mirror)
			)
		)
		(property "Device Type" "C402H22"
			(at -1.1811 -4.2291 90)
			(unlocked yes)
			(layer "B.Fab")
			(hide yes)
			(effects
				(font
					(size 1.016 1.016)
					(thickness 0.1524)
				)
				(justify mirror)
			)
		)
		(duplicate_pad_numbers_are_jumpers no)
		(fp_rect
			(start 0.4318 0.9525)
			(end -0.4318 -0.9525)
			(stroke
				(width 0)
				(type default)
			)
			(fill no)
			(layer "B.CrtYd")
		)
		(fp_rect
			(start 0.4318 0.9525)
			(end -0.4318 -0.9525)
			(stroke
				(width 0)
				(type default)
			)
			(fill no)
			(layer "B.Fab")
		)
		(pad "1" smd custom
			(at 0 -0.4445 270)
			(size 0.1524 0.1524)
			(layers "B.Cu" "B.Mask" "B.Paste")
			(net "P3V3_USB_HUB")
			(options
				(clearance outline)
				(anchor circle)
			)
			(primitives
				(gr_poly
					(pts
						(arc
							(start 0.3048 0.2032)
							(mid 0.275042 0.275042)
							(end 0.2032 0.3048)
						)
						(arc
							(start -0.2032 0.3048)
							(mid -0.275042 0.275042)
							(end -0.3048 0.2032)
						)
						(arc
							(start -0.3048 -0.2032)
							(mid -0.275042 -0.275042)
							(end -0.2032 -0.3048)
						)
						(arc
							(start 0.2032 -0.3048)
							(mid 0.275042 -0.275042)
							(end 0.3048 -0.2032)
						)
					)
					(width 0)
					(fill yes)
				)
			)
		)
		(pad "2" smd custom
			(at 0 0.4445 270)
			(size 0.1524 0.1524)
			(layers "B.Cu" "B.Mask" "B.Paste")
			(net "GND")
			(options
				(clearance outline)
				(anchor circle)
			)
			(primitives
				(gr_poly
					(pts
						(arc
							(start 0.3048 0.2032)
							(mid 0.275042 0.275042)
							(end 0.2032 0.3048)
						)
						(arc
							(start -0.2032 0.3048)
							(mid -0.275042 0.275042)
							(end -0.3048 0.2032)
						)
						(arc
							(start -0.3048 -0.2032)
							(mid -0.275042 -0.275042)
							(end -0.2032 -0.3048)
						)
						(arc
							(start 0.2032 -0.3048)
							(mid 0.275042 -0.275042)
							(end 0.3048 -0.2032)
						)
					)
					(width 0)
					(fill yes)
				)
			)
		)
	)
	(footprint ""
		(layer "B.Cu")
		(at 26.6446 -19.4056 180)
		(property "Reference" "R88"
			(at 0 0 0)
			(layer "B.SilkS")
			(hide yes)
			(effects
				(font
					(size 1.27 1.27)
				)
				(justify mirror)
			)
		)
		(property "Value" "0R2F-1-GP"
			(at -0.064008 -3.993896 180)
			(unlocked yes)
			(layer "B.Fab")
			(hide yes)
			(effects
				(font
					(size 1.016 1.016)
					(thickness 0.1524)
				)
				(justify mirror)
			)
		)
		(property "Device Type" "R402H16"
			(at -0.064008 -5.517896 180)
			(unlocked yes)
			(layer "B.Fab")
			(hide yes)
			(effects
				(font
					(size 1.016 1.016)
					(thickness 0.1524)
				)
				(justify mirror)
			)
		)
		(duplicate_pad_numbers_are_jumpers no)
		(fp_line
			(start 0.508 -0.9398)
			(end 0.508 0.9398)
			(stroke
				(width 0.1524)
				(type default)
			)
			(layer "B.SilkS")
		)
		(fp_line
			(start -0.508 -0.9398)
			(end 0.508 -0.9398)
			(stroke
				(width 0.1524)
				(type default)
			)
			(layer "B.SilkS")
		)
		(fp_rect
			(start 0.508 0.9398)
			(end -0.508 -0.9398)
			(stroke
				(width 0)
				(type default)
			)
			(fill no)
			(layer "B.CrtYd")
		)
		(fp_rect
			(start 0.508 0.9398)
			(end -0.508 -0.9398)
			(stroke
				(width 0)
				(type default)
			)
			(fill no)
			(layer "B.Fab")
		)
		(pad "1" smd custom
			(at 0 -0.4445)
			(size 0.1397 0.1397)
			(layers "B.Cu" "B.Mask" "B.Paste")
			(net "SMB_VMONITOR_SLOT3_MUX_SDA")
			(options
				(clearance outline)
				(anchor circle)
			)
			(primitives
				(gr_poly
					(pts
						(arc
							(start -0.1778 0.2794)
							(mid -0.249642 0.249642)
							(end -0.2794 0.1778)
						)
						(arc
							(start -0.2794 -0.1778)
							(mid -0.249642 -0.249642)
							(end -0.1778 -0.2794)
						)
						(arc
							(start 0.1778 -0.2794)
							(mid 0.249642 -0.249642)
							(end 0.2794 -0.1778)
						)
						(arc
							(start 0.2794 0.1778)
							(mid 0.249642 0.249642)
							(end 0.1778 0.2794)
						)
					)
					(width 0)
					(fill yes)
				)
			)
		)
		(pad "2" smd custom
			(at 0 0.4445)
			(size 0.1397 0.1397)
			(layers "B.Cu" "B.Mask" "B.Paste")
			(net "SMDAT_BMC_DEVICE")
			(options
				(clearance outline)
				(anchor circle)
			)
			(primitives
				(gr_poly
					(pts
						(arc
							(start -0.1778 0.2794)
							(mid -0.249642 0.249642)
							(end -0.2794 0.1778)
						)
						(arc
							(start -0.2794 -0.1778)
							(mid -0.249642 -0.249642)
							(end -0.1778 -0.2794)
						)
						(arc
							(start 0.1778 -0.2794)
							(mid 0.249642 -0.249642)
							(end 0.2794 -0.1778)
						)
						(arc
							(start 0.2794 0.1778)
							(mid 0.249642 0.249642)
							(end 0.1778 0.2794)
						)
					)
					(width 0)
					(fill yes)
				)
			)
		)
	)
	(footprint ""
		(layer "B.Cu")
		(at 33.9852 5.461 -90)
		(property "Reference" "R106"
			(at 0 0 90)
			(layer "B.SilkS")
			(hide yes)
			(effects
				(font
					(size 1.27 1.27)
				)
				(justify mirror)
			)
		)
		(property "Value" "10KR2F-2-GP"
			(at -0.064008 -3.993896 270)
			(unlocked yes)
			(layer "B.Fab")
			(hide yes)
			(effects
				(font
					(size 1.016 1.016)
					(thickness 0.1524)
				)
				(justify mirror)
			)
		)
		(property "Device Type" "R402H16"
			(at -0.064008 -5.517896 270)
			(unlocked yes)
			(layer "B.Fab")
			(hide yes)
			(effects
				(font
					(size 1.016 1.016)
					(thickness 0.1524)
				)
				(justify mirror)
			)
		)
		(duplicate_pad_numbers_are_jumpers no)
		(fp_line
			(start -0.508 -0.9398)
			(end 0.508 -0.9398)
			(stroke
				(width 0.1524)
				(type default)
			)
			(layer "B.SilkS")
		)
		(fp_line
			(start 0.508 -0.9398)
			(end 0.508 0.9398)
			(stroke
				(width 0.1524)
				(type default)
			)
			(layer "B.SilkS")
		)
		(fp_rect
			(start 0.508 0.9398)
			(end -0.508 -0.9398)
			(stroke
				(width 0)
				(type default)
			)
			(fill no)
			(layer "B.CrtYd")
		)
		(fp_rect
			(start 0.508 0.9398)
			(end -0.508 -0.9398)
			(stroke
				(width 0)
				(type default)
			)
			(fill no)
			(layer "B.Fab")
		)
		(pad "1" smd custom
			(at 0 -0.4445 90)
			(size 0.1397 0.1397)
			(layers "B.Cu" "B.Mask" "B.Paste")
			(net "SMB_P_REPEATER_EN")
			(options
				(clearance outline)
				(anchor circle)
			)
			(primitives
				(gr_poly
					(pts
						(arc
							(start -0.1778 0.2794)
							(mid -0.249642 0.249642)
							(end -0.2794 0.1778)
						)
						(arc
							(start -0.2794 -0.1778)
							(mid -0.249642 -0.249642)
							(end -0.1778 -0.2794)
						)
						(arc
							(start 0.1778 -0.2794)
							(mid 0.249642 -0.249642)
							(end 0.2794 -0.1778)
						)
						(arc
							(start 0.2794 0.1778)
							(mid 0.249642 0.249642)
							(end 0.1778 0.2794)
						)
					)
					(width 0)
					(fill yes)
				)
			)
		)
		(pad "2" smd custom
			(at 0 0.4445 90)
			(size 0.1397 0.1397)
			(layers "B.Cu" "B.Mask" "B.Paste")
			(net "P3V3_STBY")
			(options
				(clearance outline)
				(anchor circle)
			)
			(primitives
				(gr_poly
					(pts
						(arc
							(start -0.1778 0.2794)
							(mid -0.249642 0.249642)
							(end -0.2794 0.1778)
						)
						(arc
							(start -0.2794 -0.1778)
							(mid -0.249642 -0.249642)
							(end -0.1778 -0.2794)
						)
						(arc
							(start 0.1778 -0.2794)
							(mid 0.249642 -0.249642)
							(end 0.2794 -0.1778)
						)
						(arc
							(start 0.2794 0.1778)
							(mid 0.249642 0.249642)
							(end 0.1778 0.2794)
						)
					)
					(width 0)
					(fill yes)
				)
			)
		)
	)
	(footprint ""
		(layer "B.Cu")
		(at 132.2324 -4.8514 90)
		(property "Reference" "R72"
			(at 0 0 90)
			(layer "B.SilkS")
			(hide yes)
			(effects
				(font
					(size 1.27 1.27)
				)
				(justify mirror)
			)
		)
		(property "Value" "10KR2F-2-GP"
			(at -0.064008 -3.993896 90)
			(unlocked yes)
			(layer "B.Fab")
			(hide yes)
			(effects
				(font
					(size 1.016 1.016)
					(thickness 0.1524)
				)
				(justify mirror)
			)
		)
		(property "Device Type" "R402H16"
			(at -0.064008 -5.517896 90)
			(unlocked yes)
			(layer "B.Fab")
			(hide yes)
			(effects
				(font
					(size 1.016 1.016)
					(thickness 0.1524)
				)
				(justify mirror)
			)
		)
		(duplicate_pad_numbers_are_jumpers no)
		(fp_line
			(start 0.508 -0.9398)
			(end 0.508 0.9398)
			(stroke
				(width 0.1524)
				(type default)
			)
			(layer "B.SilkS")
		)
		(fp_line
			(start -0.508 -0.9398)
			(end 0.508 -0.9398)
			(stroke
				(width 0.1524)
				(type default)
			)
			(layer "B.SilkS")
		)
		(fp_rect
			(start 0.508 0.9398)
			(end -0.508 -0.9398)
			(stroke
				(width 0)
				(type default)
			)
			(fill no)
			(layer "B.CrtYd")
		)
		(fp_rect
			(start 0.508 0.9398)
			(end -0.508 -0.9398)
			(stroke
				(width 0)
				(type default)
			)
			(fill no)
			(layer "B.Fab")
		)
		(pad "1" smd custom
			(at 0 -0.4445 270)
			(size 0.1397 0.1397)
			(layers "B.Cu" "B.Mask" "B.Paste")
			(net "SMB_PCH_DEVICE_ALERT_N")
			(options
				(clearance outline)
				(anchor circle)
			)
			(primitives
				(gr_poly
					(pts
						(arc
							(start -0.1778 0.2794)
							(mid -0.249642 0.249642)
							(end -0.2794 0.1778)
						)
						(arc
							(start -0.2794 -0.1778)
							(mid -0.249642 -0.249642)
							(end -0.1778 -0.2794)
						)
						(arc
							(start 0.1778 -0.2794)
							(mid 0.249642 -0.249642)
							(end 0.2794 -0.1778)
						)
						(arc
							(start 0.2794 0.1778)
							(mid 0.249642 0.249642)
							(end 0.1778 0.2794)
						)
					)
					(width 0)
					(fill yes)
				)
			)
		)
		(pad "2" smd custom
			(at 0 0.4445 270)
			(size 0.1397 0.1397)
			(layers "B.Cu" "B.Mask" "B.Paste")
			(net "P3V3_STBY")
			(options
				(clearance outline)
				(anchor circle)
			)
			(primitives
				(gr_poly
					(pts
						(arc
							(start -0.1778 0.2794)
							(mid -0.249642 0.249642)
							(end -0.2794 0.1778)
						)
						(arc
							(start -0.2794 -0.1778)
							(mid -0.249642 -0.249642)
							(end -0.1778 -0.2794)
						)
						(arc
							(start 0.1778 -0.2794)
							(mid 0.249642 -0.249642)
							(end 0.2794 -0.1778)
						)
						(arc
							(start 0.2794 0.1778)
							(mid 0.249642 0.249642)
							(end 0.1778 0.2794)
						)
					)
					(width 0)
					(fill yes)
				)
			)
		)
	)
	(footprint ""
		(layer "B.Cu")
		(at 23.1267 -19.9898)
		(property "Reference" "R105"
			(at 0 0 0)
			(layer "B.SilkS")
			(hide yes)
			(effects
				(font
					(size 1.27 1.27)
				)
				(justify mirror)
			)
		)
		(property "Value" "0R2F-1-GP"
			(at -0.064008 -3.993896 0)
			(unlocked yes)
			(layer "B.Fab")
			(hide yes)
			(effects
				(font
					(size 1.016 1.016)
					(thickness 0.1524)
				)
				(justify mirror)
			)
		)
		(property "Device Type" "R402H16"
			(at -0.064008 -5.517896 0)
			(unlocked yes)
			(layer "B.Fab")
			(hide yes)
			(effects
				(font
					(size 1.016 1.016)
					(thickness 0.1524)
				)
				(justify mirror)
			)
		)
		(duplicate_pad_numbers_are_jumpers no)
		(fp_line
			(start -0.508 -0.9398)
			(end 0.508 -0.9398)
			(stroke
				(width 0.1524)
				(type default)
			)
			(layer "B.SilkS")
		)
		(fp_line
			(start 0.508 -0.9398)
			(end 0.508 0.9398)
			(stroke
				(width 0.1524)
				(type default)
			)
			(layer "B.SilkS")
		)
		(fp_rect
			(start 0.508 0.9398)
			(end -0.508 -0.9398)
			(stroke
				(width 0)
				(type default)
			)
			(fill no)
			(layer "B.CrtYd")
		)
		(fp_rect
			(start 0.508 0.9398)
			(end -0.508 -0.9398)
			(stroke
				(width 0)
				(type default)
			)
			(fill no)
			(layer "B.Fab")
		)
		(pad "1" smd custom
			(at 0 -0.4445 180)
			(size 0.1397 0.1397)
			(layers "B.Cu" "B.Mask" "B.Paste")
			(net "SMB_VMONITOR_ATX_MUX_SCL")
			(options
				(clearance outline)
				(anchor circle)
			)
			(primitives
				(gr_poly
					(pts
						(arc
							(start -0.1778 0.2794)
							(mid -0.249642 0.249642)
							(end -0.2794 0.1778)
						)
						(arc
							(start -0.2794 -0.1778)
							(mid -0.249642 -0.249642)
							(end -0.1778 -0.2794)
						)
						(arc
							(start 0.1778 -0.2794)
							(mid 0.249642 -0.249642)
							(end 0.2794 -0.1778)
						)
						(arc
							(start 0.2794 0.1778)
							(mid 0.249642 0.249642)
							(end 0.1778 0.2794)
						)
					)
					(width 0)
					(fill yes)
				)
			)
		)
		(pad "2" smd custom
			(at 0 0.4445 180)
			(size 0.1397 0.1397)
			(layers "B.Cu" "B.Mask" "B.Paste")
			(net "SMCLK_BMC_DEVICE")
			(options
				(clearance outline)
				(anchor circle)
			)
			(primitives
				(gr_poly
					(pts
						(arc
							(start -0.1778 0.2794)
							(mid -0.249642 0.249642)
							(end -0.2794 0.1778)
						)
						(arc
							(start -0.2794 -0.1778)
							(mid -0.249642 -0.249642)
							(end -0.1778 -0.2794)
						)
						(arc
							(start 0.1778 -0.2794)
							(mid 0.249642 -0.249642)
							(end 0.2794 -0.1778)
						)
						(arc
							(start 0.2794 0.1778)
							(mid 0.249642 0.249642)
							(end 0.1778 0.2794)
						)
					)
					(width 0)
					(fill yes)
				)
			)
		)
	)
	(footprint ""
		(layer "B.Cu")
		(at 128.4478 -10.4394 90)
		(property "Reference" "R22"
			(at 0 0 90)
			(layer "B.SilkS")
			(hide yes)
			(effects
				(font
					(size 1.27 1.27)
				)
				(justify mirror)
			)
		)
		(property "Value" "4K7R2F-GP"
			(at -0.064008 -3.993896 90)
			(unlocked yes)
			(layer "B.Fab")
			(hide yes)
			(effects
				(font
					(size 1.016 1.016)
					(thickness 0.1524)
				)
				(justify mirror)
			)
		)
		(property "Device Type" "R402H16"
			(at -0.064008 -5.517896 90)
			(unlocked yes)
			(layer "B.Fab")
			(hide yes)
			(effects
				(font
					(size 1.016 1.016)
					(thickness 0.1524)
				)
				(justify mirror)
			)
		)
		(duplicate_pad_numbers_are_jumpers no)
		(fp_line
			(start 0.508 -0.9398)
			(end 0.508 0.9398)
			(stroke
				(width 0.1524)
				(type default)
			)
			(layer "B.SilkS")
		)
		(fp_line
			(start -0.508 -0.9398)
			(end 0.508 -0.9398)
			(stroke
				(width 0.1524)
				(type default)
			)
			(layer "B.SilkS")
		)
		(fp_rect
			(start 0.508 0.9398)
			(end -0.508 -0.9398)
			(stroke
				(width 0)
				(type default)
			)
			(fill no)
			(layer "B.CrtYd")
		)
		(fp_rect
			(start 0.508 0.9398)
			(end -0.508 -0.9398)
			(stroke
				(width 0)
				(type default)
			)
			(fill no)
			(layer "B.Fab")
		)
		(pad "1" smd custom
			(at 0 -0.4445 270)
			(size 0.1397 0.1397)
			(layers "B.Cu" "B.Mask" "B.Paste")
			(net "P3V3_STBY")
			(options
				(clearance outline)
				(anchor circle)
			)
			(primitives
				(gr_poly
					(pts
						(arc
							(start -0.1778 0.2794)
							(mid -0.249642 0.249642)
							(end -0.2794 0.1778)
						)
						(arc
							(start -0.2794 -0.1778)
							(mid -0.249642 -0.249642)
							(end -0.1778 -0.2794)
						)
						(arc
							(start 0.1778 -0.2794)
							(mid 0.249642 -0.249642)
							(end 0.2794 -0.1778)
						)
						(arc
							(start 0.2794 0.1778)
							(mid 0.249642 0.249642)
							(end 0.1778 0.2794)
						)
					)
					(width 0)
					(fill yes)
				)
			)
		)
		(pad "2" smd custom
			(at 0 0.4445 270)
			(size 0.1397 0.1397)
			(layers "B.Cu" "B.Mask" "B.Paste")
			(net "SMDAT_PCH_SLOT3")
			(options
				(clearance outline)
				(anchor circle)
			)
			(primitives
				(gr_poly
					(pts
						(arc
							(start -0.1778 0.2794)
							(mid -0.249642 0.249642)
							(end -0.2794 0.1778)
						)
						(arc
							(start -0.2794 -0.1778)
							(mid -0.249642 -0.249642)
							(end -0.1778 -0.2794)
						)
						(arc
							(start 0.1778 -0.2794)
							(mid 0.249642 -0.249642)
							(end 0.2794 -0.1778)
						)
						(arc
							(start 0.2794 0.1778)
							(mid 0.249642 0.249642)
							(end 0.1778 0.2794)
						)
					)
					(width 0)
					(fill yes)
				)
			)
		)
	)
	(footprint ""
		(layer "B.Cu")
		(at 120.3579 -26.4795)
		(property "Reference" "TP81"
			(at 0 0 0)
			(layer "B.SilkS")
			(hide yes)
			(effects
				(font
					(size 1.27 1.27)
				)
				(justify mirror)
			)
		)
		(property "Value" "TPAD24"
			(at 0 -1.6129 0)
			(unlocked yes)
			(layer "B.Fab")
			(hide yes)
			(effects
				(font
					(size 1.016 1.016)
					(thickness 0.1524)
				)
				(justify mirror)
			)
		)
		(property "Device Type" "TPAD24"
			(at 0 -3.1369 0)
			(unlocked yes)
			(layer "B.Fab")
			(hide yes)
			(effects
				(font
					(size 1.016 1.016)
					(thickness 0.1524)
				)
				(justify mirror)
			)
		)
		(duplicate_pad_numbers_are_jumpers no)
		(fp_poly
			(pts
				(arc
					(start 0.3048 0)
					(mid -0.3048 0)
					(end 0.3048 0)
				)
			)
			(stroke
				(width 0)
				(type default)
			)
			(fill no)
			(layer "B.CrtYd")
		)
		(fp_poly
			(pts
				(arc
					(start 0.6096 0)
					(mid -0.6096 0)
					(end 0.6096 0)
				)
			)
			(stroke
				(width 0)
				(type default)
			)
			(fill no)
			(layer "B.Fab")
		)
		(pad "1" smd circle
			(at 0 0 180)
			(size 0.6096 0.6096)
			(layers "B.Cu" "B.Mask" "B.Paste")
			(net "TP_USB_OCS_N2")
		)
	)
	(footprint ""
		(layer "B.Cu")
		(at 20.955 -27.4066)
		(property "Reference" "C50"
			(at 0 0 0)
			(layer "B.SilkS")
			(hide yes)
			(effects
				(font
					(size 1.27 1.27)
				)
				(justify mirror)
			)
		)
		(property "Value" "SCD1U16V2KX-3GP"
			(at -1.1811 -2.7051 0)
			(unlocked yes)
			(layer "B.Fab")
			(hide yes)
			(effects
				(font
					(size 1.016 1.016)
					(thickness 0.1524)
				)
				(justify mirror)
			)
		)
		(property "Device Type" "C402H22"
			(at -1.1811 -4.2291 0)
			(unlocked yes)
			(layer "B.Fab")
			(hide yes)
			(effects
				(font
					(size 1.016 1.016)
					(thickness 0.1524)
				)
				(justify mirror)
			)
		)
		(duplicate_pad_numbers_are_jumpers no)
		(fp_rect
			(start 0.4318 0.9525)
			(end -0.4318 -0.9525)
			(stroke
				(width 0)
				(type default)
			)
			(fill no)
			(layer "B.CrtYd")
		)
		(fp_rect
			(start 0.4318 0.9525)
			(end -0.4318 -0.9525)
			(stroke
				(width 0)
				(type default)
			)
			(fill no)
			(layer "B.Fab")
		)
		(pad "1" smd custom
			(at 0 -0.4445 180)
			(size 0.1524 0.1524)
			(layers "B.Cu" "B.Mask" "B.Paste")
			(net "P3V3_STBY")
			(options
				(clearance outline)
				(anchor circle)
			)
			(primitives
				(gr_poly
					(pts
						(arc
							(start 0.3048 0.2032)
							(mid 0.275042 0.275042)
							(end 0.2032 0.3048)
						)
						(arc
							(start -0.2032 0.3048)
							(mid -0.275042 0.275042)
							(end -0.3048 0.2032)
						)
						(arc
							(start -0.3048 -0.2032)
							(mid -0.275042 -0.275042)
							(end -0.2032 -0.3048)
						)
						(arc
							(start 0.2032 -0.3048)
							(mid 0.275042 -0.275042)
							(end 0.3048 -0.2032)
						)
					)
					(width 0)
					(fill yes)
				)
			)
		)
		(pad "2" smd custom
			(at 0 0.4445 180)
			(size 0.1524 0.1524)
			(layers "B.Cu" "B.Mask" "B.Paste")
			(net "GND")
			(options
				(clearance outline)
				(anchor circle)
			)
			(primitives
				(gr_poly
					(pts
						(arc
							(start 0.3048 0.2032)
							(mid 0.275042 0.275042)
							(end 0.2032 0.3048)
						)
						(arc
							(start -0.2032 0.3048)
							(mid -0.275042 0.275042)
							(end -0.3048 0.2032)
						)
						(arc
							(start -0.3048 -0.2032)
							(mid -0.275042 -0.275042)
							(end -0.2032 -0.3048)
						)
						(arc
							(start 0.2032 -0.3048)
							(mid 0.275042 -0.275042)
							(end 0.3048 -0.2032)
						)
					)
					(width 0)
					(fill yes)
				)
			)
		)
	)
	(footprint ""
		(layer "B.Cu")
		(at 22.352 -9.779 90)
		(property "Reference" "PU1"
			(at 0 0 90)
			(layer "B.SilkS")
			(hide yes)
			(effects
				(font
					(size 1.27 1.27)
				)
				(justify mirror)
			)
		)
		(property "Value" "MPQ8634AGLE-Z-GP"
			(at 4.2799 1.5748 90)
			(unlocked yes)
			(layer "B.Fab")
			(hide yes)
			(effects
				(font
					(size 1.016 1.016)
					(thickness 0.1524)
				)
				(justify mirror)
			)
		)
		(property "Device Type" "QFN21M4030-1H40"
			(at 4.2799 0.0508 90)
			(unlocked yes)
			(layer "B.Fab")
			(hide yes)
			(effects
				(font
					(size 1.016 1.016)
					(thickness 0.1524)
				)
				(justify mirror)
			)
		)
		(duplicate_pad_numbers_are_jumpers no)
		(fp_line
			(start 0 -2.777998)
			(end 0 -2.269998)
			(stroke
				(width 0.1524)
				(type default)
			)
			(layer "B.SilkS")
		)
		(fp_line
			(start 3.0226 -2.5146)
			(end 3.0226 -1.2446)
			(stroke
				(width 0.1524)
				(type default)
			)
			(layer "B.SilkS")
		)
		(fp_line
			(start 1.7526 -2.5146)
			(end 3.0226 -2.5146)
			(stroke
				(width 0.1524)
				(type default)
			)
			(layer "B.SilkS")
		)
		(fp_line
			(start 3.526282 -0.299974)
			(end 2.764282 -0.299974)
			(stroke
				(width 0.1524)
				(type default)
			)
			(layer "B.SilkS")
		)
		(fp_line
			(start -2.764282 0.299974)
			(end -3.526282 0.299974)
			(stroke
				(width 0.1524)
				(type default)
			)
			(layer "B.SilkS")
		)
		(fp_line
			(start 3.0226 1.2446)
			(end 3.0226 2.5146)
			(stroke
				(width 0.1524)
				(type default)
			)
			(layer "B.SilkS")
		)
		(fp_line
			(start -3.0226 1.2446)
			(end -3.0226 2.5146)
			(stroke
				(width 0.1524)
				(type default)
			)
			(layer "B.SilkS")
		)
		(fp_line
			(start 3.0226 2.5146)
			(end 1.7526 2.5146)
			(stroke
				(width 0.1524)
				(type default)
			)
			(layer "B.SilkS")
		)
		(fp_line
			(start -3.0226 2.5146)
			(end -1.7526 2.5146)
			(stroke
				(width 0.1524)
				(type default)
			)
			(layer "B.SilkS")
		)
		(fp_line
			(start 0 2.777998)
			(end 0 2.269998)
			(stroke
				(width 0.1524)
				(type default)
			)
			(layer "B.SilkS")
		)
		(fp_poly
			(pts
				(xy -1.7526 -2.5146) (xy -3.0226 -2.5146) (xy -3.0226 -1.2446)
			)
			(stroke
				(width 0)
				(type default)
			)
			(fill yes)
			(layer "B.SilkS")
		)
		(fp_rect
			(start 1.9939 1.4986)
			(end -1.9939 -1.4986)
			(stroke
				(width 0)
				(type default)
			)
			(fill no)
			(layer "B.CrtYd")
		)
		(fp_poly
			(pts
				(xy 3.0226 2.5146) (xy 3.0226 -2.5146) (xy -3.0226 -2.5146) (xy -3.0226 -0.00635) (xy -1.9939 -0.00635)
				(xy -1.9939 -1.4986) (xy 1.9939 -1.4986) (xy 1.9939 1.4986) (xy -1.9939 1.4986) (xy -1.9939 0.00635)
				(xy -3.0226 0.00635) (xy -3.0226 2.5146)
			)
			(stroke
				(width 0)
				(type default)
			)
			(fill no)
			(layer "B.CrtYd")
		)
		(fp_rect
			(start 3.0226 2.5146)
			(end -3.0226 -2.5146)
			(stroke
				(width 0)
				(type default)
			)
			(fill no)
			(layer "B.Fab")
		)
		(pad "1" smd rect
			(at -1.700022 -1.380998 270)
			(size 0.3048 1.3208)
			(drill
				(offset 0 -0.0254)
			)
			(layers "B.Cu" "B.Mask" "B.Paste")
			(net "P3V3_BST")
		)
		(pad "2" smd rect
			(at -1.199896 -1.380998 270)
			(size 0.2032 1.27)
			(layers "B.Cu" "B.Mask" "B.Paste")
			(net "AGND_P3V3")
		)
		(pad "3" smd rect
			(at -0.8001 -1.380998 270)
			(size 0.2032 1.27)
			(layers "B.Cu" "B.Mask" "B.Paste")
			(net "P3V3_CS")
		)
		(pad "4" smd rect
			(at -0.40005 -1.380998 270)
			(size 0.2032 1.27)
			(layers "B.Cu" "B.Mask" "B.Paste")
			(net "P3V3_MODE")
		)
		(pad "5" smd rect
			(at 0 -1.380998 270)
			(size 0.2032 1.27)
			(layers "B.Cu" "B.Mask" "B.Paste")
			(net "P3V3_TRK")
		)
		(pad "6" smd rect
			(at 0.40005 -1.380998 270)
			(size 0.2032 1.27)
			(layers "B.Cu" "B.Mask" "B.Paste")
			(net "GND")
		)
		(pad "7" smd rect
			(at 0.8001 -1.380998 270)
			(size 0.2032 1.27)
			(layers "B.Cu" "B.Mask" "B.Paste")
			(net "P3V3_FB")
		)
		(pad "8" smd rect
			(at 1.199896 -1.380998 270)
			(size 0.2032 1.27)
			(layers "B.Cu" "B.Mask" "B.Paste")
			(net "P3V3_EN")
		)
		(pad "9" smd rect
			(at 1.700022 -1.380998 270)
			(size 0.3048 1.27)
			(layers "B.Cu" "B.Mask" "B.Paste")
			(net "P3V3_PG")
		)
		(pad "10" smd rect
			(at 1.380236 -0.299974 270)
			(size 2.2606 0.3556)
			(layers "B.Cu" "B.Mask" "B.Paste")
			(net "P3V3_VIN")
		)
		(pad "11" smd custom
			(at 1.700022 1.380998 270)
			(size 0.3175 0.3175)
			(layers "B.Cu" "B.Mask" "B.Paste")
			(net "GND")
			(options
				(clearance outline)
				(anchor circle)
			)
			(primitives
				(gr_poly
					(pts
						(xy -1.272032 0.034798) (xy -1.272032 -0.635) (xy -1.576832 -0.635) (xy -1.576832 0.635) (xy 1.577086 0.635)
						(xy 1.577086 -0.635) (xy 1.373886 -0.635) (xy 1.373886 0.034798) (xy 1.17729 0.034798) (xy 1.17729 -0.635)
						(xy 0.97409 -0.635) (xy 0.97409 0.034798) (xy 0.77724 0.034798) (xy 0.77724 -0.635) (xy 0.57404 -0.635)
						(xy 0.57404 0.034798) (xy 0.37719 0.034798) (xy 0.37719 -0.635) (xy 0.17399 -0.635) (xy 0.17399 0.034798)
						(xy -0.02286 0.034798) (xy -0.02286 -0.635) (xy -0.22606 -0.635) (xy -0.22606 0.034798) (xy -0.42291 0.034798)
						(xy -0.42291 -0.635) (xy -0.62611 -0.635) (xy -0.62611 0.034798) (xy -0.822706 0.034798) (xy -0.822706 -0.635)
						(xy -1.025906 -0.635) (xy -1.025906 0.034798)
					)
					(width 0)
					(fill yes)
				)
			)
		)
		(pad "12" smd rect
			(at 1.199896 1.380998 270)
			(size 0.0254 0.0254)
			(layers "B.Cu" "B.Mask" "B.Paste")
			(net "GND")
		)
		(pad "13" smd rect
			(at 0.8001 1.380998 270)
			(size 0.0254 0.0254)
			(layers "B.Cu" "B.Mask" "B.Paste")
			(net "GND")
		)
		(pad "14" smd rect
			(at 0.40005 1.380998 270)
			(size 0.0254 0.0254)
			(layers "B.Cu" "B.Mask" "B.Paste")
			(net "GND")
		)
		(pad "15" smd rect
			(at 0 1.380998 270)
			(size 0.0254 0.0254)
			(layers "B.Cu" "B.Mask" "B.Paste")
			(net "GND")
		)
		(pad "16" smd rect
			(at -0.40005 1.380998 270)
			(size 0.0254 0.0254)
			(layers "B.Cu" "B.Mask" "B.Paste")
			(net "GND")
		)
		(pad "17" smd rect
			(at -0.8001 1.380998 270)
			(size 0.0254 0.0254)
			(layers "B.Cu" "B.Mask" "B.Paste")
			(net "GND")
		)
		(pad "18" smd rect
			(at -1.199896 1.380998 270)
			(size 0.0254 0.0254)
			(layers "B.Cu" "B.Mask" "B.Paste")
			(net "GND")
		)
		(pad "19" smd rect
			(at -1.700022 1.380998 270)
			(size 0.3048 1.27)
			(layers "B.Cu" "B.Mask" "B.Paste")
			(net "P3V3_VCC")
		)
		(pad "20" smd rect
			(at -1.380236 0.299974 270)
			(size 2.2606 0.3556)
			(layers "B.Cu" "B.Mask" "B.Paste")
			(net "P3V3_SW")
		)
		(pad "21" smd rect
			(at -1.380236 -0.299974 270)
			(size 2.2606 0.3556)
			(layers "B.Cu" "B.Mask" "B.Paste")
			(net "P3V3_VIN")
		)
	)
	(footprint ""
		(layer "B.Cu")
		(at 16.2687 -12.4587 -90)
		(property "Reference" "PC10"
			(at 0 0 90)
			(layer "B.SilkS")
			(hide yes)
			(effects
				(font
					(size 1.27 1.27)
				)
				(justify mirror)
			)
		)
		(property "Value" "SC270P50V2KX-1GP"
			(at -1.1811 -2.7051 270)
			(unlocked yes)
			(layer "B.Fab")
			(hide yes)
			(effects
				(font
					(size 1.016 1.016)
					(thickness 0.1524)
				)
				(justify mirror)
			)
		)
		(property "Device Type" "C402H22"
			(at -1.1811 -4.2291 270)
			(unlocked yes)
			(layer "B.Fab")
			(hide yes)
			(effects
				(font
					(size 1.016 1.016)
					(thickness 0.1524)
				)
				(justify mirror)
			)
		)
		(duplicate_pad_numbers_are_jumpers no)
		(fp_rect
			(start 0.4318 0.9525)
			(end -0.4318 -0.9525)
			(stroke
				(width 0)
				(type default)
			)
			(fill no)
			(layer "B.CrtYd")
		)
		(fp_rect
			(start 0.4318 0.9525)
			(end -0.4318 -0.9525)
			(stroke
				(width 0)
				(type default)
			)
			(fill no)
			(layer "B.Fab")
		)
		(pad "1" smd custom
			(at 0 -0.4445 90)
			(size 0.1524 0.1524)
			(layers "B.Cu" "B.Mask" "B.Paste")
			(net "P3V3_FB")
			(options
				(clearance outline)
				(anchor circle)
			)
			(primitives
				(gr_poly
					(pts
						(arc
							(start 0.3048 0.2032)
							(mid 0.275042 0.275042)
							(end 0.2032 0.3048)
						)
						(arc
							(start -0.2032 0.3048)
							(mid -0.275042 0.275042)
							(end -0.3048 0.2032)
						)
						(arc
							(start -0.3048 -0.2032)
							(mid -0.275042 -0.275042)
							(end -0.2032 -0.3048)
						)
						(arc
							(start 0.2032 -0.3048)
							(mid 0.275042 -0.275042)
							(end 0.3048 -0.2032)
						)
					)
					(width 0)
					(fill yes)
				)
			)
		)
		(pad "2" smd custom
			(at 0 0.4445 90)
			(size 0.1524 0.1524)
			(layers "B.Cu" "B.Mask" "B.Paste")
			(net "P3V3_VFB_R")
			(options
				(clearance outline)
				(anchor circle)
			)
			(primitives
				(gr_poly
					(pts
						(arc
							(start 0.3048 0.2032)
							(mid 0.275042 0.275042)
							(end 0.2032 0.3048)
						)
						(arc
							(start -0.2032 0.3048)
							(mid -0.275042 0.275042)
							(end -0.3048 0.2032)
						)
						(arc
							(start -0.3048 -0.2032)
							(mid -0.275042 -0.275042)
							(end -0.2032 -0.3048)
						)
						(arc
							(start 0.2032 -0.3048)
							(mid 0.275042 -0.275042)
							(end 0.3048 -0.2032)
						)
					)
					(width 0)
					(fill yes)
				)
			)
		)
	)
	(footprint ""
		(layer "B.Cu")
		(at 23.1394 -13.7922 90)
		(property "Reference" "PC2"
			(at 0 0 90)
			(layer "B.SilkS")
			(hide yes)
			(effects
				(font
					(size 1.27 1.27)
				)
				(justify mirror)
			)
		)
		(property "Value" "SC22U16V5MX-4-GP"
			(at 0.0762 -6.1214 90)
			(unlocked yes)
			(layer "B.Fab")
			(hide yes)
			(effects
				(font
					(size 1.016 1.016)
					(thickness 0.1524)
				)
				(justify mirror)
			)
		)
		(property "Device Type" "C805H58"
			(at 0.0762 -8.1534 90)
			(unlocked yes)
			(layer "B.Fab")
			(hide yes)
			(effects
				(font
					(size 1.016 1.016)
					(thickness 0.1524)
				)
				(justify mirror)
			)
		)
		(duplicate_pad_numbers_are_jumpers no)
		(fp_line
			(start -0.635 0)
			(end 0.635 0)
			(stroke
				(width 0.508)
				(type default)
			)
			(layer "B.SilkS")
		)
		(fp_rect
			(start 0.9652 1.778)
			(end -0.9652 -1.778)
			(stroke
				(width 0)
				(type default)
			)
			(fill no)
			(layer "B.CrtYd")
		)
		(fp_poly
			(pts
				(xy 0.9652 -1.778) (xy -0.9652 -1.778) (xy -0.9652 1.778) (xy 0.9652 1.778)
			)
			(stroke
				(width 0)
				(type default)
			)
			(fill no)
			(layer "B.Fab")
		)
		(pad "1" smd rect
			(at 0 -0.9652 270)
			(size 1.397 1.143)
			(layers "B.Cu" "B.Mask" "B.Paste")
			(net "P3V3_VIN")
		)
		(pad "2" smd rect
			(at 0 0.9652 270)
			(size 1.397 1.143)
			(layers "B.Cu" "B.Mask" "B.Paste")
			(net "GND")
		)
	)
	(footprint ""
		(layer "B.Cu")
		(at 121.2596 -28.7782)
		(property "Reference" "TP82"
			(at 0 0 0)
			(layer "B.SilkS")
			(hide yes)
			(effects
				(font
					(size 1.27 1.27)
				)
				(justify mirror)
			)
		)
		(property "Value" "TPAD24"
			(at 0 -1.6129 0)
			(unlocked yes)
			(layer "B.Fab")
			(hide yes)
			(effects
				(font
					(size 1.016 1.016)
					(thickness 0.1524)
				)
				(justify mirror)
			)
		)
		(property "Device Type" "TPAD24"
			(at 0 -3.1369 0)
			(unlocked yes)
			(layer "B.Fab")
			(hide yes)
			(effects
				(font
					(size 1.016 1.016)
					(thickness 0.1524)
				)
				(justify mirror)
			)
		)
		(duplicate_pad_numbers_are_jumpers no)
		(fp_poly
			(pts
				(arc
					(start 0.3048 0)
					(mid -0.3048 0)
					(end 0.3048 0)
				)
			)
			(stroke
				(width 0)
				(type default)
			)
			(fill no)
			(layer "B.CrtYd")
		)
		(fp_poly
			(pts
				(arc
					(start 0.6096 0)
					(mid -0.6096 0)
					(end 0.6096 0)
				)
			)
			(stroke
				(width 0)
				(type default)
			)
			(fill no)
			(layer "B.Fab")
		)
		(pad "1" smd circle
			(at 0 0 180)
			(size 0.6096 0.6096)
			(layers "B.Cu" "B.Mask" "B.Paste")
			(net "TP_USB_OCS_N1")
		)
	)
	(footprint ""
		(layer "B.Cu")
		(at 125.7554 -25.146 90)
		(property "Reference" "RU20"
			(at 0 0 90)
			(layer "B.SilkS")
			(hide yes)
			(effects
				(font
					(size 1.27 1.27)
				)
				(justify mirror)
			)
		)
		(property "Value" "100KR2F-L1-GP"
			(at -0.064008 -3.993896 90)
			(unlocked yes)
			(layer "B.Fab")
			(hide yes)
			(effects
				(font
					(size 1.016 1.016)
					(thickness 0.1524)
				)
				(justify mirror)
			)
		)
		(property "Device Type" "R402H16"
			(at -0.064008 -5.517896 90)
			(unlocked yes)
			(layer "B.Fab")
			(hide yes)
			(effects
				(font
					(size 1.016 1.016)
					(thickness 0.1524)
				)
				(justify mirror)
			)
		)
		(duplicate_pad_numbers_are_jumpers no)
		(fp_line
			(start 0.508 -0.9398)
			(end 0.508 0.9398)
			(stroke
				(width 0.1524)
				(type default)
			)
			(layer "B.SilkS")
		)
		(fp_line
			(start -0.508 -0.9398)
			(end 0.508 -0.9398)
			(stroke
				(width 0.1524)
				(type default)
			)
			(layer "B.SilkS")
		)
		(fp_rect
			(start 0.508 0.9398)
			(end -0.508 -0.9398)
			(stroke
				(width 0)
				(type default)
			)
			(fill no)
			(layer "B.CrtYd")
		)
		(fp_rect
			(start 0.508 0.9398)
			(end -0.508 -0.9398)
			(stroke
				(width 0)
				(type default)
			)
			(fill no)
			(layer "B.Fab")
		)
		(pad "1" smd custom
			(at 0 -0.4445 270)
			(size 0.1397 0.1397)
			(layers "B.Cu" "B.Mask" "B.Paste")
			(net "P3V3_USB_HUB")
			(options
				(clearance outline)
				(anchor circle)
			)
			(primitives
				(gr_poly
					(pts
						(arc
							(start -0.1778 0.2794)
							(mid -0.249642 0.249642)
							(end -0.2794 0.1778)
						)
						(arc
							(start -0.2794 -0.1778)
							(mid -0.249642 -0.249642)
							(end -0.1778 -0.2794)
						)
						(arc
							(start 0.1778 -0.2794)
							(mid 0.249642 -0.249642)
							(end 0.2794 -0.1778)
						)
						(arc
							(start 0.2794 0.1778)
							(mid 0.249642 0.249642)
							(end 0.1778 0.2794)
						)
					)
					(width 0)
					(fill yes)
				)
			)
		)
		(pad "2" smd custom
			(at 0 0.4445 270)
			(size 0.1397 0.1397)
			(layers "B.Cu" "B.Mask" "B.Paste")
			(net "CFG_SEL1")
			(options
				(clearance outline)
				(anchor circle)
			)
			(primitives
				(gr_poly
					(pts
						(arc
							(start -0.1778 0.2794)
							(mid -0.249642 0.249642)
							(end -0.2794 0.1778)
						)
						(arc
							(start -0.2794 -0.1778)
							(mid -0.249642 -0.249642)
							(end -0.1778 -0.2794)
						)
						(arc
							(start 0.1778 -0.2794)
							(mid 0.249642 -0.249642)
							(end 0.2794 -0.1778)
						)
						(arc
							(start 0.2794 0.1778)
							(mid 0.249642 0.249642)
							(end 0.1778 0.2794)
						)
					)
					(width 0)
					(fill yes)
				)
			)
		)
	)
	(footprint ""
		(layer "B.Cu")
		(at 25.1206 -31.9532 180)
		(property "Reference" "C89"
			(at 0 0 0)
			(layer "B.SilkS")
			(hide yes)
			(effects
				(font
					(size 1.27 1.27)
				)
				(justify mirror)
			)
		)
		(property "Value" "SC22U16V5MX-4-GP"
			(at 0.0762 -6.1214 180)
			(unlocked yes)
			(layer "B.Fab")
			(hide yes)
			(effects
				(font
					(size 1.016 1.016)
					(thickness 0.1524)
				)
				(justify mirror)
			)
		)
		(property "Device Type" "C805H58"
			(at 0.0762 -8.1534 180)
			(unlocked yes)
			(layer "B.Fab")
			(hide yes)
			(effects
				(font
					(size 1.016 1.016)
					(thickness 0.1524)
				)
				(justify mirror)
			)
		)
		(duplicate_pad_numbers_are_jumpers no)
		(fp_line
			(start -0.635 0)
			(end 0.635 0)
			(stroke
				(width 0.508)
				(type default)
			)
			(layer "B.SilkS")
		)
		(fp_rect
			(start 0.9652 1.778)
			(end -0.9652 -1.778)
			(stroke
				(width 0)
				(type default)
			)
			(fill no)
			(layer "B.CrtYd")
		)
		(fp_poly
			(pts
				(xy 0.9652 -1.778) (xy -0.9652 -1.778) (xy -0.9652 1.778) (xy 0.9652 1.778)
			)
			(stroke
				(width 0)
				(type default)
			)
			(fill no)
			(layer "B.Fab")
		)
		(pad "1" smd rect
			(at 0 -0.9652)
			(size 1.397 1.143)
			(layers "B.Cu" "B.Mask" "B.Paste")
			(net "P12V_ATX")
		)
		(pad "2" smd rect
			(at 0 0.9652)
			(size 1.397 1.143)
			(layers "B.Cu" "B.Mask" "B.Paste")
			(net "GND")
		)
	)
	(footprint ""
		(layer "B.Cu")
		(at 105.0544 3.3782 180)
		(property "Reference" "R9"
			(at 0 0 0)
			(layer "B.SilkS")
			(hide yes)
			(effects
				(font
					(size 1.27 1.27)
				)
				(justify mirror)
			)
		)
		(property "Value" "10KR2F-2-GP"
			(at -0.064008 -3.993896 180)
			(unlocked yes)
			(layer "B.Fab")
			(hide yes)
			(effects
				(font
					(size 1.016 1.016)
					(thickness 0.1524)
				)
				(justify mirror)
			)
		)
		(property "Device Type" "R402H16"
			(at -0.064008 -5.517896 180)
			(unlocked yes)
			(layer "B.Fab")
			(hide yes)
			(effects
				(font
					(size 1.016 1.016)
					(thickness 0.1524)
				)
				(justify mirror)
			)
		)
		(duplicate_pad_numbers_are_jumpers no)
		(fp_line
			(start 0.508 -0.9398)
			(end 0.508 0.9398)
			(stroke
				(width 0.1524)
				(type default)
			)
			(layer "B.SilkS")
		)
		(fp_line
			(start -0.508 -0.9398)
			(end 0.508 -0.9398)
			(stroke
				(width 0.1524)
				(type default)
			)
			(layer "B.SilkS")
		)
		(fp_rect
			(start 0.508 0.9398)
			(end -0.508 -0.9398)
			(stroke
				(width 0)
				(type default)
			)
			(fill no)
			(layer "B.CrtYd")
		)
		(fp_rect
			(start 0.508 0.9398)
			(end -0.508 -0.9398)
			(stroke
				(width 0)
				(type default)
			)
			(fill no)
			(layer "B.Fab")
		)
		(pad "1" smd custom
			(at 0 -0.4445)
			(size 0.1397 0.1397)
			(layers "B.Cu" "B.Mask" "B.Paste")
			(net "IRQ_OOB_MGMT_RISER_ALERT_N")
			(options
				(clearance outline)
				(anchor circle)
			)
			(primitives
				(gr_poly
					(pts
						(arc
							(start -0.1778 0.2794)
							(mid -0.249642 0.249642)
							(end -0.2794 0.1778)
						)
						(arc
							(start -0.2794 -0.1778)
							(mid -0.249642 -0.249642)
							(end -0.1778 -0.2794)
						)
						(arc
							(start 0.1778 -0.2794)
							(mid 0.249642 -0.249642)
							(end 0.2794 -0.1778)
						)
						(arc
							(start 0.2794 0.1778)
							(mid 0.249642 0.249642)
							(end 0.1778 0.2794)
						)
					)
					(width 0)
					(fill yes)
				)
			)
		)
		(pad "2" smd custom
			(at 0 0.4445)
			(size 0.1397 0.1397)
			(layers "B.Cu" "B.Mask" "B.Paste")
			(net "P3V3_STBY")
			(options
				(clearance outline)
				(anchor circle)
			)
			(primitives
				(gr_poly
					(pts
						(arc
							(start -0.1778 0.2794)
							(mid -0.249642 0.249642)
							(end -0.2794 0.1778)
						)
						(arc
							(start -0.2794 -0.1778)
							(mid -0.249642 -0.249642)
							(end -0.1778 -0.2794)
						)
						(arc
							(start 0.1778 -0.2794)
							(mid 0.249642 -0.249642)
							(end 0.2794 -0.1778)
						)
						(arc
							(start 0.2794 0.1778)
							(mid 0.249642 0.249642)
							(end 0.1778 0.2794)
						)
					)
					(width 0)
					(fill yes)
				)
			)
		)
	)
	(footprint ""
		(layer "B.Cu")
		(at 19.0373 -13.9192 180)
		(property "Reference" "PC13"
			(at 0 0 0)
			(layer "B.SilkS")
			(hide yes)
			(effects
				(font
					(size 1.27 1.27)
				)
				(justify mirror)
			)
		)
		(property "Value" "SC2D2U10V3KX-2GP-U1"
			(at 0 -2.8194 180)
			(unlocked yes)
			(layer "B.Fab")
			(hide yes)
			(effects
				(font
					(size 1.016 1.016)
					(thickness 0.1524)
				)
				(justify mirror)
			)
		)
		(property "Device Type" "C603H40"
			(at 0 -4.3434 180)
			(unlocked yes)
			(layer "B.Fab")
			(hide yes)
			(effects
				(font
					(size 1.016 1.016)
					(thickness 0.1524)
				)
				(justify mirror)
			)
		)
		(duplicate_pad_numbers_are_jumpers no)
		(fp_line
			(start -0.508 0)
			(end 0.508 0)
			(stroke
				(width 0.2032)
				(type default)
			)
			(layer "B.SilkS")
		)
		(fp_rect
			(start 0.5842 1.3335)
			(end -0.5842 -1.3335)
			(stroke
				(width 0)
				(type default)
			)
			(fill no)
			(layer "B.CrtYd")
		)
		(fp_rect
			(start 0.5842 1.3335)
			(end -0.5842 -1.3335)
			(stroke
				(width 0)
				(type default)
			)
			(fill no)
			(layer "B.Fab")
		)
		(pad "1" smd custom
			(at 0 -0.762)
			(size 0.2159 0.2159)
			(layers "B.Cu" "B.Mask" "B.Paste")
			(net "P3V3_EN")
			(options
				(clearance outline)
				(anchor circle)
			)
			(primitives
				(gr_poly
					(pts
						(arc
							(start -0.3302 0.4318)
							(mid -0.402042 0.402042)
							(end -0.4318 0.3302)
						)
						(arc
							(start -0.4318 -0.3302)
							(mid -0.402042 -0.402042)
							(end -0.3302 -0.4318)
						)
						(arc
							(start 0.3302 -0.4318)
							(mid 0.402042 -0.402042)
							(end 0.4318 -0.3302)
						)
						(arc
							(start 0.4318 0.3302)
							(mid 0.402042 0.402042)
							(end 0.3302 0.4318)
						)
					)
					(width 0)
					(fill yes)
				)
			)
		)
		(pad "2" smd custom
			(at 0 0.762)
			(size 0.2159 0.2159)
			(layers "B.Cu" "B.Mask" "B.Paste")
			(net "GND")
			(options
				(clearance outline)
				(anchor circle)
			)
			(primitives
				(gr_poly
					(pts
						(arc
							(start -0.3302 0.4318)
							(mid -0.402042 0.402042)
							(end -0.4318 0.3302)
						)
						(arc
							(start -0.4318 -0.3302)
							(mid -0.402042 -0.402042)
							(end -0.3302 -0.4318)
						)
						(arc
							(start 0.3302 -0.4318)
							(mid 0.402042 -0.402042)
							(end 0.4318 -0.3302)
						)
						(arc
							(start 0.4318 0.3302)
							(mid 0.402042 0.402042)
							(end 0.3302 0.4318)
						)
					)
					(width 0)
					(fill yes)
				)
			)
		)
	)
	(footprint ""
		(layer "B.Cu")
		(at 25.6032 -7.6708 180)
		(property "Reference" "PC12"
			(at 0 0 0)
			(layer "B.SilkS")
			(hide yes)
			(effects
				(font
					(size 1.27 1.27)
				)
				(justify mirror)
			)
		)
		(property "Value" "SC2D2U10V3KX-2GP-U1"
			(at 0 -2.8194 180)
			(unlocked yes)
			(layer "B.Fab")
			(hide yes)
			(effects
				(font
					(size 1.016 1.016)
					(thickness 0.1524)
				)
				(justify mirror)
			)
		)
		(property "Device Type" "C603H40"
			(at 0 -4.3434 180)
			(unlocked yes)
			(layer "B.Fab")
			(hide yes)
			(effects
				(font
					(size 1.016 1.016)
					(thickness 0.1524)
				)
				(justify mirror)
			)
		)
		(duplicate_pad_numbers_are_jumpers no)
		(fp_line
			(start -0.508 0)
			(end 0.508 0)
			(stroke
				(width 0.2032)
				(type default)
			)
			(layer "B.SilkS")
		)
		(fp_rect
			(start 0.5842 1.3335)
			(end -0.5842 -1.3335)
			(stroke
				(width 0)
				(type default)
			)
			(fill no)
			(layer "B.CrtYd")
		)
		(fp_rect
			(start 0.5842 1.3335)
			(end -0.5842 -1.3335)
			(stroke
				(width 0)
				(type default)
			)
			(fill no)
			(layer "B.Fab")
		)
		(pad "1" smd custom
			(at 0 -0.762)
			(size 0.2159 0.2159)
			(layers "B.Cu" "B.Mask" "B.Paste")
			(net "P3V3_VCC")
			(options
				(clearance outline)
				(anchor circle)
			)
			(primitives
				(gr_poly
					(pts
						(arc
							(start -0.3302 0.4318)
							(mid -0.402042 0.402042)
							(end -0.4318 0.3302)
						)
						(arc
							(start -0.4318 -0.3302)
							(mid -0.402042 -0.402042)
							(end -0.3302 -0.4318)
						)
						(arc
							(start 0.3302 -0.4318)
							(mid 0.402042 -0.402042)
							(end 0.4318 -0.3302)
						)
						(arc
							(start 0.4318 0.3302)
							(mid 0.402042 0.402042)
							(end 0.3302 0.4318)
						)
					)
					(width 0)
					(fill yes)
				)
			)
		)
		(pad "2" smd custom
			(at 0 0.762)
			(size 0.2159 0.2159)
			(layers "B.Cu" "B.Mask" "B.Paste")
			(net "GND")
			(options
				(clearance outline)
				(anchor circle)
			)
			(primitives
				(gr_poly
					(pts
						(arc
							(start -0.3302 0.4318)
							(mid -0.402042 0.402042)
							(end -0.4318 0.3302)
						)
						(arc
							(start -0.4318 -0.3302)
							(mid -0.402042 -0.402042)
							(end -0.3302 -0.4318)
						)
						(arc
							(start 0.3302 -0.4318)
							(mid 0.402042 -0.402042)
							(end 0.4318 -0.3302)
						)
						(arc
							(start 0.4318 0.3302)
							(mid 0.402042 0.402042)
							(end 0.3302 0.4318)
						)
					)
					(width 0)
					(fill yes)
				)
			)
		)
	)
	(footprint ""
		(layer "B.Cu")
		(at 41.7195 3.0226 -90)
		(property "Reference" "R51"
			(at 0 0 90)
			(layer "B.SilkS")
			(hide yes)
			(effects
				(font
					(size 1.27 1.27)
				)
				(justify mirror)
			)
		)
		(property "Value" "0R2F-1-GP"
			(at -0.064008 -3.993896 270)
			(unlocked yes)
			(layer "B.Fab")
			(hide yes)
			(effects
				(font
					(size 1.016 1.016)
					(thickness 0.1524)
				)
				(justify mirror)
			)
		)
		(property "Device Type" "R402H16"
			(at -0.064008 -5.517896 270)
			(unlocked yes)
			(layer "B.Fab")
			(hide yes)
			(effects
				(font
					(size 1.016 1.016)
					(thickness 0.1524)
				)
				(justify mirror)
			)
		)
		(duplicate_pad_numbers_are_jumpers no)
		(fp_line
			(start -0.508 -0.9398)
			(end 0.508 -0.9398)
			(stroke
				(width 0.1524)
				(type default)
			)
			(layer "B.SilkS")
		)
		(fp_line
			(start 0.508 -0.9398)
			(end 0.508 0.9398)
			(stroke
				(width 0.1524)
				(type default)
			)
			(layer "B.SilkS")
		)
		(fp_rect
			(start 0.508 0.9398)
			(end -0.508 -0.9398)
			(stroke
				(width 0)
				(type default)
			)
			(fill no)
			(layer "B.CrtYd")
		)
		(fp_rect
			(start 0.508 0.9398)
			(end -0.508 -0.9398)
			(stroke
				(width 0)
				(type default)
			)
			(fill no)
			(layer "B.Fab")
		)
		(pad "1" smd custom
			(at 0 -0.4445 90)
			(size 0.1397 0.1397)
			(layers "B.Cu" "B.Mask" "B.Paste")
			(net "SMDAT_PCH_R")
			(options
				(clearance outline)
				(anchor circle)
			)
			(primitives
				(gr_poly
					(pts
						(arc
							(start -0.1778 0.2794)
							(mid -0.249642 0.249642)
							(end -0.2794 0.1778)
						)
						(arc
							(start -0.2794 -0.1778)
							(mid -0.249642 -0.249642)
							(end -0.1778 -0.2794)
						)
						(arc
							(start 0.1778 -0.2794)
							(mid 0.249642 -0.249642)
							(end 0.2794 -0.1778)
						)
						(arc
							(start 0.2794 0.1778)
							(mid 0.249642 0.249642)
							(end 0.1778 0.2794)
						)
					)
					(width 0)
					(fill yes)
				)
			)
		)
		(pad "2" smd custom
			(at 0 0.4445 90)
			(size 0.1397 0.1397)
			(layers "B.Cu" "B.Mask" "B.Paste")
			(net "SMB_HOST_STBY_LVC3_SDA_R5")
			(options
				(clearance outline)
				(anchor circle)
			)
			(primitives
				(gr_poly
					(pts
						(arc
							(start -0.1778 0.2794)
							(mid -0.249642 0.249642)
							(end -0.2794 0.1778)
						)
						(arc
							(start -0.2794 -0.1778)
							(mid -0.249642 -0.249642)
							(end -0.1778 -0.2794)
						)
						(arc
							(start 0.1778 -0.2794)
							(mid 0.249642 -0.249642)
							(end 0.2794 -0.1778)
						)
						(arc
							(start 0.2794 0.1778)
							(mid 0.249642 0.249642)
							(end 0.1778 0.2794)
						)
					)
					(width 0)
					(fill yes)
				)
			)
		)
	)
	(footprint ""
		(layer "B.Cu")
		(at 37.9603 0.3048 -90)
		(property "Reference" "R202"
			(at 0 0 90)
			(layer "B.SilkS")
			(hide yes)
			(effects
				(font
					(size 1.27 1.27)
				)
				(justify mirror)
			)
		)
		(property "Value" "4K7R2F-GP"
			(at -0.064008 -3.993896 270)
			(unlocked yes)
			(layer "B.Fab")
			(hide yes)
			(effects
				(font
					(size 1.016 1.016)
					(thickness 0.1524)
				)
				(justify mirror)
			)
		)
		(property "Device Type" "R402H16"
			(at -0.064008 -5.517896 270)
			(unlocked yes)
			(layer "B.Fab")
			(hide yes)
			(effects
				(font
					(size 1.016 1.016)
					(thickness 0.1524)
				)
				(justify mirror)
			)
		)
		(duplicate_pad_numbers_are_jumpers no)
		(fp_line
			(start -0.508 -0.9398)
			(end 0.508 -0.9398)
			(stroke
				(width 0.1524)
				(type default)
			)
			(layer "B.SilkS")
		)
		(fp_line
			(start 0.508 -0.9398)
			(end 0.508 0.9398)
			(stroke
				(width 0.1524)
				(type default)
			)
			(layer "B.SilkS")
		)
		(fp_rect
			(start 0.508 0.9398)
			(end -0.508 -0.9398)
			(stroke
				(width 0)
				(type default)
			)
			(fill no)
			(layer "B.CrtYd")
		)
		(fp_rect
			(start 0.508 0.9398)
			(end -0.508 -0.9398)
			(stroke
				(width 0)
				(type default)
			)
			(fill no)
			(layer "B.Fab")
		)
		(pad "1" smd custom
			(at 0 -0.4445 90)
			(size 0.1397 0.1397)
			(layers "B.Cu" "B.Mask" "B.Paste")
			(net "P3V3_STBY")
			(options
				(clearance outline)
				(anchor circle)
			)
			(primitives
				(gr_poly
					(pts
						(arc
							(start -0.1778 0.2794)
							(mid -0.249642 0.249642)
							(end -0.2794 0.1778)
						)
						(arc
							(start -0.2794 -0.1778)
							(mid -0.249642 -0.249642)
							(end -0.1778 -0.2794)
						)
						(arc
							(start 0.1778 -0.2794)
							(mid 0.249642 -0.249642)
							(end 0.2794 -0.1778)
						)
						(arc
							(start 0.2794 0.1778)
							(mid 0.249642 0.249642)
							(end 0.1778 0.2794)
						)
					)
					(width 0)
					(fill yes)
				)
			)
		)
		(pad "2" smd custom
			(at 0 0.4445 90)
			(size 0.1397 0.1397)
			(layers "B.Cu" "B.Mask" "B.Paste")
			(net "SMDAT_PCH_R")
			(options
				(clearance outline)
				(anchor circle)
			)
			(primitives
				(gr_poly
					(pts
						(arc
							(start -0.1778 0.2794)
							(mid -0.249642 0.249642)
							(end -0.2794 0.1778)
						)
						(arc
							(start -0.2794 -0.1778)
							(mid -0.249642 -0.249642)
							(end -0.1778 -0.2794)
						)
						(arc
							(start 0.1778 -0.2794)
							(mid 0.249642 -0.249642)
							(end 0.2794 -0.1778)
						)
						(arc
							(start 0.2794 0.1778)
							(mid 0.249642 0.249642)
							(end 0.1778 0.2794)
						)
					)
					(width 0)
					(fill yes)
				)
			)
		)
	)
	(footprint ""
		(layer "B.Cu")
		(at 35.9791 0.2921 90)
		(property "Reference" "R201"
			(at 0 0 90)
			(layer "B.SilkS")
			(hide yes)
			(effects
				(font
					(size 1.27 1.27)
				)
				(justify mirror)
			)
		)
		(property "Value" "4K7R2F-GP"
			(at -0.064008 -3.993896 90)
			(unlocked yes)
			(layer "B.Fab")
			(hide yes)
			(effects
				(font
					(size 1.016 1.016)
					(thickness 0.1524)
				)
				(justify mirror)
			)
		)
		(property "Device Type" "R402H16"
			(at -0.064008 -5.517896 90)
			(unlocked yes)
			(layer "B.Fab")
			(hide yes)
			(effects
				(font
					(size 1.016 1.016)
					(thickness 0.1524)
				)
				(justify mirror)
			)
		)
		(duplicate_pad_numbers_are_jumpers no)
		(fp_line
			(start 0.508 -0.9398)
			(end 0.508 0.9398)
			(stroke
				(width 0.1524)
				(type default)
			)
			(layer "B.SilkS")
		)
		(fp_line
			(start -0.508 -0.9398)
			(end 0.508 -0.9398)
			(stroke
				(width 0.1524)
				(type default)
			)
			(layer "B.SilkS")
		)
		(fp_rect
			(start 0.508 0.9398)
			(end -0.508 -0.9398)
			(stroke
				(width 0)
				(type default)
			)
			(fill no)
			(layer "B.CrtYd")
		)
		(fp_rect
			(start 0.508 0.9398)
			(end -0.508 -0.9398)
			(stroke
				(width 0)
				(type default)
			)
			(fill no)
			(layer "B.Fab")
		)
		(pad "1" smd custom
			(at 0 -0.4445 270)
			(size 0.1397 0.1397)
			(layers "B.Cu" "B.Mask" "B.Paste")
			(net "P3V3_STBY")
			(options
				(clearance outline)
				(anchor circle)
			)
			(primitives
				(gr_poly
					(pts
						(arc
							(start -0.1778 0.2794)
							(mid -0.249642 0.249642)
							(end -0.2794 0.1778)
						)
						(arc
							(start -0.2794 -0.1778)
							(mid -0.249642 -0.249642)
							(end -0.1778 -0.2794)
						)
						(arc
							(start 0.1778 -0.2794)
							(mid 0.249642 -0.249642)
							(end 0.2794 -0.1778)
						)
						(arc
							(start 0.2794 0.1778)
							(mid 0.249642 0.249642)
							(end 0.1778 0.2794)
						)
					)
					(width 0)
					(fill yes)
				)
			)
		)
		(pad "2" smd custom
			(at 0 0.4445 270)
			(size 0.1397 0.1397)
			(layers "B.Cu" "B.Mask" "B.Paste")
			(net "SMCLK_PCH_R")
			(options
				(clearance outline)
				(anchor circle)
			)
			(primitives
				(gr_poly
					(pts
						(arc
							(start -0.1778 0.2794)
							(mid -0.249642 0.249642)
							(end -0.2794 0.1778)
						)
						(arc
							(start -0.2794 -0.1778)
							(mid -0.249642 -0.249642)
							(end -0.1778 -0.2794)
						)
						(arc
							(start 0.1778 -0.2794)
							(mid 0.249642 -0.249642)
							(end 0.2794 -0.1778)
						)
						(arc
							(start 0.2794 0.1778)
							(mid 0.249642 0.249642)
							(end 0.1778 0.2794)
						)
					)
					(width 0)
					(fill yes)
				)
			)
		)
	)
	(footprint ""
		(layer "B.Cu")
		(at 16.8148 -10.0076 180)
		(property "Reference" "PC15"
			(at 0 0 0)
			(layer "B.SilkS")
			(hide yes)
			(effects
				(font
					(size 1.27 1.27)
				)
				(justify mirror)
			)
		)
		(property "Value" "SCD1U16V2KX-3GP"
			(at -1.1811 -2.7051 180)
			(unlocked yes)
			(layer "B.Fab")
			(hide yes)
			(effects
				(font
					(size 1.016 1.016)
					(thickness 0.1524)
				)
				(justify mirror)
			)
		)
		(property "Device Type" "C402H22"
			(at -1.1811 -4.2291 180)
			(unlocked yes)
			(layer "B.Fab")
			(hide yes)
			(effects
				(font
					(size 1.016 1.016)
					(thickness 0.1524)
				)
				(justify mirror)
			)
		)
		(duplicate_pad_numbers_are_jumpers no)
		(fp_rect
			(start 0.4318 0.9525)
			(end -0.4318 -0.9525)
			(stroke
				(width 0)
				(type default)
			)
			(fill no)
			(layer "B.CrtYd")
		)
		(fp_rect
			(start 0.4318 0.9525)
			(end -0.4318 -0.9525)
			(stroke
				(width 0)
				(type default)
			)
			(fill no)
			(layer "B.Fab")
		)
		(pad "1" smd custom
			(at 0 -0.4445)
			(size 0.1524 0.1524)
			(layers "B.Cu" "B.Mask" "B.Paste")
			(net "P3V3_TRK")
			(options
				(clearance outline)
				(anchor circle)
			)
			(primitives
				(gr_poly
					(pts
						(arc
							(start 0.3048 0.2032)
							(mid 0.275042 0.275042)
							(end 0.2032 0.3048)
						)
						(arc
							(start -0.2032 0.3048)
							(mid -0.275042 0.275042)
							(end -0.3048 0.2032)
						)
						(arc
							(start -0.3048 -0.2032)
							(mid -0.275042 -0.275042)
							(end -0.2032 -0.3048)
						)
						(arc
							(start 0.2032 -0.3048)
							(mid 0.275042 -0.275042)
							(end 0.3048 -0.2032)
						)
					)
					(width 0)
					(fill yes)
				)
			)
		)
		(pad "2" smd custom
			(at 0 0.4445)
			(size 0.1524 0.1524)
			(layers "B.Cu" "B.Mask" "B.Paste")
			(net "GND")
			(options
				(clearance outline)
				(anchor circle)
			)
			(primitives
				(gr_poly
					(pts
						(arc
							(start 0.3048 0.2032)
							(mid 0.275042 0.275042)
							(end 0.2032 0.3048)
						)
						(arc
							(start -0.2032 0.3048)
							(mid -0.275042 0.275042)
							(end -0.3048 0.2032)
						)
						(arc
							(start -0.3048 -0.2032)
							(mid -0.275042 -0.275042)
							(end -0.2032 -0.3048)
						)
						(arc
							(start 0.2032 -0.3048)
							(mid 0.275042 -0.275042)
							(end 0.3048 -0.2032)
						)
					)
					(width 0)
					(fill yes)
				)
			)
		)
	)
	(footprint ""
		(layer "B.Cu")
		(at 42.7482 -1.5367 180)
		(property "Reference" "R27"
			(at 0 0 0)
			(layer "B.SilkS")
			(hide yes)
			(effects
				(font
					(size 1.27 1.27)
				)
				(justify mirror)
			)
		)
		(property "Value" "0R2F-1-GP"
			(at -0.064008 -3.993896 180)
			(unlocked yes)
			(layer "B.Fab")
			(hide yes)
			(effects
				(font
					(size 1.016 1.016)
					(thickness 0.1524)
				)
				(justify mirror)
			)
		)
		(property "Device Type" "R402H16"
			(at -0.064008 -5.517896 180)
			(unlocked yes)
			(layer "B.Fab")
			(hide yes)
			(effects
				(font
					(size 1.016 1.016)
					(thickness 0.1524)
				)
				(justify mirror)
			)
		)
		(duplicate_pad_numbers_are_jumpers no)
		(fp_line
			(start 0.508 -0.9398)
			(end 0.508 0.9398)
			(stroke
				(width 0.1524)
				(type default)
			)
			(layer "B.SilkS")
		)
		(fp_line
			(start -0.508 -0.9398)
			(end 0.508 -0.9398)
			(stroke
				(width 0.1524)
				(type default)
			)
			(layer "B.SilkS")
		)
		(fp_rect
			(start 0.508 0.9398)
			(end -0.508 -0.9398)
			(stroke
				(width 0)
				(type default)
			)
			(fill no)
			(layer "B.CrtYd")
		)
		(fp_rect
			(start 0.508 0.9398)
			(end -0.508 -0.9398)
			(stroke
				(width 0)
				(type default)
			)
			(fill no)
			(layer "B.Fab")
		)
		(pad "1" smd custom
			(at 0 -0.4445)
			(size 0.1397 0.1397)
			(layers "B.Cu" "B.Mask" "B.Paste")
			(net "SMCLK_BMC_SLOT2")
			(options
				(clearance outline)
				(anchor circle)
			)
			(primitives
				(gr_poly
					(pts
						(arc
							(start -0.1778 0.2794)
							(mid -0.249642 0.249642)
							(end -0.2794 0.1778)
						)
						(arc
							(start -0.2794 -0.1778)
							(mid -0.249642 -0.249642)
							(end -0.1778 -0.2794)
						)
						(arc
							(start 0.1778 -0.2794)
							(mid 0.249642 -0.249642)
							(end 0.2794 -0.1778)
						)
						(arc
							(start 0.2794 0.1778)
							(mid 0.249642 0.249642)
							(end 0.1778 0.2794)
						)
					)
					(width 0)
					(fill yes)
				)
			)
		)
		(pad "2" smd custom
			(at 0 0.4445)
			(size 0.1397 0.1397)
			(layers "B.Cu" "B.Mask" "B.Paste")
			(net "SMCLK_BMC_SLOT2_R")
			(options
				(clearance outline)
				(anchor circle)
			)
			(primitives
				(gr_poly
					(pts
						(arc
							(start -0.1778 0.2794)
							(mid -0.249642 0.249642)
							(end -0.2794 0.1778)
						)
						(arc
							(start -0.2794 -0.1778)
							(mid -0.249642 -0.249642)
							(end -0.1778 -0.2794)
						)
						(arc
							(start 0.1778 -0.2794)
							(mid 0.249642 -0.249642)
							(end 0.2794 -0.1778)
						)
						(arc
							(start 0.2794 0.1778)
							(mid 0.249642 0.249642)
							(end 0.1778 0.2794)
						)
					)
					(width 0)
					(fill yes)
				)
			)
		)
	)
	(footprint ""
		(layer "B.Cu")
		(at 44.4119 -2.3622 -90)
		(property "Reference" "R32"
			(at 0 0 90)
			(layer "B.SilkS")
			(hide yes)
			(effects
				(font
					(size 1.27 1.27)
				)
				(justify mirror)
			)
		)
		(property "Value" "0R2F-1-GP"
			(at -0.064008 -3.993896 270)
			(unlocked yes)
			(layer "B.Fab")
			(hide yes)
			(effects
				(font
					(size 1.016 1.016)
					(thickness 0.1524)
				)
				(justify mirror)
			)
		)
		(property "Device Type" "R402H16"
			(at -0.064008 -5.517896 270)
			(unlocked yes)
			(layer "B.Fab")
			(hide yes)
			(effects
				(font
					(size 1.016 1.016)
					(thickness 0.1524)
				)
				(justify mirror)
			)
		)
		(duplicate_pad_numbers_are_jumpers no)
		(fp_line
			(start -0.508 -0.9398)
			(end 0.508 -0.9398)
			(stroke
				(width 0.1524)
				(type default)
			)
			(layer "B.SilkS")
		)
		(fp_line
			(start 0.508 -0.9398)
			(end 0.508 0.9398)
			(stroke
				(width 0.1524)
				(type default)
			)
			(layer "B.SilkS")
		)
		(fp_rect
			(start 0.508 0.9398)
			(end -0.508 -0.9398)
			(stroke
				(width 0)
				(type default)
			)
			(fill no)
			(layer "B.CrtYd")
		)
		(fp_rect
			(start 0.508 0.9398)
			(end -0.508 -0.9398)
			(stroke
				(width 0)
				(type default)
			)
			(fill no)
			(layer "B.Fab")
		)
		(pad "1" smd custom
			(at 0 -0.4445 90)
			(size 0.1397 0.1397)
			(layers "B.Cu" "B.Mask" "B.Paste")
			(net "SMDAT_PCH_SLOT2")
			(options
				(clearance outline)
				(anchor circle)
			)
			(primitives
				(gr_poly
					(pts
						(arc
							(start -0.1778 0.2794)
							(mid -0.249642 0.249642)
							(end -0.2794 0.1778)
						)
						(arc
							(start -0.2794 -0.1778)
							(mid -0.249642 -0.249642)
							(end -0.1778 -0.2794)
						)
						(arc
							(start 0.1778 -0.2794)
							(mid 0.249642 -0.249642)
							(end 0.2794 -0.1778)
						)
						(arc
							(start 0.2794 0.1778)
							(mid 0.249642 0.249642)
							(end 0.1778 0.2794)
						)
					)
					(width 0)
					(fill yes)
				)
			)
		)
		(pad "2" smd custom
			(at 0 0.4445 90)
			(size 0.1397 0.1397)
			(layers "B.Cu" "B.Mask" "B.Paste")
			(net "SMDAT_PCH_SLOT2_R")
			(options
				(clearance outline)
				(anchor circle)
			)
			(primitives
				(gr_poly
					(pts
						(arc
							(start -0.1778 0.2794)
							(mid -0.249642 0.249642)
							(end -0.2794 0.1778)
						)
						(arc
							(start -0.2794 -0.1778)
							(mid -0.249642 -0.249642)
							(end -0.1778 -0.2794)
						)
						(arc
							(start 0.1778 -0.2794)
							(mid 0.249642 -0.249642)
							(end 0.2794 -0.1778)
						)
						(arc
							(start 0.2794 0.1778)
							(mid 0.249642 0.249642)
							(end 0.1778 0.2794)
						)
					)
					(width 0)
					(fill yes)
				)
			)
		)
	)
	(footprint ""
		(layer "B.Cu")
		(at 123.4186 -30.7594)
		(property "Reference" "CU2"
			(at 0 0 0)
			(layer "B.SilkS")
			(hide yes)
			(effects
				(font
					(size 1.27 1.27)
				)
				(justify mirror)
			)
		)
		(property "Value" "SC1U6D3V3KX-2GP"
			(at 0 -2.8194 0)
			(unlocked yes)
			(layer "B.Fab")
			(hide yes)
			(effects
				(font
					(size 1.016 1.016)
					(thickness 0.1524)
				)
				(justify mirror)
			)
		)
		(property "Device Type" "C603H36"
			(at 0 -4.3434 0)
			(unlocked yes)
			(layer "B.Fab")
			(hide yes)
			(effects
				(font
					(size 1.016 1.016)
					(thickness 0.1524)
				)
				(justify mirror)
			)
		)
		(duplicate_pad_numbers_are_jumpers no)
		(fp_line
			(start -0.508 0)
			(end 0.508 0)
			(stroke
				(width 0.2032)
				(type default)
			)
			(layer "B.SilkS")
		)
		(fp_rect
			(start 0.5842 1.3335)
			(end -0.5842 -1.3335)
			(stroke
				(width 0)
				(type default)
			)
			(fill no)
			(layer "B.CrtYd")
		)
		(fp_rect
			(start 0.5842 1.3335)
			(end -0.5842 -1.3335)
			(stroke
				(width 0)
				(type default)
			)
			(fill no)
			(layer "B.Fab")
		)
		(pad "1" smd custom
			(at 0 -0.762 180)
			(size 0.2159 0.2159)
			(layers "B.Cu" "B.Mask" "B.Paste")
			(net "P3V3_USB_HUB")
			(options
				(clearance outline)
				(anchor circle)
			)
			(primitives
				(gr_poly
					(pts
						(arc
							(start -0.3302 0.4318)
							(mid -0.402042 0.402042)
							(end -0.4318 0.3302)
						)
						(arc
							(start -0.4318 -0.3302)
							(mid -0.402042 -0.402042)
							(end -0.3302 -0.4318)
						)
						(arc
							(start 0.3302 -0.4318)
							(mid 0.402042 -0.402042)
							(end 0.4318 -0.3302)
						)
						(arc
							(start 0.4318 0.3302)
							(mid 0.402042 0.402042)
							(end 0.3302 0.4318)
						)
					)
					(width 0)
					(fill yes)
				)
			)
		)
		(pad "2" smd custom
			(at 0 0.762 180)
			(size 0.2159 0.2159)
			(layers "B.Cu" "B.Mask" "B.Paste")
			(net "GND")
			(options
				(clearance outline)
				(anchor circle)
			)
			(primitives
				(gr_poly
					(pts
						(arc
							(start -0.3302 0.4318)
							(mid -0.402042 0.402042)
							(end -0.4318 0.3302)
						)
						(arc
							(start -0.4318 -0.3302)
							(mid -0.402042 -0.402042)
							(end -0.3302 -0.4318)
						)
						(arc
							(start 0.3302 -0.4318)
							(mid 0.402042 -0.402042)
							(end 0.4318 -0.3302)
						)
						(arc
							(start 0.4318 0.3302)
							(mid 0.402042 0.402042)
							(end 0.3302 0.4318)
						)
					)
					(width 0)
					(fill yes)
				)
			)
		)
	)
	(footprint ""
		(layer "B.Cu")
		(at 16.256 -7.4803 -90)
		(property "Reference" "PR7"
			(at 0 0 90)
			(layer "B.SilkS")
			(hide yes)
			(effects
				(font
					(size 1.27 1.27)
				)
				(justify mirror)
			)
		)
		(property "Value" "8K87R2F-2-GP"
			(at -0.064008 -3.993896 270)
			(unlocked yes)
			(layer "B.Fab")
			(hide yes)
			(effects
				(font
					(size 1.016 1.016)
					(thickness 0.1524)
				)
				(justify mirror)
			)
		)
		(property "Device Type" "R402H16"
			(at -0.064008 -5.517896 270)
			(unlocked yes)
			(layer "B.Fab")
			(hide yes)
			(effects
				(font
					(size 1.016 1.016)
					(thickness 0.1524)
				)
				(justify mirror)
			)
		)
		(duplicate_pad_numbers_are_jumpers no)
		(fp_line
			(start -0.508 -0.9398)
			(end 0.508 -0.9398)
			(stroke
				(width 0.1524)
				(type default)
			)
			(layer "B.SilkS")
		)
		(fp_line
			(start 0.508 -0.9398)
			(end 0.508 0.9398)
			(stroke
				(width 0.1524)
				(type default)
			)
			(layer "B.SilkS")
		)
		(fp_rect
			(start 0.508 0.9398)
			(end -0.508 -0.9398)
			(stroke
				(width 0)
				(type default)
			)
			(fill no)
			(layer "B.CrtYd")
		)
		(fp_rect
			(start 0.508 0.9398)
			(end -0.508 -0.9398)
			(stroke
				(width 0)
				(type default)
			)
			(fill no)
			(layer "B.Fab")
		)
		(pad "1" smd custom
			(at 0 -0.4445 90)
			(size 0.1397 0.1397)
			(layers "B.Cu" "B.Mask" "B.Paste")
			(net "P3V3_CS")
			(options
				(clearance outline)
				(anchor circle)
			)
			(primitives
				(gr_poly
					(pts
						(arc
							(start -0.1778 0.2794)
							(mid -0.249642 0.249642)
							(end -0.2794 0.1778)
						)
						(arc
							(start -0.2794 -0.1778)
							(mid -0.249642 -0.249642)
							(end -0.1778 -0.2794)
						)
						(arc
							(start 0.1778 -0.2794)
							(mid 0.249642 -0.249642)
							(end 0.2794 -0.1778)
						)
						(arc
							(start 0.2794 0.1778)
							(mid 0.249642 0.249642)
							(end 0.1778 0.2794)
						)
					)
					(width 0)
					(fill yes)
				)
			)
		)
		(pad "2" smd custom
			(at 0 0.4445 90)
			(size 0.1397 0.1397)
			(layers "B.Cu" "B.Mask" "B.Paste")
			(net "AGND_P3V3")
			(options
				(clearance outline)
				(anchor circle)
			)
			(primitives
				(gr_poly
					(pts
						(arc
							(start -0.1778 0.2794)
							(mid -0.249642 0.249642)
							(end -0.2794 0.1778)
						)
						(arc
							(start -0.2794 -0.1778)
							(mid -0.249642 -0.249642)
							(end -0.1778 -0.2794)
						)
						(arc
							(start 0.1778 -0.2794)
							(mid 0.249642 -0.249642)
							(end 0.2794 -0.1778)
						)
						(arc
							(start 0.2794 0.1778)
							(mid 0.249642 0.249642)
							(end 0.1778 0.2794)
						)
					)
					(width 0)
					(fill yes)
				)
			)
		)
	)
	(footprint ""
		(layer "B.Cu")
		(at 129.3749 0.3302 180)
		(property "Reference" "R24"
			(at 0 0 0)
			(layer "B.SilkS")
			(hide yes)
			(effects
				(font
					(size 1.27 1.27)
				)
				(justify mirror)
			)
		)
		(property "Value" "4K7R2F-GP"
			(at -0.064008 -3.993896 180)
			(unlocked yes)
			(layer "B.Fab")
			(hide yes)
			(effects
				(font
					(size 1.016 1.016)
					(thickness 0.1524)
				)
				(justify mirror)
			)
		)
		(property "Device Type" "R402H16"
			(at -0.064008 -5.517896 180)
			(unlocked yes)
			(layer "B.Fab")
			(hide yes)
			(effects
				(font
					(size 1.016 1.016)
					(thickness 0.1524)
				)
				(justify mirror)
			)
		)
		(duplicate_pad_numbers_are_jumpers no)
		(fp_line
			(start 0.508 -0.9398)
			(end 0.508 0.9398)
			(stroke
				(width 0.1524)
				(type default)
			)
			(layer "B.SilkS")
		)
		(fp_line
			(start -0.508 -0.9398)
			(end 0.508 -0.9398)
			(stroke
				(width 0.1524)
				(type default)
			)
			(layer "B.SilkS")
		)
		(fp_rect
			(start 0.508 0.9398)
			(end -0.508 -0.9398)
			(stroke
				(width 0)
				(type default)
			)
			(fill no)
			(layer "B.CrtYd")
		)
		(fp_rect
			(start 0.508 0.9398)
			(end -0.508 -0.9398)
			(stroke
				(width 0)
				(type default)
			)
			(fill no)
			(layer "B.Fab")
		)
		(pad "1" smd custom
			(at 0 -0.4445)
			(size 0.1397 0.1397)
			(layers "B.Cu" "B.Mask" "B.Paste")
			(net "P3V3_STBY")
			(options
				(clearance outline)
				(anchor circle)
			)
			(primitives
				(gr_poly
					(pts
						(arc
							(start -0.1778 0.2794)
							(mid -0.249642 0.249642)
							(end -0.2794 0.1778)
						)
						(arc
							(start -0.2794 -0.1778)
							(mid -0.249642 -0.249642)
							(end -0.1778 -0.2794)
						)
						(arc
							(start 0.1778 -0.2794)
							(mid 0.249642 -0.249642)
							(end 0.2794 -0.1778)
						)
						(arc
							(start 0.2794 0.1778)
							(mid 0.249642 0.249642)
							(end 0.1778 0.2794)
						)
					)
					(width 0)
					(fill yes)
				)
			)
		)
		(pad "2" smd custom
			(at 0 0.4445)
			(size 0.1397 0.1397)
			(layers "B.Cu" "B.Mask" "B.Paste")
			(net "PU_P_MUX_SDA2")
			(options
				(clearance outline)
				(anchor circle)
			)
			(primitives
				(gr_poly
					(pts
						(arc
							(start -0.1778 0.2794)
							(mid -0.249642 0.249642)
							(end -0.2794 0.1778)
						)
						(arc
							(start -0.2794 -0.1778)
							(mid -0.249642 -0.249642)
							(end -0.1778 -0.2794)
						)
						(arc
							(start 0.1778 -0.2794)
							(mid 0.249642 -0.249642)
							(end 0.2794 -0.1778)
						)
						(arc
							(start 0.2794 0.1778)
							(mid 0.249642 0.249642)
							(end 0.1778 0.2794)
						)
					)
					(width 0)
					(fill yes)
				)
			)
		)
	)
	(footprint ""
		(layer "B.Cu")
		(at 102.2604 1.0668)
		(property "Reference" "R3"
			(at 0 0 0)
			(layer "B.SilkS")
			(hide yes)
			(effects
				(font
					(size 1.27 1.27)
				)
				(justify mirror)
			)
		)
		(property "Value" "4K7R2F-GP"
			(at -0.064008 -3.993896 0)
			(unlocked yes)
			(layer "B.Fab")
			(hide yes)
			(effects
				(font
					(size 1.016 1.016)
					(thickness 0.1524)
				)
				(justify mirror)
			)
		)
		(property "Device Type" "R402H16"
			(at -0.064008 -5.517896 0)
			(unlocked yes)
			(layer "B.Fab")
			(hide yes)
			(effects
				(font
					(size 1.016 1.016)
					(thickness 0.1524)
				)
				(justify mirror)
			)
		)
		(duplicate_pad_numbers_are_jumpers no)
		(fp_line
			(start -0.508 -0.9398)
			(end 0.508 -0.9398)
			(stroke
				(width 0.1524)
				(type default)
			)
			(layer "B.SilkS")
		)
		(fp_line
			(start 0.508 -0.9398)
			(end 0.508 0.9398)
			(stroke
				(width 0.1524)
				(type default)
			)
			(layer "B.SilkS")
		)
		(fp_rect
			(start 0.508 0.9398)
			(end -0.508 -0.9398)
			(stroke
				(width 0)
				(type default)
			)
			(fill no)
			(layer "B.CrtYd")
		)
		(fp_rect
			(start 0.508 0.9398)
			(end -0.508 -0.9398)
			(stroke
				(width 0)
				(type default)
			)
			(fill no)
			(layer "B.Fab")
		)
		(pad "1" smd custom
			(at 0 -0.4445 180)
			(size 0.1397 0.1397)
			(layers "B.Cu" "B.Mask" "B.Paste")
			(net "P3V3_STBY")
			(options
				(clearance outline)
				(anchor circle)
			)
			(primitives
				(gr_poly
					(pts
						(arc
							(start -0.1778 0.2794)
							(mid -0.249642 0.249642)
							(end -0.2794 0.1778)
						)
						(arc
							(start -0.2794 -0.1778)
							(mid -0.249642 -0.249642)
							(end -0.1778 -0.2794)
						)
						(arc
							(start 0.1778 -0.2794)
							(mid 0.249642 -0.249642)
							(end 0.2794 -0.1778)
						)
						(arc
							(start 0.2794 0.1778)
							(mid 0.249642 0.249642)
							(end 0.1778 0.2794)
						)
					)
					(width 0)
					(fill yes)
				)
			)
		)
		(pad "2" smd custom
			(at 0 0.4445 180)
			(size 0.1397 0.1397)
			(layers "B.Cu" "B.Mask" "B.Paste")
			(net "SMCLK_BMC_SLOT2")
			(options
				(clearance outline)
				(anchor circle)
			)
			(primitives
				(gr_poly
					(pts
						(arc
							(start -0.1778 0.2794)
							(mid -0.249642 0.249642)
							(end -0.2794 0.1778)
						)
						(arc
							(start -0.2794 -0.1778)
							(mid -0.249642 -0.249642)
							(end -0.1778 -0.2794)
						)
						(arc
							(start 0.1778 -0.2794)
							(mid 0.249642 -0.249642)
							(end 0.2794 -0.1778)
						)
						(arc
							(start 0.2794 0.1778)
							(mid 0.249642 0.249642)
							(end 0.1778 0.2794)
						)
					)
					(width 0)
					(fill yes)
				)
			)
		)
	)
	(footprint ""
		(layer "B.Cu")
		(at 46.150022 -20.100036 90)
		(property "Reference" "CN2"
			(at 0 0 90)
			(layer "B.SilkS")
			(hide yes)
			(effects
				(font
					(size 1.27 1.27)
				)
				(justify mirror)
			)
		)
		(property "Value" "ALP-CONN4F-GP"
			(at 6.7691 0.381 90)
			(unlocked yes)
			(layer "B.Fab")
			(hide yes)
			(effects
				(font
					(size 1.016 1.016)
					(thickness 0.1524)
				)
				(justify mirror)
			)
		)
		(property "Device Type" "C23118-P04C0-L"
			(at 6.7691 -1.143 90)
			(unlocked yes)
			(layer "B.Fab")
			(hide yes)
			(effects
				(font
					(size 1.016 1.016)
					(thickness 0.1524)
				)
				(justify mirror)
			)
		)
		(duplicate_pad_numbers_are_jumpers no)
		(fp_line
			(start 3.6322 -4.2926)
			(end -3.6322 -4.2926)
			(stroke
				(width 0.1524)
				(type default)
			)
			(layer "B.SilkS")
		)
		(fp_line
			(start -3.6322 -4.2926)
			(end -3.6322 3.6068)
			(stroke
				(width 0.1524)
				(type default)
			)
			(layer "B.SilkS")
		)
		(fp_line
			(start -5.5499 3.5179)
			(end -5.5499 17.0053)
			(stroke
				(width 0.3302)
				(type default)
			)
			(layer "B.SilkS")
		)
		(fp_line
			(start 5.0546 3.6068)
			(end 3.6322 3.6068)
			(stroke
				(width 0.1524)
				(type default)
			)
			(layer "B.SilkS")
		)
		(fp_line
			(start 3.6322 3.6068)
			(end 3.6322 -4.2926)
			(stroke
				(width 0.1524)
				(type default)
			)
			(layer "B.SilkS")
		)
		(fp_line
			(start -3.6322 3.6068)
			(end -5.461 3.6068)
			(stroke
				(width 0.1524)
				(type default)
			)
			(layer "B.SilkS")
		)
		(fp_line
			(start -5.461 3.6068)
			(end -5.461 16.9164)
			(stroke
				(width 0.1524)
				(type default)
			)
			(layer "B.SilkS")
		)
		(fp_line
			(start 1.016 15.9004)
			(end -1.016 15.9004)
			(stroke
				(width 0.1524)
				(type default)
			)
			(layer "B.SilkS")
		)
		(fp_line
			(start -1.016 15.9004)
			(end -1.016 16.9164)
			(stroke
				(width 0.1524)
				(type default)
			)
			(layer "B.SilkS")
		)
		(fp_line
			(start 5.0546 16.9164)
			(end 5.0546 3.6068)
			(stroke
				(width 0.1524)
				(type default)
			)
			(layer "B.SilkS")
		)
		(fp_line
			(start 1.016 16.9164)
			(end 1.016 15.9004)
			(stroke
				(width 0.1524)
				(type default)
			)
			(layer "B.SilkS")
		)
		(fp_line
			(start -5.461 16.9164)
			(end 5.0546 16.9164)
			(stroke
				(width 0.1524)
				(type default)
			)
			(layer "B.SilkS")
		)
		(fp_circle
			(center 2.100072 -2.750058)
			(end 2.100072 -1.111758)
			(stroke
				(width 0.3048)
				(type default)
			)
			(fill no)
			(layer "B.SilkS")
		)
		(fp_circle
			(center -2.100072 -2.750058)
			(end -2.100072 -1.111758)
			(stroke
				(width 0.3048)
				(type default)
			)
			(fill no)
			(layer "B.SilkS")
		)
		(fp_circle
			(center 2.100072 2.750058)
			(end 2.100072 4.388358)
			(stroke
				(width 0.3048)
				(type default)
			)
			(fill no)
			(layer "B.SilkS")
		)
		(fp_circle
			(center -2.100072 2.750058)
			(end -2.100072 4.388358)
			(stroke
				(width 0.3048)
				(type default)
			)
			(fill no)
			(layer "B.SilkS")
		)
		(fp_poly
			(pts
				(xy 2.667 -3.2512) (xy -2.667 -3.2512) (xy -2.667 3.8608) (xy -5.207 3.8608) (xy -5.207 16.6624)
				(xy 4.8006 16.6624) (xy 4.8006 3.8608) (xy 2.667 3.8608)
			)
			(stroke
				(width 0)
				(type default)
			)
			(fill no)
			(layer "B.CrtYd")
		)
		(fp_poly
			(pts
				(xy 5.3086 17.1704) (xy 5.3086 3.3528) (xy 3.8862 3.3528) (xy 3.8862 -4.5466) (xy -3.8862 -4.5466)
				(xy -3.8862 -0.00635) (xy -2.667 -0.00635) (xy -2.667 -3.2512) (xy 2.667 -3.2512) (xy 2.667 3.8608)
				(xy 4.8006 3.8608) (xy 4.8006 16.6624) (xy -5.207 16.6624) (xy -5.207 3.8608) (xy -2.667 3.8608)
				(xy -2.667 0.00635) (xy -3.8862 0.00635) (xy -3.8862 3.3528) (xy -5.715 3.3528) (xy -5.715 17.1704)
			)
			(stroke
				(width 0)
				(type default)
			)
			(fill no)
			(layer "B.CrtYd")
		)
		(fp_poly
			(pts
				(xy 5.3086 17.1704) (xy 5.3086 3.3528) (xy 3.8862 3.3528) (xy 3.8862 -4.5466) (xy -3.8862 -4.5466)
				(xy -3.8862 3.3528) (xy -5.715 3.3528) (xy -5.715 17.1704)
			)
			(stroke
				(width 0)
				(type default)
			)
			(fill no)
			(layer "B.Fab")
		)
		(pad "1" thru_hole circle
			(at -2.100072 2.750058 270)
			(size 2.5654 2.5654)
			(drill 1.8034)
			(layers "*.Cu" "*.Mask")
			(remove_unused_layers no)
			(net "GND")
			(clearance 0.127)
			(thermal_gap 0.127)
		)
		(pad "2" thru_hole circle
			(at 2.100072 2.750058 270)
			(size 2.5654 2.5654)
			(drill 1.8034)
			(layers "*.Cu" "*.Mask")
			(remove_unused_layers no)
			(net "GND")
			(clearance 0.127)
			(thermal_gap 0.127)
		)
		(pad "3" thru_hole circle
			(at -2.100072 -2.750058 270)
			(size 2.5654 2.5654)
			(drill 1.8034)
			(layers "*.Cu" "*.Mask")
			(remove_unused_layers no)
			(net "P12V_ATX")
			(clearance 0.127)
			(thermal_gap 0.127)
		)
		(pad "4" thru_hole circle
			(at 2.100072 -2.750058 270)
			(size 2.5654 2.5654)
			(drill 1.8034)
			(layers "*.Cu" "*.Mask")
			(remove_unused_layers no)
			(net "P12V_ATX")
			(clearance 0.127)
			(thermal_gap 0.127)
		)
	)
	(footprint ""
		(layer "B.Cu")
		(at 129.2352 -22.4028)
		(property "Reference" "R175"
			(at 0 0 0)
			(layer "B.SilkS")
			(hide yes)
			(effects
				(font
					(size 1.27 1.27)
				)
				(justify mirror)
			)
		)
		(property "Value" "0R2F-1-GP"
			(at -0.064008 -3.993896 0)
			(unlocked yes)
			(layer "B.Fab")
			(hide yes)
			(effects
				(font
					(size 1.016 1.016)
					(thickness 0.1524)
				)
				(justify mirror)
			)
		)
		(property "Device Type" "R402H16"
			(at -0.064008 -5.517896 0)
			(unlocked yes)
			(layer "B.Fab")
			(hide yes)
			(effects
				(font
					(size 1.016 1.016)
					(thickness 0.1524)
				)
				(justify mirror)
			)
		)
		(duplicate_pad_numbers_are_jumpers no)
		(fp_line
			(start -0.508 -0.9398)
			(end 0.508 -0.9398)
			(stroke
				(width 0.1524)
				(type default)
			)
			(layer "B.SilkS")
		)
		(fp_line
			(start 0.508 -0.9398)
			(end 0.508 0.9398)
			(stroke
				(width 0.1524)
				(type default)
			)
			(layer "B.SilkS")
		)
		(fp_rect
			(start 0.508 0.9398)
			(end -0.508 -0.9398)
			(stroke
				(width 0)
				(type default)
			)
			(fill no)
			(layer "B.CrtYd")
		)
		(fp_rect
			(start 0.508 0.9398)
			(end -0.508 -0.9398)
			(stroke
				(width 0)
				(type default)
			)
			(fill no)
			(layer "B.Fab")
		)
		(pad "1" smd custom
			(at 0 -0.4445 180)
			(size 0.1397 0.1397)
			(layers "B.Cu" "B.Mask" "B.Paste")
			(net "SMDAT_USB_HUB")
			(options
				(clearance outline)
				(anchor circle)
			)
			(primitives
				(gr_poly
					(pts
						(arc
							(start -0.1778 0.2794)
							(mid -0.249642 0.249642)
							(end -0.2794 0.1778)
						)
						(arc
							(start -0.2794 -0.1778)
							(mid -0.249642 -0.249642)
							(end -0.1778 -0.2794)
						)
						(arc
							(start 0.1778 -0.2794)
							(mid 0.249642 -0.249642)
							(end 0.2794 -0.1778)
						)
						(arc
							(start 0.2794 0.1778)
							(mid 0.249642 0.249642)
							(end 0.1778 0.2794)
						)
					)
					(width 0)
					(fill yes)
				)
			)
		)
		(pad "2" smd custom
			(at 0 0.4445 180)
			(size 0.1397 0.1397)
			(layers "B.Cu" "B.Mask" "B.Paste")
			(net "SMDAT_BMC_DEVICE")
			(options
				(clearance outline)
				(anchor circle)
			)
			(primitives
				(gr_poly
					(pts
						(arc
							(start -0.1778 0.2794)
							(mid -0.249642 0.249642)
							(end -0.2794 0.1778)
						)
						(arc
							(start -0.2794 -0.1778)
							(mid -0.249642 -0.249642)
							(end -0.1778 -0.2794)
						)
						(arc
							(start 0.1778 -0.2794)
							(mid 0.249642 -0.249642)
							(end 0.2794 -0.1778)
						)
						(arc
							(start 0.2794 0.1778)
							(mid 0.249642 0.249642)
							(end 0.1778 0.2794)
						)
					)
					(width 0)
					(fill yes)
				)
			)
		)
	)
	(footprint ""
		(layer "B.Cu")
		(at 19.2278 -31.9532 180)
		(property "Reference" "C90"
			(at 0 0 0)
			(layer "B.SilkS")
			(hide yes)
			(effects
				(font
					(size 1.27 1.27)
				)
				(justify mirror)
			)
		)
		(property "Value" "SC22U16V5MX-4-GP"
			(at 0.0762 -6.1214 180)
			(unlocked yes)
			(layer "B.Fab")
			(hide yes)
			(effects
				(font
					(size 1.016 1.016)
					(thickness 0.1524)
				)
				(justify mirror)
			)
		)
		(property "Device Type" "C805H58"
			(at 0.0762 -8.1534 180)
			(unlocked yes)
			(layer "B.Fab")
			(hide yes)
			(effects
				(font
					(size 1.016 1.016)
					(thickness 0.1524)
				)
				(justify mirror)
			)
		)
		(duplicate_pad_numbers_are_jumpers no)
		(fp_line
			(start -0.635 0)
			(end 0.635 0)
			(stroke
				(width 0.508)
				(type default)
			)
			(layer "B.SilkS")
		)
		(fp_rect
			(start 0.9652 1.778)
			(end -0.9652 -1.778)
			(stroke
				(width 0)
				(type default)
			)
			(fill no)
			(layer "B.CrtYd")
		)
		(fp_poly
			(pts
				(xy 0.9652 -1.778) (xy -0.9652 -1.778) (xy -0.9652 1.778) (xy 0.9652 1.778)
			)
			(stroke
				(width 0)
				(type default)
			)
			(fill no)
			(layer "B.Fab")
		)
		(pad "1" smd rect
			(at 0 -0.9652)
			(size 1.397 1.143)
			(layers "B.Cu" "B.Mask" "B.Paste")
			(net "P12V_ATX")
		)
		(pad "2" smd rect
			(at 0 0.9652)
			(size 1.397 1.143)
			(layers "B.Cu" "B.Mask" "B.Paste")
			(net "GND")
		)
	)
	(footprint ""
		(layer "B.Cu")
		(at 17.6657 -13.8557 180)
		(property "Reference" "PR9"
			(at 0 0 0)
			(layer "B.SilkS")
			(hide yes)
			(effects
				(font
					(size 1.27 1.27)
				)
				(justify mirror)
			)
		)
		(property "Value" "3K74R2F-GP"
			(at -0.064008 -3.993896 180)
			(unlocked yes)
			(layer "B.Fab")
			(hide yes)
			(effects
				(font
					(size 1.016 1.016)
					(thickness 0.1524)
				)
				(justify mirror)
			)
		)
		(property "Device Type" "R402H16"
			(at -0.064008 -5.517896 180)
			(unlocked yes)
			(layer "B.Fab")
			(hide yes)
			(effects
				(font
					(size 1.016 1.016)
					(thickness 0.1524)
				)
				(justify mirror)
			)
		)
		(duplicate_pad_numbers_are_jumpers no)
		(fp_line
			(start 0.508 -0.9398)
			(end 0.508 0.9398)
			(stroke
				(width 0.1524)
				(type default)
			)
			(layer "B.SilkS")
		)
		(fp_line
			(start -0.508 -0.9398)
			(end 0.508 -0.9398)
			(stroke
				(width 0.1524)
				(type default)
			)
			(layer "B.SilkS")
		)
		(fp_rect
			(start 0.508 0.9398)
			(end -0.508 -0.9398)
			(stroke
				(width 0)
				(type default)
			)
			(fill no)
			(layer "B.CrtYd")
		)
		(fp_rect
			(start 0.508 0.9398)
			(end -0.508 -0.9398)
			(stroke
				(width 0)
				(type default)
			)
			(fill no)
			(layer "B.Fab")
		)
		(pad "1" smd custom
			(at 0 -0.4445)
			(size 0.1397 0.1397)
			(layers "B.Cu" "B.Mask" "B.Paste")
			(net "P3V3_EN")
			(options
				(clearance outline)
				(anchor circle)
			)
			(primitives
				(gr_poly
					(pts
						(arc
							(start -0.1778 0.2794)
							(mid -0.249642 0.249642)
							(end -0.2794 0.1778)
						)
						(arc
							(start -0.2794 -0.1778)
							(mid -0.249642 -0.249642)
							(end -0.1778 -0.2794)
						)
						(arc
							(start 0.1778 -0.2794)
							(mid 0.249642 -0.249642)
							(end 0.2794 -0.1778)
						)
						(arc
							(start 0.2794 0.1778)
							(mid 0.249642 0.249642)
							(end 0.1778 0.2794)
						)
					)
					(width 0)
					(fill yes)
				)
			)
		)
		(pad "2" smd custom
			(at 0 0.4445)
			(size 0.1397 0.1397)
			(layers "B.Cu" "B.Mask" "B.Paste")
			(net "GND")
			(options
				(clearance outline)
				(anchor circle)
			)
			(primitives
				(gr_poly
					(pts
						(arc
							(start -0.1778 0.2794)
							(mid -0.249642 0.249642)
							(end -0.2794 0.1778)
						)
						(arc
							(start -0.2794 -0.1778)
							(mid -0.249642 -0.249642)
							(end -0.1778 -0.2794)
						)
						(arc
							(start 0.1778 -0.2794)
							(mid 0.249642 -0.249642)
							(end 0.2794 -0.1778)
						)
						(arc
							(start 0.2794 0.1778)
							(mid 0.249642 0.249642)
							(end 0.1778 0.2794)
						)
					)
					(width 0)
					(fill yes)
				)
			)
		)
	)
	(footprint ""
		(layer "B.Cu")
		(at 129.7432 -28.194 -90)
		(property "Reference" "LU1"
			(at 0 0 90)
			(layer "B.SilkS")
			(hide yes)
			(effects
				(font
					(size 1.27 1.27)
				)
				(justify mirror)
			)
		)
		(property "Value" "MMZ1608S301AT-GP"
			(at 0.0254 -2.8956 270)
			(unlocked yes)
			(layer "B.Fab")
			(hide yes)
			(effects
				(font
					(size 1.016 1.016)
					(thickness 0.1524)
				)
				(justify mirror)
			)
		)
		(property "Device Type" "L1608-UH38"
			(at 0.0254 -4.4196 270)
			(unlocked yes)
			(layer "B.Fab")
			(hide yes)
			(effects
				(font
					(size 1.016 1.016)
					(thickness 0.1524)
				)
				(justify mirror)
			)
		)
		(duplicate_pad_numbers_are_jumpers no)
		(fp_line
			(start -0.254 0)
			(end 0.254 0)
			(stroke
				(width 0.2032)
				(type default)
			)
			(layer "B.SilkS")
		)
		(fp_rect
			(start 0.5842 1.3335)
			(end -0.5842 -1.3335)
			(stroke
				(width 0)
				(type default)
			)
			(fill no)
			(layer "B.CrtYd")
		)
		(fp_rect
			(start 0.5842 1.3335)
			(end -0.5842 -1.3335)
			(stroke
				(width 0)
				(type default)
			)
			(fill no)
			(layer "B.Fab")
		)
		(pad "1" smd custom
			(at 0 -0.762 90)
			(size 0.2159 0.2159)
			(layers "B.Cu" "B.Mask" "B.Paste")
			(net "P3V3_STBY")
			(options
				(clearance outline)
				(anchor circle)
			)
			(primitives
				(gr_poly
					(pts
						(arc
							(start -0.3302 0.4318)
							(mid -0.402042 0.402042)
							(end -0.4318 0.3302)
						)
						(arc
							(start -0.4318 -0.3302)
							(mid -0.402042 -0.402042)
							(end -0.3302 -0.4318)
						)
						(arc
							(start 0.3302 -0.4318)
							(mid 0.402042 -0.402042)
							(end 0.4318 -0.3302)
						)
						(arc
							(start 0.4318 0.3302)
							(mid 0.402042 0.402042)
							(end 0.3302 0.4318)
						)
					)
					(width 0)
					(fill yes)
				)
			)
		)
		(pad "2" smd custom
			(at 0 0.762 90)
			(size 0.2159 0.2159)
			(layers "B.Cu" "B.Mask" "B.Paste")
			(net "P3V3_USB_HUB")
			(options
				(clearance outline)
				(anchor circle)
			)
			(primitives
				(gr_poly
					(pts
						(arc
							(start -0.3302 0.4318)
							(mid -0.402042 0.402042)
							(end -0.4318 0.3302)
						)
						(arc
							(start -0.4318 -0.3302)
							(mid -0.402042 -0.402042)
							(end -0.3302 -0.4318)
						)
						(arc
							(start 0.3302 -0.4318)
							(mid 0.402042 -0.402042)
							(end 0.4318 -0.3302)
						)
						(arc
							(start 0.4318 0.3302)
							(mid 0.402042 0.402042)
							(end 0.3302 0.4318)
						)
					)
					(width 0)
					(fill yes)
				)
			)
		)
	)
	(footprint ""
		(layer "B.Cu")
		(at 27.9527 -2.0066 180)
		(property "Reference" "PC6"
			(at 0 0 0)
			(layer "B.SilkS")
			(hide yes)
			(effects
				(font
					(size 1.27 1.27)
				)
				(justify mirror)
			)
		)
		(property "Value" "SC22U6D3V5MX-5-GP"
			(at 0.0762 -6.1214 180)
			(unlocked yes)
			(layer "B.Fab")
			(hide yes)
			(effects
				(font
					(size 1.016 1.016)
					(thickness 0.1524)
				)
				(justify mirror)
			)
		)
		(property "Device Type" "C805H56"
			(at 0.0762 -8.1534 180)
			(unlocked yes)
			(layer "B.Fab")
			(hide yes)
			(effects
				(font
					(size 1.016 1.016)
					(thickness 0.1524)
				)
				(justify mirror)
			)
		)
		(duplicate_pad_numbers_are_jumpers no)
		(fp_line
			(start -0.635 0)
			(end 0.635 0)
			(stroke
				(width 0.508)
				(type default)
			)
			(layer "B.SilkS")
		)
		(fp_rect
			(start 0.9652 1.778)
			(end -0.9652 -1.778)
			(stroke
				(width 0)
				(type default)
			)
			(fill no)
			(layer "B.CrtYd")
		)
		(fp_poly
			(pts
				(xy 0.9652 -1.778) (xy -0.9652 -1.778) (xy -0.9652 1.778) (xy 0.9652 1.778)
			)
			(stroke
				(width 0)
				(type default)
			)
			(fill no)
			(layer "B.Fab")
		)
		(pad "1" smd rect
			(at 0 -0.9652)
			(size 1.397 1.143)
			(layers "B.Cu" "B.Mask" "B.Paste")
			(net "P3V3_VR")
		)
		(pad "2" smd rect
			(at 0 0.9652)
			(size 1.397 1.143)
			(layers "B.Cu" "B.Mask" "B.Paste")
			(net "GND")
		)
	)
	(footprint ""
		(layer "B.Cu")
		(at 22.2504 -23.9014 -90)
		(property "Reference" "U18"
			(at 0 0 90)
			(layer "B.SilkS")
			(hide yes)
			(effects
				(font
					(size 1.27 1.27)
				)
				(justify mirror)
			)
		)
		(property "Value" "INA230AIRGTR-GP"
			(at 5.6388 -6.1468 270)
			(unlocked yes)
			(layer "B.Fab")
			(hide yes)
			(effects
				(font
					(size 1.016 1.016)
					(thickness 0.1524)
				)
				(justify mirror)
			)
		)
		(property "Device Type" "QFN16-G1D8-UH40"
			(at 5.6388 -7.6708 270)
			(unlocked yes)
			(layer "B.Fab")
			(hide yes)
			(effects
				(font
					(size 1.016 1.016)
					(thickness 0.1524)
				)
				(justify mirror)
			)
		)
		(duplicate_pad_numbers_are_jumpers no)
		(fp_line
			(start -2.5146 2.5146)
			(end -2.5146 1.2446)
			(stroke
				(width 0.1524)
				(type default)
			)
			(layer "B.SilkS")
		)
		(fp_line
			(start -1.2446 2.5146)
			(end -2.5146 2.5146)
			(stroke
				(width 0.1524)
				(type default)
			)
			(layer "B.SilkS")
		)
		(fp_line
			(start 2.5146 2.5146)
			(end 1.2446 2.5146)
			(stroke
				(width 0.1524)
				(type default)
			)
			(layer "B.SilkS")
		)
		(fp_line
			(start 0.248666 2.287524)
			(end 0.248666 3.049524)
			(stroke
				(width 0.1524)
				(type default)
			)
			(layer "B.SilkS")
		)
		(fp_line
			(start 2.5146 1.2446)
			(end 2.5146 2.5146)
			(stroke
				(width 0.1524)
				(type default)
			)
			(layer "B.SilkS")
		)
		(fp_line
			(start -2.287524 -0.260604)
			(end -2.795524 -0.260604)
			(stroke
				(width 0.1524)
				(type default)
			)
			(layer "B.SilkS")
		)
		(fp_line
			(start 2.287524 -0.753364)
			(end 2.795524 -0.753364)
			(stroke
				(width 0.1524)
				(type default)
			)
			(layer "B.SilkS")
		)
		(fp_line
			(start 1.2446 -2.5146)
			(end 2.5146 -2.5146)
			(stroke
				(width 0.1524)
				(type default)
			)
			(layer "B.SilkS")
		)
		(fp_line
			(start 2.5146 -2.5146)
			(end 2.5146 -1.2446)
			(stroke
				(width 0.1524)
				(type default)
			)
			(layer "B.SilkS")
		)
		(fp_poly
			(pts
				(xy -1.2446 -2.5146) (xy -2.5146 -2.5146) (xy -2.5146 -1.2446)
			)
			(stroke
				(width 0)
				(type default)
			)
			(fill yes)
			(layer "B.SilkS")
		)
		(fp_rect
			(start 1.4986 1.4986)
			(end -1.4986 -1.4986)
			(stroke
				(width 0)
				(type default)
			)
			(fill no)
			(layer "B.CrtYd")
		)
		(fp_poly
			(pts
				(xy 1.4986 -1.4986) (xy 2.5146 -1.4986) (xy 2.5146 -2.5146) (xy -2.5146 -2.5146) (xy -2.5146 2.5146)
				(xy 2.5146 2.5146) (xy 2.5146 -1.4859) (xy 1.4986 -1.4859) (xy 1.4986 1.4986) (xy -1.4986 1.4986)
				(xy -1.4986 -1.4986)
			)
			(stroke
				(width 0)
				(type default)
			)
			(fill no)
			(layer "B.CrtYd")
		)
		(fp_rect
			(start 2.5146 2.5146)
			(end -2.5146 -2.5146)
			(stroke
				(width 0)
				(type default)
			)
			(fill no)
			(layer "B.Fab")
		)
		(pad "1" smd rect
			(at -0.750062 -1.550924 90)
			(size 0.3048 0.9144)
			(layers "B.Cu" "B.Mask" "B.Paste")
			(net "ATX_VMONITOR_A1")
		)
		(pad "2" smd rect
			(at -0.249936 -1.550924 90)
			(size 0.3048 0.9144)
			(layers "B.Cu" "B.Mask" "B.Paste")
			(net "ATX_VMONITOR_A0")
		)
		(pad "3" smd rect
			(at 0.249936 -1.550924 90)
			(size 0.3048 0.9144)
			(layers "B.Cu" "B.Mask" "B.Paste")
			(net "SMB_VMONITOR_ATX_ALERT_N")
		)
		(pad "4" smd rect
			(at 0.750062 -1.550924 90)
			(size 0.3048 0.9144)
			(layers "B.Cu" "B.Mask" "B.Paste")
			(net "SMB_VMONITOR_ATX_MUX_SDA")
		)
		(pad "5" smd rect
			(at 1.550924 -0.750062 90)
			(size 0.9144 0.3048)
			(layers "B.Cu" "B.Mask" "B.Paste")
			(net "SMB_VMONITOR_ATX_MUX_SCL")
		)
		(pad "6" smd rect
			(at 1.550924 -0.249936 90)
			(size 0.9144 0.3048)
			(layers "B.Cu" "B.Mask" "B.Paste")
			(net "Net_214")
		)
		(pad "7" smd rect
			(at 1.550924 0.249936 90)
			(size 0.9144 0.3048)
			(layers "B.Cu" "B.Mask" "B.Paste")
			(net "Net_215")
		)
		(pad "8" smd rect
			(at 1.550924 0.750062 90)
			(size 0.9144 0.3048)
			(layers "B.Cu" "B.Mask" "B.Paste")
			(net "Net_216")
		)
		(pad "9" smd rect
			(at 0.750062 1.550924 90)
			(size 0.3048 0.9144)
			(layers "B.Cu" "B.Mask" "B.Paste")
			(net "P3V3_STBY")
		)
		(pad "10" smd rect
			(at 0.249936 1.550924 90)
			(size 0.3048 0.9144)
			(layers "B.Cu" "B.Mask" "B.Paste")
			(net "GND")
		)
		(pad "11" smd rect
			(at -0.249936 1.550924 90)
			(size 0.3048 0.9144)
			(layers "B.Cu" "B.Mask" "B.Paste")
			(net "P12V")
		)
		(pad "12" smd rect
			(at -0.750062 1.550924 90)
			(size 0.3048 0.9144)
			(layers "B.Cu" "B.Mask" "B.Paste")
			(net "ATX_P12V_SENSE_VN_R")
		)
		(pad "13" smd rect
			(at -1.550924 0.750062 90)
			(size 0.9144 0.3048)
			(layers "B.Cu" "B.Mask" "B.Paste")
			(net "ATX_P12V_SENSE_VP_R")
		)
		(pad "14" smd rect
			(at -1.550924 0.249936 90)
			(size 0.9144 0.3048)
			(layers "B.Cu" "B.Mask" "B.Paste")
			(net "Net_211")
		)
		(pad "15" smd rect
			(at -1.550924 -0.249936 90)
			(size 0.9144 0.3048)
			(layers "B.Cu" "B.Mask" "B.Paste")
			(net "Net_212")
		)
		(pad "16" smd rect
			(at -1.550924 -0.750062 90)
			(size 0.9144 0.3048)
			(layers "B.Cu" "B.Mask" "B.Paste")
			(net "Net_213")
		)
		(pad "17" smd rect
			(at 0 0 90)
			(size 1.778 1.778)
			(layers "B.Cu" "B.Mask" "B.Paste")
			(net "GND")
		)
	)
	(footprint ""
		(layer "B.Cu")
		(at 127.44704 -5.9944 180)
		(property "Reference" "U2"
			(at 0 0 0)
			(layer "B.SilkS")
			(hide yes)
			(effects
				(font
					(size 1.27 1.27)
				)
				(justify mirror)
			)
		)
		(property "Value" "PCA9544APW-GP"
			(at 0 -11.8872 180)
			(unlocked yes)
			(layer "B.Fab")
			(hide yes)
			(effects
				(font
					(size 1.016 1.016)
					(thickness 0.1524)
				)
				(justify mirror)
			)
		)
		(property "Device Type" "TSOIC20H44"
			(at 0 -13.7922 180)
			(unlocked yes)
			(layer "B.Fab")
			(hide yes)
			(effects
				(font
					(size 1.016 1.016)
					(thickness 0.1524)
				)
				(justify mirror)
			)
		)
		(duplicate_pad_numbers_are_jumpers no)
		(fp_line
			(start 3.556 3.6322)
			(end 3.556 1.397)
			(stroke
				(width 0.508)
				(type default)
			)
			(layer "B.SilkS")
		)
		(fp_line
			(start 3.556 1.397)
			(end 3.556 1.778)
			(stroke
				(width 0.2032)
				(type default)
			)
			(layer "B.SilkS")
		)
		(fp_line
			(start 3.556 -1.397)
			(end 3.556 3.7084)
			(stroke
				(width 0.2032)
				(type default)
			)
			(layer "B.SilkS")
		)
		(fp_line
			(start 3.556 -1.397)
			(end -3.175 -1.397)
			(stroke
				(width 0.2032)
				(type default)
			)
			(layer "B.SilkS")
		)
		(fp_line
			(start 2.667 0)
			(end 3.556 0.889)
			(stroke
				(width 0.2032)
				(type default)
			)
			(layer "B.SilkS")
		)
		(fp_line
			(start 2.667 0)
			(end 3.556 -0.889)
			(stroke
				(width 0.2032)
				(type default)
			)
			(layer "B.SilkS")
		)
		(fp_line
			(start -3.175 1.397)
			(end 3.556 1.397)
			(stroke
				(width 0.2032)
				(type default)
			)
			(layer "B.SilkS")
		)
		(fp_line
			(start -3.175 -1.397)
			(end -3.175 1.397)
			(stroke
				(width 0.2032)
				(type default)
			)
			(layer "B.SilkS")
		)
		(fp_poly
			(pts
				(xy 3.25628 -1.8542) (xy -3.25628 -1.8542) (xy -3.25628 1.8542) (xy 3.25628 1.8542)
			)
			(stroke
				(width 0)
				(type default)
			)
			(fill yes)
			(layer "B.SilkS")
		)
		(fp_rect
			(start 3.556 3.81)
			(end -3.556 -3.81)
			(stroke
				(width 0)
				(type default)
			)
			(fill no)
			(layer "B.CrtYd")
		)
		(fp_poly
			(pts
				(xy 3.556 -3.81) (xy -3.556 -3.81) (xy -3.556 3.81) (xy 3.556 3.81)
			)
			(stroke
				(width 0)
				(type default)
			)
			(fill no)
			(layer "B.Fab")
		)
		(pad "1" smd rect
			(at 2.92608 2.8194)
			(size 0.3556 1.524)
			(layers "B.Cu" "B.Mask" "B.Paste")
			(net "SMB_P_HUB_A0")
		)
		(pad "2" smd rect
			(at 2.27584 2.8194)
			(size 0.3556 1.524)
			(layers "B.Cu" "B.Mask" "B.Paste")
			(net "SMB_P_HUB_A1")
		)
		(pad "3" smd rect
			(at 1.6256 2.8194)
			(size 0.3556 1.524)
			(layers "B.Cu" "B.Mask" "B.Paste")
			(net "SMB_P_HUB_A2")
		)
		(pad "4" smd rect
			(at 0.97536 2.8194)
			(size 0.3556 1.524)
			(layers "B.Cu" "B.Mask" "B.Paste")
			(net "SMB_PCIE_SLOT2_ALERT_N")
		)
		(pad "5" smd rect
			(at 0.32512 2.8194)
			(size 0.3556 1.524)
			(layers "B.Cu" "B.Mask" "B.Paste")
			(net "SMDAT_PCH_SLOT2")
		)
		(pad "6" smd rect
			(at -0.32512 2.8194)
			(size 0.3556 1.524)
			(layers "B.Cu" "B.Mask" "B.Paste")
			(net "SMCLK_PCH_SLOT2")
		)
		(pad "7" smd rect
			(at -0.97536 2.8194)
			(size 0.3556 1.524)
			(layers "B.Cu" "B.Mask" "B.Paste")
			(net "SMB_PCIE_SLOT3_ALERT_N")
		)
		(pad "8" smd rect
			(at -1.6256 2.8194)
			(size 0.3556 1.524)
			(layers "B.Cu" "B.Mask" "B.Paste")
			(net "SMDAT_PCH_SLOT3")
		)
		(pad "9" smd rect
			(at -2.27584 2.8194)
			(size 0.3556 1.524)
			(layers "B.Cu" "B.Mask" "B.Paste")
			(net "SMCLK_PCH_SLOT3")
		)
		(pad "10" smd rect
			(at -2.92608 2.8194)
			(size 0.3556 1.524)
			(layers "B.Cu" "B.Mask" "B.Paste")
			(net "GND")
		)
		(pad "11" smd rect
			(at -2.92608 -2.8194)
			(size 0.3556 1.524)
			(layers "B.Cu" "B.Mask" "B.Paste")
			(net "PU_P_I2CMUX_INT2_N")
		)
		(pad "12" smd rect
			(at -2.27584 -2.8194)
			(size 0.3556 1.524)
			(layers "B.Cu" "B.Mask" "B.Paste")
			(net "PU_P_MUX_SDA2")
		)
		(pad "13" smd rect
			(at -1.6256 -2.8194)
			(size 0.3556 1.524)
			(layers "B.Cu" "B.Mask" "B.Paste")
			(net "PU_P_MUX_SCL2")
		)
		(pad "14" smd rect
			(at -0.97536 -2.8194)
			(size 0.3556 1.524)
			(layers "B.Cu" "B.Mask" "B.Paste")
			(net "SMB_PCH_DEVICE_ALERT_N")
		)
		(pad "15" smd rect
			(at -0.32512 -2.8194)
			(size 0.3556 1.524)
			(layers "B.Cu" "B.Mask" "B.Paste")
			(net "SMDAT_PCH_DEVICE")
		)
		(pad "16" smd rect
			(at 0.32512 -2.8194)
			(size 0.3556 1.524)
			(layers "B.Cu" "B.Mask" "B.Paste")
			(net "SMCLK_PCH_DEVICE")
		)
		(pad "17" smd rect
			(at 0.97536 -2.8194)
			(size 0.3556 1.524)
			(layers "B.Cu" "B.Mask" "B.Paste")
			(net "SMB_PCH_ALERT_N")
		)
		(pad "18" smd rect
			(at 1.6256 -2.8194)
			(size 0.3556 1.524)
			(layers "B.Cu" "B.Mask" "B.Paste")
			(net "SMCLK_PCH_R")
		)
		(pad "19" smd rect
			(at 2.27584 -2.8194)
			(size 0.3556 1.524)
			(layers "B.Cu" "B.Mask" "B.Paste")
			(net "SMDAT_PCH_R")
		)
		(pad "20" smd rect
			(at 2.92608 -2.8194)
			(size 0.3556 1.524)
			(layers "B.Cu" "B.Mask" "B.Paste")
			(net "P3V3_STBY")
		)
	)
	(footprint ""
		(layer "B.Cu")
		(at 119.6594 -22.7838 180)
		(property "Reference" "R112"
			(at 0 0 0)
			(layer "B.SilkS")
			(hide yes)
			(effects
				(font
					(size 1.27 1.27)
				)
				(justify mirror)
			)
		)
		(property "Value" "0R2F-1-GP"
			(at -0.064008 -3.993896 180)
			(unlocked yes)
			(layer "B.Fab")
			(hide yes)
			(effects
				(font
					(size 1.016 1.016)
					(thickness 0.1524)
				)
				(justify mirror)
			)
		)
		(property "Device Type" "R402H16"
			(at -0.064008 -5.517896 180)
			(unlocked yes)
			(layer "B.Fab")
			(hide yes)
			(effects
				(font
					(size 1.016 1.016)
					(thickness 0.1524)
				)
				(justify mirror)
			)
		)
		(duplicate_pad_numbers_are_jumpers no)
		(fp_line
			(start 0.508 -0.9398)
			(end 0.508 0.9398)
			(stroke
				(width 0.1524)
				(type default)
			)
			(layer "B.SilkS")
		)
		(fp_line
			(start -0.508 -0.9398)
			(end 0.508 -0.9398)
			(stroke
				(width 0.1524)
				(type default)
			)
			(layer "B.SilkS")
		)
		(fp_rect
			(start 0.508 0.9398)
			(end -0.508 -0.9398)
			(stroke
				(width 0)
				(type default)
			)
			(fill no)
			(layer "B.CrtYd")
		)
		(fp_rect
			(start 0.508 0.9398)
			(end -0.508 -0.9398)
			(stroke
				(width 0)
				(type default)
			)
			(fill no)
			(layer "B.Fab")
		)
		(pad "1" smd custom
			(at 0 -0.4445)
			(size 0.1397 0.1397)
			(layers "B.Cu" "B.Mask" "B.Paste")
			(net "SMDAT_USB_HUB_R")
			(options
				(clearance outline)
				(anchor circle)
			)
			(primitives
				(gr_poly
					(pts
						(arc
							(start -0.1778 0.2794)
							(mid -0.249642 0.249642)
							(end -0.2794 0.1778)
						)
						(arc
							(start -0.2794 -0.1778)
							(mid -0.249642 -0.249642)
							(end -0.1778 -0.2794)
						)
						(arc
							(start 0.1778 -0.2794)
							(mid 0.249642 -0.249642)
							(end 0.2794 -0.1778)
						)
						(arc
							(start 0.2794 0.1778)
							(mid 0.249642 0.249642)
							(end 0.1778 0.2794)
						)
					)
					(width 0)
					(fill yes)
				)
			)
		)
		(pad "2" smd custom
			(at 0 0.4445)
			(size 0.1397 0.1397)
			(layers "B.Cu" "B.Mask" "B.Paste")
			(net "SMDAT_USB_HUB")
			(options
				(clearance outline)
				(anchor circle)
			)
			(primitives
				(gr_poly
					(pts
						(arc
							(start -0.1778 0.2794)
							(mid -0.249642 0.249642)
							(end -0.2794 0.1778)
						)
						(arc
							(start -0.2794 -0.1778)
							(mid -0.249642 -0.249642)
							(end -0.1778 -0.2794)
						)
						(arc
							(start 0.1778 -0.2794)
							(mid 0.249642 -0.249642)
							(end 0.2794 -0.1778)
						)
						(arc
							(start 0.2794 0.1778)
							(mid 0.249642 0.249642)
							(end 0.1778 0.2794)
						)
					)
					(width 0)
					(fill yes)
				)
			)
		)
	)
	(footprint ""
		(layer "B.Cu")
		(at 131.318 -0.4699)
		(property "Reference" "R97"
			(at 0 0 0)
			(layer "B.SilkS")
			(hide yes)
			(effects
				(font
					(size 1.27 1.27)
				)
				(justify mirror)
			)
		)
		(property "Value" "10KR2F-2-GP"
			(at -0.064008 -3.993896 0)
			(unlocked yes)
			(layer "B.Fab")
			(hide yes)
			(effects
				(font
					(size 1.016 1.016)
					(thickness 0.1524)
				)
				(justify mirror)
			)
		)
		(property "Device Type" "R402H16"
			(at -0.064008 -5.517896 0)
			(unlocked yes)
			(layer "B.Fab")
			(hide yes)
			(effects
				(font
					(size 1.016 1.016)
					(thickness 0.1524)
				)
				(justify mirror)
			)
		)
		(duplicate_pad_numbers_are_jumpers no)
		(fp_line
			(start -0.508 -0.9398)
			(end 0.508 -0.9398)
			(stroke
				(width 0.1524)
				(type default)
			)
			(layer "B.SilkS")
		)
		(fp_line
			(start 0.508 -0.9398)
			(end 0.508 0.9398)
			(stroke
				(width 0.1524)
				(type default)
			)
			(layer "B.SilkS")
		)
		(fp_rect
			(start 0.508 0.9398)
			(end -0.508 -0.9398)
			(stroke
				(width 0)
				(type default)
			)
			(fill no)
			(layer "B.CrtYd")
		)
		(fp_rect
			(start 0.508 0.9398)
			(end -0.508 -0.9398)
			(stroke
				(width 0)
				(type default)
			)
			(fill no)
			(layer "B.Fab")
		)
		(pad "1" smd custom
			(at 0 -0.4445 180)
			(size 0.1397 0.1397)
			(layers "B.Cu" "B.Mask" "B.Paste")
			(net "PU_P_I2CMUX_INT2_N")
			(options
				(clearance outline)
				(anchor circle)
			)
			(primitives
				(gr_poly
					(pts
						(arc
							(start -0.1778 0.2794)
							(mid -0.249642 0.249642)
							(end -0.2794 0.1778)
						)
						(arc
							(start -0.2794 -0.1778)
							(mid -0.249642 -0.249642)
							(end -0.1778 -0.2794)
						)
						(arc
							(start 0.1778 -0.2794)
							(mid 0.249642 -0.249642)
							(end 0.2794 -0.1778)
						)
						(arc
							(start 0.2794 0.1778)
							(mid 0.249642 0.249642)
							(end 0.1778 0.2794)
						)
					)
					(width 0)
					(fill yes)
				)
			)
		)
		(pad "2" smd custom
			(at 0 0.4445 180)
			(size 0.1397 0.1397)
			(layers "B.Cu" "B.Mask" "B.Paste")
			(net "P3V3_STBY")
			(options
				(clearance outline)
				(anchor circle)
			)
			(primitives
				(gr_poly
					(pts
						(arc
							(start -0.1778 0.2794)
							(mid -0.249642 0.249642)
							(end -0.2794 0.1778)
						)
						(arc
							(start -0.2794 -0.1778)
							(mid -0.249642 -0.249642)
							(end -0.1778 -0.2794)
						)
						(arc
							(start 0.1778 -0.2794)
							(mid 0.249642 -0.249642)
							(end 0.2794 -0.1778)
						)
						(arc
							(start 0.2794 0.1778)
							(mid 0.249642 0.249642)
							(end 0.1778 0.2794)
						)
					)
					(width 0)
					(fill yes)
				)
			)
		)
	)
	(footprint ""
		(layer "B.Cu")
		(at 26.7208 -7.0612)
		(property "Reference" "PR3"
			(at 0 0 0)
			(layer "B.SilkS")
			(hide yes)
			(effects
				(font
					(size 1.27 1.27)
				)
				(justify mirror)
			)
		)
		(property "Value" "10KR2F-2-GP"
			(at -0.064008 -3.993896 0)
			(unlocked yes)
			(layer "B.Fab")
			(hide yes)
			(effects
				(font
					(size 1.016 1.016)
					(thickness 0.1524)
				)
				(justify mirror)
			)
		)
		(property "Device Type" "R402H16"
			(at -0.064008 -5.517896 0)
			(unlocked yes)
			(layer "B.Fab")
			(hide yes)
			(effects
				(font
					(size 1.016 1.016)
					(thickness 0.1524)
				)
				(justify mirror)
			)
		)
		(duplicate_pad_numbers_are_jumpers no)
		(fp_line
			(start -0.508 -0.9398)
			(end 0.508 -0.9398)
			(stroke
				(width 0.1524)
				(type default)
			)
			(layer "B.SilkS")
		)
		(fp_line
			(start 0.508 -0.9398)
			(end 0.508 0.9398)
			(stroke
				(width 0.1524)
				(type default)
			)
			(layer "B.SilkS")
		)
		(fp_rect
			(start 0.508 0.9398)
			(end -0.508 -0.9398)
			(stroke
				(width 0)
				(type default)
			)
			(fill no)
			(layer "B.CrtYd")
		)
		(fp_rect
			(start 0.508 0.9398)
			(end -0.508 -0.9398)
			(stroke
				(width 0)
				(type default)
			)
			(fill no)
			(layer "B.Fab")
		)
		(pad "1" smd custom
			(at 0 -0.4445 180)
			(size 0.1397 0.1397)
			(layers "B.Cu" "B.Mask" "B.Paste")
			(net "P3V3_PG")
			(options
				(clearance outline)
				(anchor circle)
			)
			(primitives
				(gr_poly
					(pts
						(arc
							(start -0.1778 0.2794)
							(mid -0.249642 0.249642)
							(end -0.2794 0.1778)
						)
						(arc
							(start -0.2794 -0.1778)
							(mid -0.249642 -0.249642)
							(end -0.1778 -0.2794)
						)
						(arc
							(start 0.1778 -0.2794)
							(mid 0.249642 -0.249642)
							(end 0.2794 -0.1778)
						)
						(arc
							(start 0.2794 0.1778)
							(mid 0.249642 0.249642)
							(end 0.1778 0.2794)
						)
					)
					(width 0)
					(fill yes)
				)
			)
		)
		(pad "2" smd custom
			(at 0 0.4445 180)
			(size 0.1397 0.1397)
			(layers "B.Cu" "B.Mask" "B.Paste")
			(net "P3V3_VCC")
			(options
				(clearance outline)
				(anchor circle)
			)
			(primitives
				(gr_poly
					(pts
						(arc
							(start -0.1778 0.2794)
							(mid -0.249642 0.249642)
							(end -0.2794 0.1778)
						)
						(arc
							(start -0.2794 -0.1778)
							(mid -0.249642 -0.249642)
							(end -0.1778 -0.2794)
						)
						(arc
							(start 0.1778 -0.2794)
							(mid 0.249642 -0.249642)
							(end 0.2794 -0.1778)
						)
						(arc
							(start 0.2794 0.1778)
							(mid 0.249642 0.249642)
							(end 0.1778 0.2794)
						)
					)
					(width 0)
					(fill yes)
				)
			)
		)
	)
	(footprint ""
		(layer "B.Cu")
		(at 41.6814 -1.5367 180)
		(property "Reference" "R28"
			(at 0 0 0)
			(layer "B.SilkS")
			(hide yes)
			(effects
				(font
					(size 1.27 1.27)
				)
				(justify mirror)
			)
		)
		(property "Value" "0R2F-1-GP"
			(at -0.064008 -3.993896 180)
			(unlocked yes)
			(layer "B.Fab")
			(hide yes)
			(effects
				(font
					(size 1.016 1.016)
					(thickness 0.1524)
				)
				(justify mirror)
			)
		)
		(property "Device Type" "R402H16"
			(at -0.064008 -5.517896 180)
			(unlocked yes)
			(layer "B.Fab")
			(hide yes)
			(effects
				(font
					(size 1.016 1.016)
					(thickness 0.1524)
				)
				(justify mirror)
			)
		)
		(duplicate_pad_numbers_are_jumpers no)
		(fp_line
			(start 0.508 -0.9398)
			(end 0.508 0.9398)
			(stroke
				(width 0.1524)
				(type default)
			)
			(layer "B.SilkS")
		)
		(fp_line
			(start -0.508 -0.9398)
			(end 0.508 -0.9398)
			(stroke
				(width 0.1524)
				(type default)
			)
			(layer "B.SilkS")
		)
		(fp_rect
			(start 0.508 0.9398)
			(end -0.508 -0.9398)
			(stroke
				(width 0)
				(type default)
			)
			(fill no)
			(layer "B.CrtYd")
		)
		(fp_rect
			(start 0.508 0.9398)
			(end -0.508 -0.9398)
			(stroke
				(width 0)
				(type default)
			)
			(fill no)
			(layer "B.Fab")
		)
		(pad "1" smd custom
			(at 0 -0.4445)
			(size 0.1397 0.1397)
			(layers "B.Cu" "B.Mask" "B.Paste")
			(net "SMDAT_BMC_SLOT2")
			(options
				(clearance outline)
				(anchor circle)
			)
			(primitives
				(gr_poly
					(pts
						(arc
							(start -0.1778 0.2794)
							(mid -0.249642 0.249642)
							(end -0.2794 0.1778)
						)
						(arc
							(start -0.2794 -0.1778)
							(mid -0.249642 -0.249642)
							(end -0.1778 -0.2794)
						)
						(arc
							(start 0.1778 -0.2794)
							(mid 0.249642 -0.249642)
							(end 0.2794 -0.1778)
						)
						(arc
							(start 0.2794 0.1778)
							(mid 0.249642 0.249642)
							(end 0.1778 0.2794)
						)
					)
					(width 0)
					(fill yes)
				)
			)
		)
		(pad "2" smd custom
			(at 0 0.4445)
			(size 0.1397 0.1397)
			(layers "B.Cu" "B.Mask" "B.Paste")
			(net "SMDAT_BMC_SLOT2_R")
			(options
				(clearance outline)
				(anchor circle)
			)
			(primitives
				(gr_poly
					(pts
						(arc
							(start -0.1778 0.2794)
							(mid -0.249642 0.249642)
							(end -0.2794 0.1778)
						)
						(arc
							(start -0.2794 -0.1778)
							(mid -0.249642 -0.249642)
							(end -0.1778 -0.2794)
						)
						(arc
							(start 0.1778 -0.2794)
							(mid 0.249642 -0.249642)
							(end 0.2794 -0.1778)
						)
						(arc
							(start 0.2794 0.1778)
							(mid 0.249642 0.249642)
							(end 0.1778 0.2794)
						)
					)
					(width 0)
					(fill yes)
				)
			)
		)
	)
	(footprint ""
		(layer "B.Cu")
		(at 26.8478 -21.0312 90)
		(property "Reference" "R170"
			(at 0 0 90)
			(layer "B.SilkS")
			(hide yes)
			(effects
				(font
					(size 1.27 1.27)
				)
				(justify mirror)
			)
		)
		(property "Value" "0R2F-1-GP"
			(at -0.064008 -3.993896 90)
			(unlocked yes)
			(layer "B.Fab")
			(hide yes)
			(effects
				(font
					(size 1.016 1.016)
					(thickness 0.1524)
				)
				(justify mirror)
			)
		)
		(property "Device Type" "R402H16"
			(at -0.064008 -5.517896 90)
			(unlocked yes)
			(layer "B.Fab")
			(hide yes)
			(effects
				(font
					(size 1.016 1.016)
					(thickness 0.1524)
				)
				(justify mirror)
			)
		)
		(duplicate_pad_numbers_are_jumpers no)
		(fp_line
			(start 0.508 -0.9398)
			(end 0.508 0.9398)
			(stroke
				(width 0.1524)
				(type default)
			)
			(layer "B.SilkS")
		)
		(fp_line
			(start -0.508 -0.9398)
			(end 0.508 -0.9398)
			(stroke
				(width 0.1524)
				(type default)
			)
			(layer "B.SilkS")
		)
		(fp_rect
			(start 0.508 0.9398)
			(end -0.508 -0.9398)
			(stroke
				(width 0)
				(type default)
			)
			(fill no)
			(layer "B.CrtYd")
		)
		(fp_rect
			(start 0.508 0.9398)
			(end -0.508 -0.9398)
			(stroke
				(width 0)
				(type default)
			)
			(fill no)
			(layer "B.Fab")
		)
		(pad "1" smd custom
			(at 0 -0.4445 270)
			(size 0.1397 0.1397)
			(layers "B.Cu" "B.Mask" "B.Paste")
			(net "SMB_VMONITOR_SLOT3_ALERT_N")
			(options
				(clearance outline)
				(anchor circle)
			)
			(primitives
				(gr_poly
					(pts
						(arc
							(start -0.1778 0.2794)
							(mid -0.249642 0.249642)
							(end -0.2794 0.1778)
						)
						(arc
							(start -0.2794 -0.1778)
							(mid -0.249642 -0.249642)
							(end -0.1778 -0.2794)
						)
						(arc
							(start 0.1778 -0.2794)
							(mid 0.249642 -0.249642)
							(end 0.2794 -0.1778)
						)
						(arc
							(start 0.2794 0.1778)
							(mid 0.249642 0.249642)
							(end 0.1778 0.2794)
						)
					)
					(width 0)
					(fill yes)
				)
			)
		)
		(pad "2" smd custom
			(at 0 0.4445 270)
			(size 0.1397 0.1397)
			(layers "B.Cu" "B.Mask" "B.Paste")
			(net "SMB_BMC_DEVICE_ALERT_N")
			(options
				(clearance outline)
				(anchor circle)
			)
			(primitives
				(gr_poly
					(pts
						(arc
							(start -0.1778 0.2794)
							(mid -0.249642 0.249642)
							(end -0.2794 0.1778)
						)
						(arc
							(start -0.2794 -0.1778)
							(mid -0.249642 -0.249642)
							(end -0.1778 -0.2794)
						)
						(arc
							(start 0.1778 -0.2794)
							(mid 0.249642 -0.249642)
							(end 0.2794 -0.1778)
						)
						(arc
							(start 0.2794 0.1778)
							(mid 0.249642 0.249642)
							(end 0.1778 0.2794)
						)
					)
					(width 0)
					(fill yes)
				)
			)
		)
	)
	(footprint ""
		(layer "B.Cu")
		(at 129.032 -24.9936 180)
		(property "Reference" "R169"
			(at 0 0 0)
			(layer "B.SilkS")
			(hide yes)
			(effects
				(font
					(size 1.27 1.27)
				)
				(justify mirror)
			)
		)
		(property "Value" "0R2F-1-GP"
			(at -0.064008 -3.993896 180)
			(unlocked yes)
			(layer "B.Fab")
			(hide yes)
			(effects
				(font
					(size 1.016 1.016)
					(thickness 0.1524)
				)
				(justify mirror)
			)
		)
		(property "Device Type" "R402H16"
			(at -0.064008 -5.517896 180)
			(unlocked yes)
			(layer "B.Fab")
			(hide yes)
			(effects
				(font
					(size 1.016 1.016)
					(thickness 0.1524)
				)
				(justify mirror)
			)
		)
		(duplicate_pad_numbers_are_jumpers no)
		(fp_line
			(start 0.508 -0.9398)
			(end 0.508 0.9398)
			(stroke
				(width 0.1524)
				(type default)
			)
			(layer "B.SilkS")
		)
		(fp_line
			(start -0.508 -0.9398)
			(end 0.508 -0.9398)
			(stroke
				(width 0.1524)
				(type default)
			)
			(layer "B.SilkS")
		)
		(fp_rect
			(start 0.508 0.9398)
			(end -0.508 -0.9398)
			(stroke
				(width 0)
				(type default)
			)
			(fill no)
			(layer "B.CrtYd")
		)
		(fp_rect
			(start 0.508 0.9398)
			(end -0.508 -0.9398)
			(stroke
				(width 0)
				(type default)
			)
			(fill no)
			(layer "B.Fab")
		)
		(pad "1" smd custom
			(at 0 -0.4445)
			(size 0.1397 0.1397)
			(layers "B.Cu" "B.Mask" "B.Paste")
			(net "SMDAT_USB_HUB")
			(options
				(clearance outline)
				(anchor circle)
			)
			(primitives
				(gr_poly
					(pts
						(arc
							(start -0.1778 0.2794)
							(mid -0.249642 0.249642)
							(end -0.2794 0.1778)
						)
						(arc
							(start -0.2794 -0.1778)
							(mid -0.249642 -0.249642)
							(end -0.1778 -0.2794)
						)
						(arc
							(start 0.1778 -0.2794)
							(mid 0.249642 -0.249642)
							(end 0.2794 -0.1778)
						)
						(arc
							(start 0.2794 0.1778)
							(mid 0.249642 0.249642)
							(end 0.1778 0.2794)
						)
					)
					(width 0)
					(fill yes)
				)
			)
		)
		(pad "2" smd custom
			(at 0 0.4445)
			(size 0.1397 0.1397)
			(layers "B.Cu" "B.Mask" "B.Paste")
			(net "SMDAT_PCH_DEVICE")
			(options
				(clearance outline)
				(anchor circle)
			)
			(primitives
				(gr_poly
					(pts
						(arc
							(start -0.1778 0.2794)
							(mid -0.249642 0.249642)
							(end -0.2794 0.1778)
						)
						(arc
							(start -0.2794 -0.1778)
							(mid -0.249642 -0.249642)
							(end -0.1778 -0.2794)
						)
						(arc
							(start 0.1778 -0.2794)
							(mid 0.249642 -0.249642)
							(end 0.2794 -0.1778)
						)
						(arc
							(start 0.2794 0.1778)
							(mid 0.249642 0.249642)
							(end 0.1778 0.2794)
						)
					)
					(width 0)
					(fill yes)
				)
			)
		)
	)
	(footprint ""
		(layer "B.Cu")
		(at 123.2916 -2.921)
		(property "Reference" "C59"
			(at 0 0 0)
			(layer "B.SilkS")
			(hide yes)
			(effects
				(font
					(size 1.27 1.27)
				)
				(justify mirror)
			)
		)
		(property "Value" "SCD1U16V2KX-3GP"
			(at -1.1811 -2.7051 0)
			(unlocked yes)
			(layer "B.Fab")
			(hide yes)
			(effects
				(font
					(size 1.016 1.016)
					(thickness 0.1524)
				)
				(justify mirror)
			)
		)
		(property "Device Type" "C402H22"
			(at -1.1811 -4.2291 0)
			(unlocked yes)
			(layer "B.Fab")
			(hide yes)
			(effects
				(font
					(size 1.016 1.016)
					(thickness 0.1524)
				)
				(justify mirror)
			)
		)
		(duplicate_pad_numbers_are_jumpers no)
		(fp_rect
			(start 0.4318 0.9525)
			(end -0.4318 -0.9525)
			(stroke
				(width 0)
				(type default)
			)
			(fill no)
			(layer "B.CrtYd")
		)
		(fp_rect
			(start 0.4318 0.9525)
			(end -0.4318 -0.9525)
			(stroke
				(width 0)
				(type default)
			)
			(fill no)
			(layer "B.Fab")
		)
		(pad "1" smd custom
			(at 0 -0.4445 180)
			(size 0.1524 0.1524)
			(layers "B.Cu" "B.Mask" "B.Paste")
			(net "P3V3_STBY")
			(options
				(clearance outline)
				(anchor circle)
			)
			(primitives
				(gr_poly
					(pts
						(arc
							(start 0.3048 0.2032)
							(mid 0.275042 0.275042)
							(end 0.2032 0.3048)
						)
						(arc
							(start -0.2032 0.3048)
							(mid -0.275042 0.275042)
							(end -0.3048 0.2032)
						)
						(arc
							(start -0.3048 -0.2032)
							(mid -0.275042 -0.275042)
							(end -0.2032 -0.3048)
						)
						(arc
							(start 0.2032 -0.3048)
							(mid 0.275042 -0.275042)
							(end 0.3048 -0.2032)
						)
					)
					(width 0)
					(fill yes)
				)
			)
		)
		(pad "2" smd custom
			(at 0 0.4445 180)
			(size 0.1524 0.1524)
			(layers "B.Cu" "B.Mask" "B.Paste")
			(net "GND")
			(options
				(clearance outline)
				(anchor circle)
			)
			(primitives
				(gr_poly
					(pts
						(arc
							(start 0.3048 0.2032)
							(mid 0.275042 0.275042)
							(end 0.2032 0.3048)
						)
						(arc
							(start -0.2032 0.3048)
							(mid -0.275042 0.275042)
							(end -0.3048 0.2032)
						)
						(arc
							(start -0.3048 -0.2032)
							(mid -0.275042 -0.275042)
							(end -0.2032 -0.3048)
						)
						(arc
							(start 0.2032 -0.3048)
							(mid 0.275042 -0.275042)
							(end 0.3048 -0.2032)
						)
					)
					(width 0)
					(fill yes)
				)
			)
		)
	)
	(footprint ""
		(layer "B.Cu")
		(at 17.2339 -28.8544 -135)
		(property "Reference" "R109"
			(at 0 0 45)
			(layer "B.SilkS")
			(hide yes)
			(effects
				(font
					(size 1.27 1.27)
				)
				(justify mirror)
			)
		)
		(property "Value" "D001R6F-L-GP"
			(at 0.126442 -3.733916 225)
			(unlocked yes)
			(layer "B.Fab")
			(hide yes)
			(effects
				(font
					(size 1.016 1.016)
					(thickness 0.1524)
				)
				(justify mirror)
			)
		)
		(property "Device Type" "R1206H36"
			(at 0.126801 -5.257685 225)
			(unlocked yes)
			(layer "B.Fab")
			(hide yes)
			(effects
				(font
					(size 1.016 1.016)
					(thickness 0.1524)
				)
				(justify mirror)
			)
		)
		(duplicate_pad_numbers_are_jumpers no)
		(fp_line
			(start 1.016026 2.235186)
			(end 1.016026 -2.235186)
			(stroke
				(width 0.1524)
				(type default)
			)
			(layer "B.SilkS")
		)
		(fp_line
			(start -1.016206 2.235365)
			(end 1.016026 2.235186)
			(stroke
				(width 0.1524)
				(type default)
			)
			(layer "B.SilkS")
		)
		(fp_line
			(start 1.016026 -2.235186)
			(end -1.016385 -2.235186)
			(stroke
				(width 0.1524)
				(type default)
			)
			(layer "B.SilkS")
		)
		(fp_line
			(start -1.016385 -2.235186)
			(end -1.016206 2.235365)
			(stroke
				(width 0.1524)
				(type default)
			)
			(layer "B.SilkS")
		)
		(fp_poly
			(pts
				(xy -0.800059 1.600102) (xy -0.80006 -1.600298) (xy 0.800141 -1.600299) (xy 0.800141 1.600102)
			)
			(stroke
				(width 0)
				(type default)
			)
			(fill no)
			(layer "B.CrtYd")
		)
		(fp_poly
			(pts
				(xy 1.091999 2.311518) (xy 1.09164 -2.311518) (xy -1.092179 -2.311338) (xy -1.092179 1.58753) (xy -0.8005 1.58753)
				(xy -0.80032 -1.600282) (xy 0.800141 -1.600102) (xy 0.800141 1.600102) (xy -1.092179 1.600102) (xy -1.092179 2.311338)
			)
			(stroke
				(width 0)
				(type default)
			)
			(fill no)
			(layer "B.CrtYd")
		)
		(fp_poly
			(pts
				(xy -1.092401 2.311518) (xy -1.092401 -2.311282) (xy 1.091999 -2.311282) (xy 1.091999 2.311518)
			)
			(stroke
				(width 0)
				(type default)
			)
			(fill no)
			(layer "B.Fab")
		)
		(pad "1" smd rect
			(at 0 -1.397 45)
			(size 1.651 1.27)
			(layers "B.Cu" "B.Mask" "B.Paste")
			(net "P12V")
		)
		(pad "2" smd rect
			(at 0 1.397 45)
			(size 1.651 1.27)
			(layers "B.Cu" "B.Mask" "B.Paste")
			(net "P12V_ATX")
		)
	)
	(footprint ""
		(layer "B.Cu")
		(at 130.3528 -10.4394 -90)
		(property "Reference" "R21"
			(at 0 0 90)
			(layer "B.SilkS")
			(hide yes)
			(effects
				(font
					(size 1.27 1.27)
				)
				(justify mirror)
			)
		)
		(property "Value" "4K7R2F-GP"
			(at -0.064008 -3.993896 270)
			(unlocked yes)
			(layer "B.Fab")
			(hide yes)
			(effects
				(font
					(size 1.016 1.016)
					(thickness 0.1524)
				)
				(justify mirror)
			)
		)
		(property "Device Type" "R402H16"
			(at -0.064008 -5.517896 270)
			(unlocked yes)
			(layer "B.Fab")
			(hide yes)
			(effects
				(font
					(size 1.016 1.016)
					(thickness 0.1524)
				)
				(justify mirror)
			)
		)
		(duplicate_pad_numbers_are_jumpers no)
		(fp_line
			(start -0.508 -0.9398)
			(end 0.508 -0.9398)
			(stroke
				(width 0.1524)
				(type default)
			)
			(layer "B.SilkS")
		)
		(fp_line
			(start 0.508 -0.9398)
			(end 0.508 0.9398)
			(stroke
				(width 0.1524)
				(type default)
			)
			(layer "B.SilkS")
		)
		(fp_rect
			(start 0.508 0.9398)
			(end -0.508 -0.9398)
			(stroke
				(width 0)
				(type default)
			)
			(fill no)
			(layer "B.CrtYd")
		)
		(fp_rect
			(start 0.508 0.9398)
			(end -0.508 -0.9398)
			(stroke
				(width 0)
				(type default)
			)
			(fill no)
			(layer "B.Fab")
		)
		(pad "1" smd custom
			(at 0 -0.4445 90)
			(size 0.1397 0.1397)
			(layers "B.Cu" "B.Mask" "B.Paste")
			(net "P3V3_STBY")
			(options
				(clearance outline)
				(anchor circle)
			)
			(primitives
				(gr_poly
					(pts
						(arc
							(start -0.1778 0.2794)
							(mid -0.249642 0.249642)
							(end -0.2794 0.1778)
						)
						(arc
							(start -0.2794 -0.1778)
							(mid -0.249642 -0.249642)
							(end -0.1778 -0.2794)
						)
						(arc
							(start 0.1778 -0.2794)
							(mid 0.249642 -0.249642)
							(end 0.2794 -0.1778)
						)
						(arc
							(start 0.2794 0.1778)
							(mid 0.249642 0.249642)
							(end 0.1778 0.2794)
						)
					)
					(width 0)
					(fill yes)
				)
			)
		)
		(pad "2" smd custom
			(at 0 0.4445 90)
			(size 0.1397 0.1397)
			(layers "B.Cu" "B.Mask" "B.Paste")
			(net "SMCLK_PCH_SLOT3")
			(options
				(clearance outline)
				(anchor circle)
			)
			(primitives
				(gr_poly
					(pts
						(arc
							(start -0.1778 0.2794)
							(mid -0.249642 0.249642)
							(end -0.2794 0.1778)
						)
						(arc
							(start -0.2794 -0.1778)
							(mid -0.249642 -0.249642)
							(end -0.1778 -0.2794)
						)
						(arc
							(start 0.1778 -0.2794)
							(mid 0.249642 -0.249642)
							(end 0.2794 -0.1778)
						)
						(arc
							(start 0.2794 0.1778)
							(mid 0.249642 0.249642)
							(end 0.1778 0.2794)
						)
					)
					(width 0)
					(fill yes)
				)
			)
		)
	)
	(footprint ""
		(layer "B.Cu")
		(at 109.6772 0.0508 -90)
		(property "Reference" "U1"
			(at 0 0 90)
			(layer "B.SilkS")
			(hide yes)
			(effects
				(font
					(size 1.27 1.27)
				)
				(justify mirror)
			)
		)
		(property "Value" "PCA9544APW-GP"
			(at 0 -11.8872 270)
			(unlocked yes)
			(layer "B.Fab")
			(hide yes)
			(effects
				(font
					(size 1.016 1.016)
					(thickness 0.1524)
				)
				(justify mirror)
			)
		)
		(property "Device Type" "TSOIC20H44"
			(at 0 -13.7922 270)
			(unlocked yes)
			(layer "B.Fab")
			(hide yes)
			(effects
				(font
					(size 1.016 1.016)
					(thickness 0.1524)
				)
				(justify mirror)
			)
		)
		(duplicate_pad_numbers_are_jumpers no)
		(fp_line
			(start 3.556 3.6322)
			(end 3.556 1.397)
			(stroke
				(width 0.508)
				(type default)
			)
			(layer "B.SilkS")
		)
		(fp_line
			(start -3.175 1.397)
			(end 3.556 1.397)
			(stroke
				(width 0.2032)
				(type default)
			)
			(layer "B.SilkS")
		)
		(fp_line
			(start 3.556 1.397)
			(end 3.556 1.778)
			(stroke
				(width 0.2032)
				(type default)
			)
			(layer "B.SilkS")
		)
		(fp_line
			(start 2.667 0)
			(end 3.556 0.889)
			(stroke
				(width 0.2032)
				(type default)
			)
			(layer "B.SilkS")
		)
		(fp_line
			(start 2.667 0)
			(end 3.556 -0.889)
			(stroke
				(width 0.2032)
				(type default)
			)
			(layer "B.SilkS")
		)
		(fp_line
			(start -3.175 -1.397)
			(end -3.175 1.397)
			(stroke
				(width 0.2032)
				(type default)
			)
			(layer "B.SilkS")
		)
		(fp_line
			(start 3.556 -1.397)
			(end 3.556 3.7084)
			(stroke
				(width 0.2032)
				(type default)
			)
			(layer "B.SilkS")
		)
		(fp_line
			(start 3.556 -1.397)
			(end -3.175 -1.397)
			(stroke
				(width 0.2032)
				(type default)
			)
			(layer "B.SilkS")
		)
		(fp_poly
			(pts
				(xy 3.25628 -1.8542) (xy -3.25628 -1.8542) (xy -3.25628 1.8542) (xy 3.25628 1.8542)
			)
			(stroke
				(width 0)
				(type default)
			)
			(fill yes)
			(layer "B.SilkS")
		)
		(fp_rect
			(start 3.556 3.81)
			(end -3.556 -3.81)
			(stroke
				(width 0)
				(type default)
			)
			(fill no)
			(layer "B.CrtYd")
		)
		(fp_poly
			(pts
				(xy 3.556 -3.81) (xy -3.556 -3.81) (xy -3.556 3.81) (xy 3.556 3.81)
			)
			(stroke
				(width 0)
				(type default)
			)
			(fill no)
			(layer "B.Fab")
		)
		(pad "1" smd rect
			(at 2.92608 2.8194 90)
			(size 0.3556 1.524)
			(layers "B.Cu" "B.Mask" "B.Paste")
			(net "SMB_B_HUB_A0")
		)
		(pad "2" smd rect
			(at 2.27584 2.8194 90)
			(size 0.3556 1.524)
			(layers "B.Cu" "B.Mask" "B.Paste")
			(net "SMB_B_HUB_A1")
		)
		(pad "3" smd rect
			(at 1.6256 2.8194 90)
			(size 0.3556 1.524)
			(layers "B.Cu" "B.Mask" "B.Paste")
			(net "SMB_B_HUB_A2")
		)
		(pad "4" smd rect
			(at 0.97536 2.8194 90)
			(size 0.3556 1.524)
			(layers "B.Cu" "B.Mask" "B.Paste")
			(net "SMB_PCIE_SLOT2_ALERT_N")
		)
		(pad "5" smd rect
			(at 0.32512 2.8194 90)
			(size 0.3556 1.524)
			(layers "B.Cu" "B.Mask" "B.Paste")
			(net "SMDAT_BMC_SLOT2")
		)
		(pad "6" smd rect
			(at -0.32512 2.8194 90)
			(size 0.3556 1.524)
			(layers "B.Cu" "B.Mask" "B.Paste")
			(net "SMCLK_BMC_SLOT2")
		)
		(pad "7" smd rect
			(at -0.97536 2.8194 90)
			(size 0.3556 1.524)
			(layers "B.Cu" "B.Mask" "B.Paste")
			(net "SMB_PCIE_SLOT3_ALERT_N")
		)
		(pad "8" smd rect
			(at -1.6256 2.8194 90)
			(size 0.3556 1.524)
			(layers "B.Cu" "B.Mask" "B.Paste")
			(net "SMDAT_BMC_SLOT3")
		)
		(pad "9" smd rect
			(at -2.27584 2.8194 90)
			(size 0.3556 1.524)
			(layers "B.Cu" "B.Mask" "B.Paste")
			(net "SMCLK_BMC_SLOT3")
		)
		(pad "10" smd rect
			(at -2.92608 2.8194 90)
			(size 0.3556 1.524)
			(layers "B.Cu" "B.Mask" "B.Paste")
			(net "GND")
		)
		(pad "11" smd rect
			(at -2.92608 -2.8194 90)
			(size 0.3556 1.524)
			(layers "B.Cu" "B.Mask" "B.Paste")
			(net "PU_I2CMUX_INT2_N")
		)
		(pad "12" smd rect
			(at -2.27584 -2.8194 90)
			(size 0.3556 1.524)
			(layers "B.Cu" "B.Mask" "B.Paste")
			(net "PU_B_MUX_SDA2")
		)
		(pad "13" smd rect
			(at -1.6256 -2.8194 90)
			(size 0.3556 1.524)
			(layers "B.Cu" "B.Mask" "B.Paste")
			(net "PU_B_MUX_SCL2")
		)
		(pad "14" smd rect
			(at -0.97536 -2.8194 90)
			(size 0.3556 1.524)
			(layers "B.Cu" "B.Mask" "B.Paste")
			(net "SMB_BMC_DEVICE_ALERT_N")
		)
		(pad "15" smd rect
			(at -0.32512 -2.8194 90)
			(size 0.3556 1.524)
			(layers "B.Cu" "B.Mask" "B.Paste")
			(net "SMDAT_BMC_DEVICE")
		)
		(pad "16" smd rect
			(at 0.32512 -2.8194 90)
			(size 0.3556 1.524)
			(layers "B.Cu" "B.Mask" "B.Paste")
			(net "SMCLK_BMC_DEVICE")
		)
		(pad "17" smd rect
			(at 0.97536 -2.8194 90)
			(size 0.3556 1.524)
			(layers "B.Cu" "B.Mask" "B.Paste")
			(net "IRQ_OOB_MGMT_RISER_ALERT_N")
		)
		(pad "18" smd rect
			(at 1.6256 -2.8194 90)
			(size 0.3556 1.524)
			(layers "B.Cu" "B.Mask" "B.Paste")
			(net "SMCLK_BMC_R")
		)
		(pad "19" smd rect
			(at 2.27584 -2.8194 90)
			(size 0.3556 1.524)
			(layers "B.Cu" "B.Mask" "B.Paste")
			(net "SMDAT_BMC_R")
		)
		(pad "20" smd rect
			(at 2.92608 -2.8194 90)
			(size 0.3556 1.524)
			(layers "B.Cu" "B.Mask" "B.Paste")
			(net "P3V3_STBY")
		)
	)
	(footprint ""
		(layer "B.Cu")
		(at 27.051 -33.2486 -90)
		(property "Reference" "R61"
			(at 0 0 90)
			(layer "B.SilkS")
			(hide yes)
			(effects
				(font
					(size 1.27 1.27)
				)
				(justify mirror)
			)
		)
		(property "Value" "0R2F-1-GP"
			(at -0.064008 -3.993896 270)
			(unlocked yes)
			(layer "B.Fab")
			(hide yes)
			(effects
				(font
					(size 1.016 1.016)
					(thickness 0.1524)
				)
				(justify mirror)
			)
		)
		(property "Device Type" "R402H16"
			(at -0.064008 -5.517896 270)
			(unlocked yes)
			(layer "B.Fab")
			(hide yes)
			(effects
				(font
					(size 1.016 1.016)
					(thickness 0.1524)
				)
				(justify mirror)
			)
		)
		(duplicate_pad_numbers_are_jumpers no)
		(fp_line
			(start -0.508 -0.9398)
			(end 0.508 -0.9398)
			(stroke
				(width 0.1524)
				(type default)
			)
			(layer "B.SilkS")
		)
		(fp_line
			(start 0.508 -0.9398)
			(end 0.508 0.9398)
			(stroke
				(width 0.1524)
				(type default)
			)
			(layer "B.SilkS")
		)
		(fp_rect
			(start 0.508 0.9398)
			(end -0.508 -0.9398)
			(stroke
				(width 0)
				(type default)
			)
			(fill no)
			(layer "B.CrtYd")
		)
		(fp_rect
			(start 0.508 0.9398)
			(end -0.508 -0.9398)
			(stroke
				(width 0)
				(type default)
			)
			(fill no)
			(layer "B.Fab")
		)
		(pad "1" smd custom
			(at 0 -0.4445 90)
			(size 0.1397 0.1397)
			(layers "B.Cu" "B.Mask" "B.Paste")
			(net "PD_SLOT3_PRSNT1")
			(options
				(clearance outline)
				(anchor circle)
			)
			(primitives
				(gr_poly
					(pts
						(arc
							(start -0.1778 0.2794)
							(mid -0.249642 0.249642)
							(end -0.2794 0.1778)
						)
						(arc
							(start -0.2794 -0.1778)
							(mid -0.249642 -0.249642)
							(end -0.1778 -0.2794)
						)
						(arc
							(start 0.1778 -0.2794)
							(mid 0.249642 -0.249642)
							(end 0.2794 -0.1778)
						)
						(arc
							(start 0.2794 0.1778)
							(mid 0.249642 0.249642)
							(end 0.1778 0.2794)
						)
					)
					(width 0)
					(fill yes)
				)
			)
		)
		(pad "2" smd custom
			(at 0 0.4445 90)
			(size 0.1397 0.1397)
			(layers "B.Cu" "B.Mask" "B.Paste")
			(net "GND")
			(options
				(clearance outline)
				(anchor circle)
			)
			(primitives
				(gr_poly
					(pts
						(arc
							(start -0.1778 0.2794)
							(mid -0.249642 0.249642)
							(end -0.2794 0.1778)
						)
						(arc
							(start -0.2794 -0.1778)
							(mid -0.249642 -0.249642)
							(end -0.1778 -0.2794)
						)
						(arc
							(start 0.1778 -0.2794)
							(mid 0.249642 -0.249642)
							(end 0.2794 -0.1778)
						)
						(arc
							(start 0.2794 0.1778)
							(mid 0.249642 0.249642)
							(end 0.1778 0.2794)
						)
					)
					(width 0)
					(fill yes)
				)
			)
		)
	)
	(footprint ""
		(layer "B.Cu")
		(at 125.6284 -11.7094)
		(property "Reference" "R53"
			(at 0 0 0)
			(layer "B.SilkS")
			(hide yes)
			(effects
				(font
					(size 1.27 1.27)
				)
				(justify mirror)
			)
		)
		(property "Value" "10KR2F-2-GP"
			(at -0.064008 -3.993896 0)
			(unlocked yes)
			(layer "B.Fab")
			(hide yes)
			(effects
				(font
					(size 1.016 1.016)
					(thickness 0.1524)
				)
				(justify mirror)
			)
		)
		(property "Device Type" "R402H16"
			(at -0.064008 -5.517896 0)
			(unlocked yes)
			(layer "B.Fab")
			(hide yes)
			(effects
				(font
					(size 1.016 1.016)
					(thickness 0.1524)
				)
				(justify mirror)
			)
		)
		(duplicate_pad_numbers_are_jumpers no)
		(fp_line
			(start -0.508 -0.9398)
			(end 0.508 -0.9398)
			(stroke
				(width 0.1524)
				(type default)
			)
			(layer "B.SilkS")
		)
		(fp_line
			(start 0.508 -0.9398)
			(end 0.508 0.9398)
			(stroke
				(width 0.1524)
				(type default)
			)
			(layer "B.SilkS")
		)
		(fp_rect
			(start 0.508 0.9398)
			(end -0.508 -0.9398)
			(stroke
				(width 0)
				(type default)
			)
			(fill no)
			(layer "B.CrtYd")
		)
		(fp_rect
			(start 0.508 0.9398)
			(end -0.508 -0.9398)
			(stroke
				(width 0)
				(type default)
			)
			(fill no)
			(layer "B.Fab")
		)
		(pad "1" smd custom
			(at 0 -0.4445 180)
			(size 0.1397 0.1397)
			(layers "B.Cu" "B.Mask" "B.Paste")
			(net "P3V3_STBY")
			(options
				(clearance outline)
				(anchor circle)
			)
			(primitives
				(gr_poly
					(pts
						(arc
							(start -0.1778 0.2794)
							(mid -0.249642 0.249642)
							(end -0.2794 0.1778)
						)
						(arc
							(start -0.2794 -0.1778)
							(mid -0.249642 -0.249642)
							(end -0.1778 -0.2794)
						)
						(arc
							(start 0.1778 -0.2794)
							(mid 0.249642 -0.249642)
							(end 0.2794 -0.1778)
						)
						(arc
							(start 0.2794 0.1778)
							(mid 0.249642 0.249642)
							(end 0.1778 0.2794)
						)
					)
					(width 0)
					(fill yes)
				)
			)
		)
		(pad "2" smd custom
			(at 0 0.4445 180)
			(size 0.1397 0.1397)
			(layers "B.Cu" "B.Mask" "B.Paste")
			(net "SMB_P_HUB_A2")
			(options
				(clearance outline)
				(anchor circle)
			)
			(primitives
				(gr_poly
					(pts
						(arc
							(start -0.1778 0.2794)
							(mid -0.249642 0.249642)
							(end -0.2794 0.1778)
						)
						(arc
							(start -0.2794 -0.1778)
							(mid -0.249642 -0.249642)
							(end -0.1778 -0.2794)
						)
						(arc
							(start 0.1778 -0.2794)
							(mid 0.249642 -0.249642)
							(end 0.2794 -0.1778)
						)
						(arc
							(start 0.2794 0.1778)
							(mid 0.249642 0.249642)
							(end 0.1778 0.2794)
						)
					)
					(width 0)
					(fill yes)
				)
			)
		)
	)
	(footprint ""
		(layer "B.Cu")
		(at 123.444 -11.5316 180)
		(property "Reference" "R110"
			(at 0 0 0)
			(layer "B.SilkS")
			(hide yes)
			(effects
				(font
					(size 1.27 1.27)
				)
				(justify mirror)
			)
		)
		(property "Value" "10KR2F-2-GP"
			(at -0.064008 -3.993896 180)
			(unlocked yes)
			(layer "B.Fab")
			(hide yes)
			(effects
				(font
					(size 1.016 1.016)
					(thickness 0.1524)
				)
				(justify mirror)
			)
		)
		(property "Device Type" "R402H16"
			(at -0.064008 -5.517896 180)
			(unlocked yes)
			(layer "B.Fab")
			(hide yes)
			(effects
				(font
					(size 1.016 1.016)
					(thickness 0.1524)
				)
				(justify mirror)
			)
		)
		(duplicate_pad_numbers_are_jumpers no)
		(fp_line
			(start 0.508 -0.9398)
			(end 0.508 0.9398)
			(stroke
				(width 0.1524)
				(type default)
			)
			(layer "B.SilkS")
		)
		(fp_line
			(start -0.508 -0.9398)
			(end 0.508 -0.9398)
			(stroke
				(width 0.1524)
				(type default)
			)
			(layer "B.SilkS")
		)
		(fp_rect
			(start 0.508 0.9398)
			(end -0.508 -0.9398)
			(stroke
				(width 0)
				(type default)
			)
			(fill no)
			(layer "B.CrtYd")
		)
		(fp_rect
			(start 0.508 0.9398)
			(end -0.508 -0.9398)
			(stroke
				(width 0)
				(type default)
			)
			(fill no)
			(layer "B.Fab")
		)
		(pad "1" smd custom
			(at 0 -0.4445)
			(size 0.1397 0.1397)
			(layers "B.Cu" "B.Mask" "B.Paste")
			(net "SMB_P_HUB_A0")
			(options
				(clearance outline)
				(anchor circle)
			)
			(primitives
				(gr_poly
					(pts
						(arc
							(start -0.1778 0.2794)
							(mid -0.249642 0.249642)
							(end -0.2794 0.1778)
						)
						(arc
							(start -0.2794 -0.1778)
							(mid -0.249642 -0.249642)
							(end -0.1778 -0.2794)
						)
						(arc
							(start 0.1778 -0.2794)
							(mid 0.249642 -0.249642)
							(end 0.2794 -0.1778)
						)
						(arc
							(start 0.2794 0.1778)
							(mid 0.249642 0.249642)
							(end 0.1778 0.2794)
						)
					)
					(width 0)
					(fill yes)
				)
			)
		)
		(pad "2" smd custom
			(at 0 0.4445)
			(size 0.1397 0.1397)
			(layers "B.Cu" "B.Mask" "B.Paste")
			(net "GND")
			(options
				(clearance outline)
				(anchor circle)
			)
			(primitives
				(gr_poly
					(pts
						(arc
							(start -0.1778 0.2794)
							(mid -0.249642 0.249642)
							(end -0.2794 0.1778)
						)
						(arc
							(start -0.2794 -0.1778)
							(mid -0.249642 -0.249642)
							(end -0.1778 -0.2794)
						)
						(arc
							(start 0.1778 -0.2794)
							(mid 0.249642 -0.249642)
							(end 0.2794 -0.1778)
						)
						(arc
							(start 0.2794 0.1778)
							(mid 0.249642 0.249642)
							(end 0.1778 0.2794)
						)
					)
					(width 0)
					(fill yes)
				)
			)
		)
	)
	(footprint ""
		(layer "B.Cu")
		(at 125.1966 -30.6578)
		(property "Reference" "CU5"
			(at 0 0 0)
			(layer "B.SilkS")
			(hide yes)
			(effects
				(font
					(size 1.27 1.27)
				)
				(justify mirror)
			)
		)
		(property "Value" "SC1U10V2KX-4-GP"
			(at -1.1811 -2.7051 0)
			(unlocked yes)
			(layer "B.Fab")
			(hide yes)
			(effects
				(font
					(size 1.016 1.016)
					(thickness 0.1524)
				)
				(justify mirror)
			)
		)
		(property "Device Type" "C402H22"
			(at -1.1811 -4.2291 0)
			(unlocked yes)
			(layer "B.Fab")
			(hide yes)
			(effects
				(font
					(size 1.016 1.016)
					(thickness 0.1524)
				)
				(justify mirror)
			)
		)
		(duplicate_pad_numbers_are_jumpers no)
		(fp_rect
			(start 0.4318 0.9525)
			(end -0.4318 -0.9525)
			(stroke
				(width 0)
				(type default)
			)
			(fill no)
			(layer "B.CrtYd")
		)
		(fp_rect
			(start 0.4318 0.9525)
			(end -0.4318 -0.9525)
			(stroke
				(width 0)
				(type default)
			)
			(fill no)
			(layer "B.Fab")
		)
		(pad "1" smd custom
			(at 0 -0.4445 180)
			(size 0.1524 0.1524)
			(layers "B.Cu" "B.Mask" "B.Paste")
			(net "P3V3_USB_HUB")
			(options
				(clearance outline)
				(anchor circle)
			)
			(primitives
				(gr_poly
					(pts
						(arc
							(start 0.3048 0.2032)
							(mid 0.275042 0.275042)
							(end 0.2032 0.3048)
						)
						(arc
							(start -0.2032 0.3048)
							(mid -0.275042 0.275042)
							(end -0.3048 0.2032)
						)
						(arc
							(start -0.3048 -0.2032)
							(mid -0.275042 -0.275042)
							(end -0.2032 -0.3048)
						)
						(arc
							(start 0.2032 -0.3048)
							(mid 0.275042 -0.275042)
							(end 0.3048 -0.2032)
						)
					)
					(width 0)
					(fill yes)
				)
			)
		)
		(pad "2" smd custom
			(at 0 0.4445 180)
			(size 0.1524 0.1524)
			(layers "B.Cu" "B.Mask" "B.Paste")
			(net "GND")
			(options
				(clearance outline)
				(anchor circle)
			)
			(primitives
				(gr_poly
					(pts
						(arc
							(start 0.3048 0.2032)
							(mid 0.275042 0.275042)
							(end 0.2032 0.3048)
						)
						(arc
							(start -0.2032 0.3048)
							(mid -0.275042 0.275042)
							(end -0.3048 0.2032)
						)
						(arc
							(start -0.3048 -0.2032)
							(mid -0.275042 -0.275042)
							(end -0.2032 -0.3048)
						)
						(arc
							(start 0.2032 -0.3048)
							(mid 0.275042 -0.275042)
							(end 0.3048 -0.2032)
						)
					)
					(width 0)
					(fill yes)
				)
			)
		)
	)
	(footprint ""
		(layer "B.Cu")
		(at 103.886 -2.0828)
		(property "Reference" "R5"
			(at 0 0 0)
			(layer "B.SilkS")
			(hide yes)
			(effects
				(font
					(size 1.27 1.27)
				)
				(justify mirror)
			)
		)
		(property "Value" "4K7R2F-GP"
			(at -0.064008 -3.993896 0)
			(unlocked yes)
			(layer "B.Fab")
			(hide yes)
			(effects
				(font
					(size 1.016 1.016)
					(thickness 0.1524)
				)
				(justify mirror)
			)
		)
		(property "Device Type" "R402H16"
			(at -0.064008 -5.517896 0)
			(unlocked yes)
			(layer "B.Fab")
			(hide yes)
			(effects
				(font
					(size 1.016 1.016)
					(thickness 0.1524)
				)
				(justify mirror)
			)
		)
		(duplicate_pad_numbers_are_jumpers no)
		(fp_line
			(start -0.508 -0.9398)
			(end 0.508 -0.9398)
			(stroke
				(width 0.1524)
				(type default)
			)
			(layer "B.SilkS")
		)
		(fp_line
			(start 0.508 -0.9398)
			(end 0.508 0.9398)
			(stroke
				(width 0.1524)
				(type default)
			)
			(layer "B.SilkS")
		)
		(fp_rect
			(start 0.508 0.9398)
			(end -0.508 -0.9398)
			(stroke
				(width 0)
				(type default)
			)
			(fill no)
			(layer "B.CrtYd")
		)
		(fp_rect
			(start 0.508 0.9398)
			(end -0.508 -0.9398)
			(stroke
				(width 0)
				(type default)
			)
			(fill no)
			(layer "B.Fab")
		)
		(pad "1" smd custom
			(at 0 -0.4445 180)
			(size 0.1397 0.1397)
			(layers "B.Cu" "B.Mask" "B.Paste")
			(net "P3V3_STBY")
			(options
				(clearance outline)
				(anchor circle)
			)
			(primitives
				(gr_poly
					(pts
						(arc
							(start -0.1778 0.2794)
							(mid -0.249642 0.249642)
							(end -0.2794 0.1778)
						)
						(arc
							(start -0.2794 -0.1778)
							(mid -0.249642 -0.249642)
							(end -0.1778 -0.2794)
						)
						(arc
							(start 0.1778 -0.2794)
							(mid 0.249642 -0.249642)
							(end 0.2794 -0.1778)
						)
						(arc
							(start 0.2794 0.1778)
							(mid 0.249642 0.249642)
							(end 0.1778 0.2794)
						)
					)
					(width 0)
					(fill yes)
				)
			)
		)
		(pad "2" smd custom
			(at 0 0.4445 180)
			(size 0.1397 0.1397)
			(layers "B.Cu" "B.Mask" "B.Paste")
			(net "SMCLK_BMC_SLOT3")
			(options
				(clearance outline)
				(anchor circle)
			)
			(primitives
				(gr_poly
					(pts
						(arc
							(start -0.1778 0.2794)
							(mid -0.249642 0.249642)
							(end -0.2794 0.1778)
						)
						(arc
							(start -0.2794 -0.1778)
							(mid -0.249642 -0.249642)
							(end -0.1778 -0.2794)
						)
						(arc
							(start 0.1778 -0.2794)
							(mid 0.249642 -0.249642)
							(end 0.2794 -0.1778)
						)
						(arc
							(start 0.2794 0.1778)
							(mid 0.249642 0.249642)
							(end 0.1778 0.2794)
						)
					)
					(width 0)
					(fill yes)
				)
			)
		)
	)
	(footprint ""
		(layer "B.Cu")
		(at 16.2814 -11.4808 -90)
		(property "Reference" "PR4"
			(at 0 0 90)
			(layer "B.SilkS")
			(hide yes)
			(effects
				(font
					(size 1.27 1.27)
				)
				(justify mirror)
			)
		)
		(property "Value" "10KR2F-2-GP"
			(at -0.064008 -3.993896 270)
			(unlocked yes)
			(layer "B.Fab")
			(hide yes)
			(effects
				(font
					(size 1.016 1.016)
					(thickness 0.1524)
				)
				(justify mirror)
			)
		)
		(property "Device Type" "R402H16"
			(at -0.064008 -5.517896 270)
			(unlocked yes)
			(layer "B.Fab")
			(hide yes)
			(effects
				(font
					(size 1.016 1.016)
					(thickness 0.1524)
				)
				(justify mirror)
			)
		)
		(duplicate_pad_numbers_are_jumpers no)
		(fp_line
			(start -0.508 -0.9398)
			(end 0.508 -0.9398)
			(stroke
				(width 0.1524)
				(type default)
			)
			(layer "B.SilkS")
		)
		(fp_line
			(start 0.508 -0.9398)
			(end 0.508 0.9398)
			(stroke
				(width 0.1524)
				(type default)
			)
			(layer "B.SilkS")
		)
		(fp_rect
			(start 0.508 0.9398)
			(end -0.508 -0.9398)
			(stroke
				(width 0)
				(type default)
			)
			(fill no)
			(layer "B.CrtYd")
		)
		(fp_rect
			(start 0.508 0.9398)
			(end -0.508 -0.9398)
			(stroke
				(width 0)
				(type default)
			)
			(fill no)
			(layer "B.Fab")
		)
		(pad "1" smd custom
			(at 0 -0.4445 90)
			(size 0.1397 0.1397)
			(layers "B.Cu" "B.Mask" "B.Paste")
			(net "P3V3_FB")
			(options
				(clearance outline)
				(anchor circle)
			)
			(primitives
				(gr_poly
					(pts
						(arc
							(start -0.1778 0.2794)
							(mid -0.249642 0.249642)
							(end -0.2794 0.1778)
						)
						(arc
							(start -0.2794 -0.1778)
							(mid -0.249642 -0.249642)
							(end -0.1778 -0.2794)
						)
						(arc
							(start 0.1778 -0.2794)
							(mid 0.249642 -0.249642)
							(end 0.2794 -0.1778)
						)
						(arc
							(start 0.2794 0.1778)
							(mid 0.249642 0.249642)
							(end 0.1778 0.2794)
						)
					)
					(width 0)
					(fill yes)
				)
			)
		)
		(pad "2" smd custom
			(at 0 0.4445 90)
			(size 0.1397 0.1397)
			(layers "B.Cu" "B.Mask" "B.Paste")
			(net "P3V3_VFB_R")
			(options
				(clearance outline)
				(anchor circle)
			)
			(primitives
				(gr_poly
					(pts
						(arc
							(start -0.1778 0.2794)
							(mid -0.249642 0.249642)
							(end -0.2794 0.1778)
						)
						(arc
							(start -0.2794 -0.1778)
							(mid -0.249642 -0.249642)
							(end -0.1778 -0.2794)
						)
						(arc
							(start 0.1778 -0.2794)
							(mid 0.249642 -0.249642)
							(end 0.2794 -0.1778)
						)
						(arc
							(start 0.2794 0.1778)
							(mid 0.249642 0.249642)
							(end 0.1778 0.2794)
						)
					)
					(width 0)
					(fill yes)
				)
			)
		)
	)
	(footprint ""
		(layer "B.Cu")
		(at 129.0066 -32.512)
		(property "Reference" "LU2"
			(at 0 0 0)
			(layer "B.SilkS")
			(hide yes)
			(effects
				(font
					(size 1.27 1.27)
				)
				(justify mirror)
			)
		)
		(property "Value" "MMZ1608S301AT-GP"
			(at 0.0254 -2.8956 0)
			(unlocked yes)
			(layer "B.Fab")
			(hide yes)
			(effects
				(font
					(size 1.016 1.016)
					(thickness 0.1524)
				)
				(justify mirror)
			)
		)
		(property "Device Type" "L1608-UH38"
			(at 0.0254 -4.4196 0)
			(unlocked yes)
			(layer "B.Fab")
			(hide yes)
			(effects
				(font
					(size 1.016 1.016)
					(thickness 0.1524)
				)
				(justify mirror)
			)
		)
		(duplicate_pad_numbers_are_jumpers no)
		(fp_line
			(start -0.254 0)
			(end 0.254 0)
			(stroke
				(width 0.2032)
				(type default)
			)
			(layer "B.SilkS")
		)
		(fp_rect
			(start 0.5842 1.3335)
			(end -0.5842 -1.3335)
			(stroke
				(width 0)
				(type default)
			)
			(fill no)
			(layer "B.CrtYd")
		)
		(fp_rect
			(start 0.5842 1.3335)
			(end -0.5842 -1.3335)
			(stroke
				(width 0)
				(type default)
			)
			(fill no)
			(layer "B.Fab")
		)
		(pad "1" smd custom
			(at 0 -0.762 180)
			(size 0.2159 0.2159)
			(layers "B.Cu" "B.Mask" "B.Paste")
			(net "P3V3")
			(options
				(clearance outline)
				(anchor circle)
			)
			(primitives
				(gr_poly
					(pts
						(arc
							(start -0.3302 0.4318)
							(mid -0.402042 0.402042)
							(end -0.4318 0.3302)
						)
						(arc
							(start -0.4318 -0.3302)
							(mid -0.402042 -0.402042)
							(end -0.3302 -0.4318)
						)
						(arc
							(start 0.3302 -0.4318)
							(mid 0.402042 -0.402042)
							(end 0.4318 -0.3302)
						)
						(arc
							(start 0.4318 0.3302)
							(mid 0.402042 0.402042)
							(end 0.3302 0.4318)
						)
					)
					(width 0)
					(fill yes)
				)
			)
		)
		(pad "2" smd custom
			(at 0 0.762 180)
			(size 0.2159 0.2159)
			(layers "B.Cu" "B.Mask" "B.Paste")
			(net "P3V3_USB_HUB")
			(options
				(clearance outline)
				(anchor circle)
			)
			(primitives
				(gr_poly
					(pts
						(arc
							(start -0.3302 0.4318)
							(mid -0.402042 0.402042)
							(end -0.4318 0.3302)
						)
						(arc
							(start -0.4318 -0.3302)
							(mid -0.402042 -0.402042)
							(end -0.3302 -0.4318)
						)
						(arc
							(start 0.3302 -0.4318)
							(mid 0.402042 -0.402042)
							(end 0.4318 -0.3302)
						)
						(arc
							(start 0.4318 0.3302)
							(mid 0.402042 0.402042)
							(end 0.3302 0.4318)
						)
					)
					(width 0)
					(fill yes)
				)
			)
		)
	)
	(footprint ""
		(layer "B.Cu")
		(at 25.2984 -23.6728 180)
		(property "Reference" "R150"
			(at 0 0 0)
			(layer "B.SilkS")
			(hide yes)
			(effects
				(font
					(size 1.27 1.27)
				)
				(justify mirror)
			)
		)
		(property "Value" "10KR2F-2-GP"
			(at -0.064008 -3.993896 180)
			(unlocked yes)
			(layer "B.Fab")
			(hide yes)
			(effects
				(font
					(size 1.016 1.016)
					(thickness 0.1524)
				)
				(justify mirror)
			)
		)
		(property "Device Type" "R402H16"
			(at -0.064008 -5.517896 180)
			(unlocked yes)
			(layer "B.Fab")
			(hide yes)
			(effects
				(font
					(size 1.016 1.016)
					(thickness 0.1524)
				)
				(justify mirror)
			)
		)
		(duplicate_pad_numbers_are_jumpers no)
		(fp_line
			(start 0.508 -0.9398)
			(end 0.508 0.9398)
			(stroke
				(width 0.1524)
				(type default)
			)
			(layer "B.SilkS")
		)
		(fp_line
			(start -0.508 -0.9398)
			(end 0.508 -0.9398)
			(stroke
				(width 0.1524)
				(type default)
			)
			(layer "B.SilkS")
		)
		(fp_rect
			(start 0.508 0.9398)
			(end -0.508 -0.9398)
			(stroke
				(width 0)
				(type default)
			)
			(fill no)
			(layer "B.CrtYd")
		)
		(fp_rect
			(start 0.508 0.9398)
			(end -0.508 -0.9398)
			(stroke
				(width 0)
				(type default)
			)
			(fill no)
			(layer "B.Fab")
		)
		(pad "1" smd custom
			(at 0 -0.4445)
			(size 0.1397 0.1397)
			(layers "B.Cu" "B.Mask" "B.Paste")
			(net "ATX_VMONITOR_A0")
			(options
				(clearance outline)
				(anchor circle)
			)
			(primitives
				(gr_poly
					(pts
						(arc
							(start -0.1778 0.2794)
							(mid -0.249642 0.249642)
							(end -0.2794 0.1778)
						)
						(arc
							(start -0.2794 -0.1778)
							(mid -0.249642 -0.249642)
							(end -0.1778 -0.2794)
						)
						(arc
							(start 0.1778 -0.2794)
							(mid 0.249642 -0.249642)
							(end 0.2794 -0.1778)
						)
						(arc
							(start 0.2794 0.1778)
							(mid 0.249642 0.249642)
							(end 0.1778 0.2794)
						)
					)
					(width 0)
					(fill yes)
				)
			)
		)
		(pad "2" smd custom
			(at 0 0.4445)
			(size 0.1397 0.1397)
			(layers "B.Cu" "B.Mask" "B.Paste")
			(net "GND")
			(options
				(clearance outline)
				(anchor circle)
			)
			(primitives
				(gr_poly
					(pts
						(arc
							(start -0.1778 0.2794)
							(mid -0.249642 0.249642)
							(end -0.2794 0.1778)
						)
						(arc
							(start -0.2794 -0.1778)
							(mid -0.249642 -0.249642)
							(end -0.1778 -0.2794)
						)
						(arc
							(start 0.1778 -0.2794)
							(mid 0.249642 -0.249642)
							(end 0.2794 -0.1778)
						)
						(arc
							(start 0.2794 0.1778)
							(mid 0.249642 0.249642)
							(end 0.1778 0.2794)
						)
					)
					(width 0)
					(fill yes)
				)
			)
		)
	)
	(footprint ""
		(layer "B.Cu")
		(at 30.4165 2.1971)
		(property "Reference" "PC9"
			(at 0 0 0)
			(layer "B.SilkS")
			(hide yes)
			(effects
				(font
					(size 1.27 1.27)
				)
				(justify mirror)
			)
		)
		(property "Value" "SC22U6D3V5MX-5-GP"
			(at 0.0762 -6.1214 0)
			(unlocked yes)
			(layer "B.Fab")
			(hide yes)
			(effects
				(font
					(size 1.016 1.016)
					(thickness 0.1524)
				)
				(justify mirror)
			)
		)
		(property "Device Type" "C805H56"
			(at 0.0762 -8.1534 0)
			(unlocked yes)
			(layer "B.Fab")
			(hide yes)
			(effects
				(font
					(size 1.016 1.016)
					(thickness 0.1524)
				)
				(justify mirror)
			)
		)
		(duplicate_pad_numbers_are_jumpers no)
		(fp_line
			(start -0.635 0)
			(end 0.635 0)
			(stroke
				(width 0.508)
				(type default)
			)
			(layer "B.SilkS")
		)
		(fp_rect
			(start 0.9652 1.778)
			(end -0.9652 -1.778)
			(stroke
				(width 0)
				(type default)
			)
			(fill no)
			(layer "B.CrtYd")
		)
		(fp_poly
			(pts
				(xy 0.9652 -1.778) (xy -0.9652 -1.778) (xy -0.9652 1.778) (xy 0.9652 1.778)
			)
			(stroke
				(width 0)
				(type default)
			)
			(fill no)
			(layer "B.Fab")
		)
		(pad "1" smd rect
			(at 0 -0.9652 180)
			(size 1.397 1.143)
			(layers "B.Cu" "B.Mask" "B.Paste")
			(net "P3V3_VR")
		)
		(pad "2" smd rect
			(at 0 0.9652 180)
			(size 1.397 1.143)
			(layers "B.Cu" "B.Mask" "B.Paste")
			(net "GND")
		)
	)
	(footprint ""
		(layer "B.Cu")
		(at 122.8344 -8.8392 -90)
		(property "Reference" "R39"
			(at 0 0 90)
			(layer "B.SilkS")
			(hide yes)
			(effects
				(font
					(size 1.27 1.27)
				)
				(justify mirror)
			)
		)
		(property "Value" "10KR2F-2-GP"
			(at -0.064008 -3.993896 270)
			(unlocked yes)
			(layer "B.Fab")
			(hide yes)
			(effects
				(font
					(size 1.016 1.016)
					(thickness 0.1524)
				)
				(justify mirror)
			)
		)
		(property "Device Type" "R402H16"
			(at -0.064008 -5.517896 270)
			(unlocked yes)
			(layer "B.Fab")
			(hide yes)
			(effects
				(font
					(size 1.016 1.016)
					(thickness 0.1524)
				)
				(justify mirror)
			)
		)
		(duplicate_pad_numbers_are_jumpers no)
		(fp_line
			(start -0.508 -0.9398)
			(end 0.508 -0.9398)
			(stroke
				(width 0.1524)
				(type default)
			)
			(layer "B.SilkS")
		)
		(fp_line
			(start 0.508 -0.9398)
			(end 0.508 0.9398)
			(stroke
				(width 0.1524)
				(type default)
			)
			(layer "B.SilkS")
		)
		(fp_rect
			(start 0.508 0.9398)
			(end -0.508 -0.9398)
			(stroke
				(width 0)
				(type default)
			)
			(fill no)
			(layer "B.CrtYd")
		)
		(fp_rect
			(start 0.508 0.9398)
			(end -0.508 -0.9398)
			(stroke
				(width 0)
				(type default)
			)
			(fill no)
			(layer "B.Fab")
		)
		(pad "1" smd custom
			(at 0 -0.4445 90)
			(size 0.1397 0.1397)
			(layers "B.Cu" "B.Mask" "B.Paste")
			(net "SMB_P_HUB_A1")
			(options
				(clearance outline)
				(anchor circle)
			)
			(primitives
				(gr_poly
					(pts
						(arc
							(start -0.1778 0.2794)
							(mid -0.249642 0.249642)
							(end -0.2794 0.1778)
						)
						(arc
							(start -0.2794 -0.1778)
							(mid -0.249642 -0.249642)
							(end -0.1778 -0.2794)
						)
						(arc
							(start 0.1778 -0.2794)
							(mid 0.249642 -0.249642)
							(end 0.2794 -0.1778)
						)
						(arc
							(start 0.2794 0.1778)
							(mid 0.249642 0.249642)
							(end 0.1778 0.2794)
						)
					)
					(width 0)
					(fill yes)
				)
			)
		)
		(pad "2" smd custom
			(at 0 0.4445 90)
			(size 0.1397 0.1397)
			(layers "B.Cu" "B.Mask" "B.Paste")
			(net "GND")
			(options
				(clearance outline)
				(anchor circle)
			)
			(primitives
				(gr_poly
					(pts
						(arc
							(start -0.1778 0.2794)
							(mid -0.249642 0.249642)
							(end -0.2794 0.1778)
						)
						(arc
							(start -0.2794 -0.1778)
							(mid -0.249642 -0.249642)
							(end -0.1778 -0.2794)
						)
						(arc
							(start 0.1778 -0.2794)
							(mid 0.249642 -0.249642)
							(end 0.2794 -0.1778)
						)
						(arc
							(start 0.2794 0.1778)
							(mid 0.249642 0.249642)
							(end 0.1778 0.2794)
						)
					)
					(width 0)
					(fill yes)
				)
			)
		)
	)
	(footprint ""
		(layer "B.Cu")
		(at 117.4496 1.6256 180)
		(property "Reference" "R8"
			(at 0 0 0)
			(layer "B.SilkS")
			(hide yes)
			(effects
				(font
					(size 1.27 1.27)
				)
				(justify mirror)
			)
		)
		(property "Value" "4K7R2F-GP"
			(at -0.064008 -3.993896 180)
			(unlocked yes)
			(layer "B.Fab")
			(hide yes)
			(effects
				(font
					(size 1.016 1.016)
					(thickness 0.1524)
				)
				(justify mirror)
			)
		)
		(property "Device Type" "R402H16"
			(at -0.064008 -5.517896 180)
			(unlocked yes)
			(layer "B.Fab")
			(hide yes)
			(effects
				(font
					(size 1.016 1.016)
					(thickness 0.1524)
				)
				(justify mirror)
			)
		)
		(duplicate_pad_numbers_are_jumpers no)
		(fp_line
			(start 0.508 -0.9398)
			(end 0.508 0.9398)
			(stroke
				(width 0.1524)
				(type default)
			)
			(layer "B.SilkS")
		)
		(fp_line
			(start -0.508 -0.9398)
			(end 0.508 -0.9398)
			(stroke
				(width 0.1524)
				(type default)
			)
			(layer "B.SilkS")
		)
		(fp_rect
			(start 0.508 0.9398)
			(end -0.508 -0.9398)
			(stroke
				(width 0)
				(type default)
			)
			(fill no)
			(layer "B.CrtYd")
		)
		(fp_rect
			(start 0.508 0.9398)
			(end -0.508 -0.9398)
			(stroke
				(width 0)
				(type default)
			)
			(fill no)
			(layer "B.Fab")
		)
		(pad "1" smd custom
			(at 0 -0.4445)
			(size 0.1397 0.1397)
			(layers "B.Cu" "B.Mask" "B.Paste")
			(net "P3V3_STBY")
			(options
				(clearance outline)
				(anchor circle)
			)
			(primitives
				(gr_poly
					(pts
						(arc
							(start -0.1778 0.2794)
							(mid -0.249642 0.249642)
							(end -0.2794 0.1778)
						)
						(arc
							(start -0.2794 -0.1778)
							(mid -0.249642 -0.249642)
							(end -0.1778 -0.2794)
						)
						(arc
							(start 0.1778 -0.2794)
							(mid 0.249642 -0.249642)
							(end 0.2794 -0.1778)
						)
						(arc
							(start 0.2794 0.1778)
							(mid 0.249642 0.249642)
							(end 0.1778 0.2794)
						)
					)
					(width 0)
					(fill yes)
				)
			)
		)
		(pad "2" smd custom
			(at 0 0.4445)
			(size 0.1397 0.1397)
			(layers "B.Cu" "B.Mask" "B.Paste")
			(net "SMCLK_BMC_DEVICE")
			(options
				(clearance outline)
				(anchor circle)
			)
			(primitives
				(gr_poly
					(pts
						(arc
							(start -0.1778 0.2794)
							(mid -0.249642 0.249642)
							(end -0.2794 0.1778)
						)
						(arc
							(start -0.2794 -0.1778)
							(mid -0.249642 -0.249642)
							(end -0.1778 -0.2794)
						)
						(arc
							(start 0.1778 -0.2794)
							(mid 0.249642 -0.249642)
							(end 0.2794 -0.1778)
						)
						(arc
							(start 0.2794 0.1778)
							(mid 0.249642 0.249642)
							(end 0.1778 0.2794)
						)
					)
					(width 0)
					(fill yes)
				)
			)
		)
	)
	(footprint ""
		(layer "B.Cu")
		(at 128.2827 0.3302 180)
		(property "Reference" "R23"
			(at 0 0 0)
			(layer "B.SilkS")
			(hide yes)
			(effects
				(font
					(size 1.27 1.27)
				)
				(justify mirror)
			)
		)
		(property "Value" "4K7R2F-GP"
			(at -0.064008 -3.993896 180)
			(unlocked yes)
			(layer "B.Fab")
			(hide yes)
			(effects
				(font
					(size 1.016 1.016)
					(thickness 0.1524)
				)
				(justify mirror)
			)
		)
		(property "Device Type" "R402H16"
			(at -0.064008 -5.517896 180)
			(unlocked yes)
			(layer "B.Fab")
			(hide yes)
			(effects
				(font
					(size 1.016 1.016)
					(thickness 0.1524)
				)
				(justify mirror)
			)
		)
		(duplicate_pad_numbers_are_jumpers no)
		(fp_line
			(start 0.508 -0.9398)
			(end 0.508 0.9398)
			(stroke
				(width 0.1524)
				(type default)
			)
			(layer "B.SilkS")
		)
		(fp_line
			(start -0.508 -0.9398)
			(end 0.508 -0.9398)
			(stroke
				(width 0.1524)
				(type default)
			)
			(layer "B.SilkS")
		)
		(fp_rect
			(start 0.508 0.9398)
			(end -0.508 -0.9398)
			(stroke
				(width 0)
				(type default)
			)
			(fill no)
			(layer "B.CrtYd")
		)
		(fp_rect
			(start 0.508 0.9398)
			(end -0.508 -0.9398)
			(stroke
				(width 0)
				(type default)
			)
			(fill no)
			(layer "B.Fab")
		)
		(pad "1" smd custom
			(at 0 -0.4445)
			(size 0.1397 0.1397)
			(layers "B.Cu" "B.Mask" "B.Paste")
			(net "P3V3_STBY")
			(options
				(clearance outline)
				(anchor circle)
			)
			(primitives
				(gr_poly
					(pts
						(arc
							(start -0.1778 0.2794)
							(mid -0.249642 0.249642)
							(end -0.2794 0.1778)
						)
						(arc
							(start -0.2794 -0.1778)
							(mid -0.249642 -0.249642)
							(end -0.1778 -0.2794)
						)
						(arc
							(start 0.1778 -0.2794)
							(mid 0.249642 -0.249642)
							(end 0.2794 -0.1778)
						)
						(arc
							(start 0.2794 0.1778)
							(mid 0.249642 0.249642)
							(end 0.1778 0.2794)
						)
					)
					(width 0)
					(fill yes)
				)
			)
		)
		(pad "2" smd custom
			(at 0 0.4445)
			(size 0.1397 0.1397)
			(layers "B.Cu" "B.Mask" "B.Paste")
			(net "PU_P_MUX_SCL2")
			(options
				(clearance outline)
				(anchor circle)
			)
			(primitives
				(gr_poly
					(pts
						(arc
							(start -0.1778 0.2794)
							(mid -0.249642 0.249642)
							(end -0.2794 0.1778)
						)
						(arc
							(start -0.2794 -0.1778)
							(mid -0.249642 -0.249642)
							(end -0.1778 -0.2794)
						)
						(arc
							(start 0.1778 -0.2794)
							(mid 0.249642 -0.249642)
							(end 0.2794 -0.1778)
						)
						(arc
							(start 0.2794 0.1778)
							(mid 0.249642 0.249642)
							(end 0.1778 0.2794)
						)
					)
					(width 0)
					(fill yes)
				)
			)
		)
	)
	(footprint ""
		(layer "B.Cu")
		(at 119.9388 -14.6304 -90)
		(property "Reference" "RU96"
			(at 0 0 90)
			(layer "B.SilkS")
			(hide yes)
			(effects
				(font
					(size 1.27 1.27)
				)
				(justify mirror)
			)
		)
		(property "Value" "10KR2F-2-GP"
			(at -0.064008 -3.993896 270)
			(unlocked yes)
			(layer "B.Fab")
			(hide yes)
			(effects
				(font
					(size 1.016 1.016)
					(thickness 0.1524)
				)
				(justify mirror)
			)
		)
		(property "Device Type" "R402H16"
			(at -0.064008 -5.517896 270)
			(unlocked yes)
			(layer "B.Fab")
			(hide yes)
			(effects
				(font
					(size 1.016 1.016)
					(thickness 0.1524)
				)
				(justify mirror)
			)
		)
		(duplicate_pad_numbers_are_jumpers no)
		(fp_line
			(start -0.508 -0.9398)
			(end 0.508 -0.9398)
			(stroke
				(width 0.1524)
				(type default)
			)
			(layer "B.SilkS")
		)
		(fp_line
			(start 0.508 -0.9398)
			(end 0.508 0.9398)
			(stroke
				(width 0.1524)
				(type default)
			)
			(layer "B.SilkS")
		)
		(fp_rect
			(start 0.508 0.9398)
			(end -0.508 -0.9398)
			(stroke
				(width 0)
				(type default)
			)
			(fill no)
			(layer "B.CrtYd")
		)
		(fp_rect
			(start 0.508 0.9398)
			(end -0.508 -0.9398)
			(stroke
				(width 0)
				(type default)
			)
			(fill no)
			(layer "B.Fab")
		)
		(pad "1" smd custom
			(at 0 -0.4445 90)
			(size 0.1397 0.1397)
			(layers "B.Cu" "B.Mask" "B.Paste")
			(net "SMB_U_REPEATER_EN")
			(options
				(clearance outline)
				(anchor circle)
			)
			(primitives
				(gr_poly
					(pts
						(arc
							(start -0.1778 0.2794)
							(mid -0.249642 0.249642)
							(end -0.2794 0.1778)
						)
						(arc
							(start -0.2794 -0.1778)
							(mid -0.249642 -0.249642)
							(end -0.1778 -0.2794)
						)
						(arc
							(start 0.1778 -0.2794)
							(mid 0.249642 -0.249642)
							(end 0.2794 -0.1778)
						)
						(arc
							(start 0.2794 0.1778)
							(mid 0.249642 0.249642)
							(end 0.1778 0.2794)
						)
					)
					(width 0)
					(fill yes)
				)
			)
		)
		(pad "2" smd custom
			(at 0 0.4445 90)
			(size 0.1397 0.1397)
			(layers "B.Cu" "B.Mask" "B.Paste")
			(net "P3V3_USB_HUB")
			(options
				(clearance outline)
				(anchor circle)
			)
			(primitives
				(gr_poly
					(pts
						(arc
							(start -0.1778 0.2794)
							(mid -0.249642 0.249642)
							(end -0.2794 0.1778)
						)
						(arc
							(start -0.2794 -0.1778)
							(mid -0.249642 -0.249642)
							(end -0.1778 -0.2794)
						)
						(arc
							(start 0.1778 -0.2794)
							(mid 0.249642 -0.249642)
							(end 0.2794 -0.1778)
						)
						(arc
							(start 0.2794 0.1778)
							(mid 0.249642 0.249642)
							(end 0.1778 0.2794)
						)
					)
					(width 0)
					(fill yes)
				)
			)
		)
	)
	(footprint ""
		(layer "B.Cu")
		(at 14.5415 -25.9207 -135)
		(property "Reference" "C51"
			(at 0 0 45)
			(layer "B.SilkS")
			(hide yes)
			(effects
				(font
					(size 1.27 1.27)
				)
				(justify mirror)
			)
		)
		(property "Value" "SCD1U25V2KX-2-GP"
			(at -1.181083 -2.705137 225)
			(unlocked yes)
			(layer "B.Fab")
			(hide yes)
			(effects
				(font
					(size 1.016 1.016)
					(thickness 0.1524)
				)
				(justify mirror)
			)
		)
		(property "Device Type" "C402H22"
			(at -1.181263 -4.229087 225)
			(unlocked yes)
			(layer "B.Fab")
			(hide yes)
			(effects
				(font
					(size 1.016 1.016)
					(thickness 0.1524)
				)
				(justify mirror)
			)
		)
		(duplicate_pad_numbers_are_jumpers no)
		(fp_poly
			(pts
				(xy -0.431829 0.952626) (xy -0.431829 -0.952375) (xy 0.431771 -0.952374) (xy 0.431771 0.952626)
			)
			(stroke
				(width 0)
				(type default)
			)
			(fill no)
			(layer "B.CrtYd")
		)
		(fp_poly
			(pts
				(xy -0.431829 0.952626) (xy -0.431829 -0.952375) (xy 0.431771 -0.952374) (xy 0.431771 0.952626)
			)
			(stroke
				(width 0)
				(type default)
			)
			(fill no)
			(layer "B.Fab")
		)
		(pad "1" smd custom
			(at 0 -0.4445 45)
			(size 0.1524 0.1524)
			(layers "B.Cu" "B.Mask" "B.Paste")
			(net "ATX_P12V_SENSE_VP_R")
			(options
				(clearance outline)
				(anchor circle)
			)
			(primitives
				(gr_poly
					(pts
						(arc
							(start 0.3048 0.2032)
							(mid 0.275042 0.275042)
							(end 0.2032 0.3048)
						)
						(arc
							(start -0.2032 0.3048)
							(mid -0.275042 0.275042)
							(end -0.3048 0.2032)
						)
						(arc
							(start -0.3048 -0.2032)
							(mid -0.275042 -0.275042)
							(end -0.2032 -0.3048)
						)
						(arc
							(start 0.2032 -0.3048)
							(mid 0.275042 -0.275042)
							(end 0.3048 -0.2032)
						)
					)
					(width 0)
					(fill yes)
				)
			)
		)
		(pad "2" smd custom
			(at 0 0.4445 45)
			(size 0.1524 0.1524)
			(layers "B.Cu" "B.Mask" "B.Paste")
			(net "ATX_P12V_SENSE_VN_R")
			(options
				(clearance outline)
				(anchor circle)
			)
			(primitives
				(gr_poly
					(pts
						(arc
							(start 0.3048 0.2032)
							(mid 0.275042 0.275042)
							(end 0.2032 0.3048)
						)
						(arc
							(start -0.2032 0.3048)
							(mid -0.275042 0.275042)
							(end -0.3048 0.2032)
						)
						(arc
							(start -0.3048 -0.2032)
							(mid -0.275042 -0.275042)
							(end -0.2032 -0.3048)
						)
						(arc
							(start 0.2032 -0.3048)
							(mid 0.275042 -0.275042)
							(end 0.3048 -0.2032)
						)
					)
					(width 0)
					(fill yes)
				)
			)
		)
	)
	(footprint ""
		(layer "B.Cu")
		(at 32.7787 -1.6129)
		(property "Reference" "R60"
			(at 0 0 0)
			(layer "B.SilkS")
			(hide yes)
			(effects
				(font
					(size 1.27 1.27)
				)
				(justify mirror)
			)
		)
		(property "Value" "0R2F-1-GP"
			(at -0.064008 -3.993896 0)
			(unlocked yes)
			(layer "B.Fab")
			(hide yes)
			(effects
				(font
					(size 1.016 1.016)
					(thickness 0.1524)
				)
				(justify mirror)
			)
		)
		(property "Device Type" "R402H16"
			(at -0.064008 -5.517896 0)
			(unlocked yes)
			(layer "B.Fab")
			(hide yes)
			(effects
				(font
					(size 1.016 1.016)
					(thickness 0.1524)
				)
				(justify mirror)
			)
		)
		(duplicate_pad_numbers_are_jumpers no)
		(fp_line
			(start -0.508 -0.9398)
			(end 0.508 -0.9398)
			(stroke
				(width 0.1524)
				(type default)
			)
			(layer "B.SilkS")
		)
		(fp_line
			(start 0.508 -0.9398)
			(end 0.508 0.9398)
			(stroke
				(width 0.1524)
				(type default)
			)
			(layer "B.SilkS")
		)
		(fp_rect
			(start 0.508 0.9398)
			(end -0.508 -0.9398)
			(stroke
				(width 0)
				(type default)
			)
			(fill no)
			(layer "B.CrtYd")
		)
		(fp_rect
			(start 0.508 0.9398)
			(end -0.508 -0.9398)
			(stroke
				(width 0)
				(type default)
			)
			(fill no)
			(layer "B.Fab")
		)
		(pad "1" smd custom
			(at 0 -0.4445 180)
			(size 0.1397 0.1397)
			(layers "B.Cu" "B.Mask" "B.Paste")
			(net "PD_SLOT2_PRSNT1")
			(options
				(clearance outline)
				(anchor circle)
			)
			(primitives
				(gr_poly
					(pts
						(arc
							(start -0.1778 0.2794)
							(mid -0.249642 0.249642)
							(end -0.2794 0.1778)
						)
						(arc
							(start -0.2794 -0.1778)
							(mid -0.249642 -0.249642)
							(end -0.1778 -0.2794)
						)
						(arc
							(start 0.1778 -0.2794)
							(mid 0.249642 -0.249642)
							(end 0.2794 -0.1778)
						)
						(arc
							(start 0.2794 0.1778)
							(mid 0.249642 0.249642)
							(end 0.1778 0.2794)
						)
					)
					(width 0)
					(fill yes)
				)
			)
		)
		(pad "2" smd custom
			(at 0 0.4445 180)
			(size 0.1397 0.1397)
			(layers "B.Cu" "B.Mask" "B.Paste")
			(net "GND")
			(options
				(clearance outline)
				(anchor circle)
			)
			(primitives
				(gr_poly
					(pts
						(arc
							(start -0.1778 0.2794)
							(mid -0.249642 0.249642)
							(end -0.2794 0.1778)
						)
						(arc
							(start -0.2794 -0.1778)
							(mid -0.249642 -0.249642)
							(end -0.1778 -0.2794)
						)
						(arc
							(start 0.1778 -0.2794)
							(mid 0.249642 -0.249642)
							(end 0.2794 -0.1778)
						)
						(arc
							(start 0.2794 0.1778)
							(mid 0.249642 0.249642)
							(end 0.1778 0.2794)
						)
					)
					(width 0)
					(fill yes)
				)
			)
		)
	)
	(footprint ""
		(layer "B.Cu")
		(at 127.0762 -18.4404 90)
		(property "Reference" "CU60"
			(at 0 0 90)
			(layer "B.SilkS")
			(hide yes)
			(effects
				(font
					(size 1.27 1.27)
				)
				(justify mirror)
			)
		)
		(property "Value" "SCD1U16V2KX-3GP"
			(at -1.1811 -2.7051 90)
			(unlocked yes)
			(layer "B.Fab")
			(hide yes)
			(effects
				(font
					(size 1.016 1.016)
					(thickness 0.1524)
				)
				(justify mirror)
			)
		)
		(property "Device Type" "C402H22"
			(at -1.1811 -4.2291 90)
			(unlocked yes)
			(layer "B.Fab")
			(hide yes)
			(effects
				(font
					(size 1.016 1.016)
					(thickness 0.1524)
				)
				(justify mirror)
			)
		)
		(duplicate_pad_numbers_are_jumpers no)
		(fp_rect
			(start 0.4318 0.9525)
			(end -0.4318 -0.9525)
			(stroke
				(width 0)
				(type default)
			)
			(fill no)
			(layer "B.CrtYd")
		)
		(fp_rect
			(start 0.4318 0.9525)
			(end -0.4318 -0.9525)
			(stroke
				(width 0)
				(type default)
			)
			(fill no)
			(layer "B.Fab")
		)
		(pad "1" smd custom
			(at 0 -0.4445 270)
			(size 0.1524 0.1524)
			(layers "B.Cu" "B.Mask" "B.Paste")
			(net "P3V3_STBY")
			(options
				(clearance outline)
				(anchor circle)
			)
			(primitives
				(gr_poly
					(pts
						(arc
							(start 0.3048 0.2032)
							(mid 0.275042 0.275042)
							(end 0.2032 0.3048)
						)
						(arc
							(start -0.2032 0.3048)
							(mid -0.275042 0.275042)
							(end -0.3048 0.2032)
						)
						(arc
							(start -0.3048 -0.2032)
							(mid -0.275042 -0.275042)
							(end -0.2032 -0.3048)
						)
						(arc
							(start 0.2032 -0.3048)
							(mid 0.275042 -0.275042)
							(end 0.3048 -0.2032)
						)
					)
					(width 0)
					(fill yes)
				)
			)
		)
		(pad "2" smd custom
			(at 0 0.4445 270)
			(size 0.1524 0.1524)
			(layers "B.Cu" "B.Mask" "B.Paste")
			(net "GND")
			(options
				(clearance outline)
				(anchor circle)
			)
			(primitives
				(gr_poly
					(pts
						(arc
							(start 0.3048 0.2032)
							(mid 0.275042 0.275042)
							(end 0.2032 0.3048)
						)
						(arc
							(start -0.2032 0.3048)
							(mid -0.275042 0.275042)
							(end -0.3048 0.2032)
						)
						(arc
							(start -0.3048 -0.2032)
							(mid -0.275042 -0.275042)
							(end -0.2032 -0.3048)
						)
						(arc
							(start 0.2032 -0.3048)
							(mid 0.275042 -0.275042)
							(end 0.3048 -0.2032)
						)
					)
					(width 0)
					(fill yes)
				)
			)
		)
	)
	(footprint ""
		(layer "B.Cu")
		(at 127.3556 -27.4066 -90)
		(property "Reference" "CU6"
			(at 0 0 90)
			(layer "B.SilkS")
			(hide yes)
			(effects
				(font
					(size 1.27 1.27)
				)
				(justify mirror)
			)
		)
		(property "Value" "SC1U10V2KX-4-GP"
			(at -1.1811 -2.7051 270)
			(unlocked yes)
			(layer "B.Fab")
			(hide yes)
			(effects
				(font
					(size 1.016 1.016)
					(thickness 0.1524)
				)
				(justify mirror)
			)
		)
		(property "Device Type" "C402H22"
			(at -1.1811 -4.2291 270)
			(unlocked yes)
			(layer "B.Fab")
			(hide yes)
			(effects
				(font
					(size 1.016 1.016)
					(thickness 0.1524)
				)
				(justify mirror)
			)
		)
		(duplicate_pad_numbers_are_jumpers no)
		(fp_rect
			(start 0.4318 0.9525)
			(end -0.4318 -0.9525)
			(stroke
				(width 0)
				(type default)
			)
			(fill no)
			(layer "B.CrtYd")
		)
		(fp_rect
			(start 0.4318 0.9525)
			(end -0.4318 -0.9525)
			(stroke
				(width 0)
				(type default)
			)
			(fill no)
			(layer "B.Fab")
		)
		(pad "1" smd custom
			(at 0 -0.4445 90)
			(size 0.1524 0.1524)
			(layers "B.Cu" "B.Mask" "B.Paste")
			(net "P3V3_USB_HUB")
			(options
				(clearance outline)
				(anchor circle)
			)
			(primitives
				(gr_poly
					(pts
						(arc
							(start 0.3048 0.2032)
							(mid 0.275042 0.275042)
							(end 0.2032 0.3048)
						)
						(arc
							(start -0.2032 0.3048)
							(mid -0.275042 0.275042)
							(end -0.3048 0.2032)
						)
						(arc
							(start -0.3048 -0.2032)
							(mid -0.275042 -0.275042)
							(end -0.2032 -0.3048)
						)
						(arc
							(start 0.2032 -0.3048)
							(mid 0.275042 -0.275042)
							(end 0.3048 -0.2032)
						)
					)
					(width 0)
					(fill yes)
				)
			)
		)
		(pad "2" smd custom
			(at 0 0.4445 90)
			(size 0.1524 0.1524)
			(layers "B.Cu" "B.Mask" "B.Paste")
			(net "GND")
			(options
				(clearance outline)
				(anchor circle)
			)
			(primitives
				(gr_poly
					(pts
						(arc
							(start 0.3048 0.2032)
							(mid 0.275042 0.275042)
							(end 0.2032 0.3048)
						)
						(arc
							(start -0.2032 0.3048)
							(mid -0.275042 0.275042)
							(end -0.3048 0.2032)
						)
						(arc
							(start -0.3048 -0.2032)
							(mid -0.275042 -0.275042)
							(end -0.2032 -0.3048)
						)
						(arc
							(start 0.2032 -0.3048)
							(mid 0.275042 -0.275042)
							(end 0.3048 -0.2032)
						)
					)
					(width 0)
					(fill yes)
				)
			)
		)
	)
	(footprint ""
		(layer "B.Cu")
		(at 15.6972 -10.0076)
		(property "Reference" "PC11"
			(at 0 0 0)
			(layer "B.SilkS")
			(hide yes)
			(effects
				(font
					(size 1.27 1.27)
				)
				(justify mirror)
			)
		)
		(property "Value" "SCD022U16V2KX-3DLGP"
			(at -1.1811 -2.7051 0)
			(unlocked yes)
			(layer "B.Fab")
			(hide yes)
			(effects
				(font
					(size 1.016 1.016)
					(thickness 0.1524)
				)
				(justify mirror)
			)
		)
		(property "Device Type" "C402H22"
			(at -1.1811 -4.2291 0)
			(unlocked yes)
			(layer "B.Fab")
			(hide yes)
			(effects
				(font
					(size 1.016 1.016)
					(thickness 0.1524)
				)
				(justify mirror)
			)
		)
		(duplicate_pad_numbers_are_jumpers no)
		(fp_rect
			(start 0.4318 0.9525)
			(end -0.4318 -0.9525)
			(stroke
				(width 0)
				(type default)
			)
			(fill no)
			(layer "B.CrtYd")
		)
		(fp_rect
			(start 0.4318 0.9525)
			(end -0.4318 -0.9525)
			(stroke
				(width 0)
				(type default)
			)
			(fill no)
			(layer "B.Fab")
		)
		(pad "1" smd custom
			(at 0 -0.4445 180)
			(size 0.1524 0.1524)
			(layers "B.Cu" "B.Mask" "B.Paste")
			(net "P3V3_TRK")
			(options
				(clearance outline)
				(anchor circle)
			)
			(primitives
				(gr_poly
					(pts
						(arc
							(start 0.3048 0.2032)
							(mid 0.275042 0.275042)
							(end 0.2032 0.3048)
						)
						(arc
							(start -0.2032 0.3048)
							(mid -0.275042 0.275042)
							(end -0.3048 0.2032)
						)
						(arc
							(start -0.3048 -0.2032)
							(mid -0.275042 -0.275042)
							(end -0.2032 -0.3048)
						)
						(arc
							(start 0.2032 -0.3048)
							(mid 0.275042 -0.275042)
							(end 0.3048 -0.2032)
						)
					)
					(width 0)
					(fill yes)
				)
			)
		)
		(pad "2" smd custom
			(at 0 0.4445 180)
			(size 0.1524 0.1524)
			(layers "B.Cu" "B.Mask" "B.Paste")
			(net "AGND_P3V3")
			(options
				(clearance outline)
				(anchor circle)
			)
			(primitives
				(gr_poly
					(pts
						(arc
							(start 0.3048 0.2032)
							(mid 0.275042 0.275042)
							(end 0.2032 0.3048)
						)
						(arc
							(start -0.2032 0.3048)
							(mid -0.275042 0.275042)
							(end -0.3048 0.2032)
						)
						(arc
							(start -0.3048 -0.2032)
							(mid -0.275042 -0.275042)
							(end -0.2032 -0.3048)
						)
						(arc
							(start 0.2032 -0.3048)
							(mid 0.275042 -0.275042)
							(end 0.3048 -0.2032)
						)
					)
					(width 0)
					(fill yes)
				)
			)
		)
	)
	(footprint ""
		(layer "B.Cu")
		(at 127.2794 -29.1084 -90)
		(property "Reference" "CU8"
			(at 0 0 90)
			(layer "B.SilkS")
			(hide yes)
			(effects
				(font
					(size 1.27 1.27)
				)
				(justify mirror)
			)
		)
		(property "Value" "SC1U10V2KX-4-GP"
			(at -1.1811 -2.7051 270)
			(unlocked yes)
			(layer "B.Fab")
			(hide yes)
			(effects
				(font
					(size 1.016 1.016)
					(thickness 0.1524)
				)
				(justify mirror)
			)
		)
		(property "Device Type" "C402H22"
			(at -1.1811 -4.2291 270)
			(unlocked yes)
			(layer "B.Fab")
			(hide yes)
			(effects
				(font
					(size 1.016 1.016)
					(thickness 0.1524)
				)
				(justify mirror)
			)
		)
		(duplicate_pad_numbers_are_jumpers no)
		(fp_rect
			(start 0.4318 0.9525)
			(end -0.4318 -0.9525)
			(stroke
				(width 0)
				(type default)
			)
			(fill no)
			(layer "B.CrtYd")
		)
		(fp_rect
			(start 0.4318 0.9525)
			(end -0.4318 -0.9525)
			(stroke
				(width 0)
				(type default)
			)
			(fill no)
			(layer "B.Fab")
		)
		(pad "1" smd custom
			(at 0 -0.4445 90)
			(size 0.1524 0.1524)
			(layers "B.Cu" "B.Mask" "B.Paste")
			(net "P3V3_USB_HUB")
			(options
				(clearance outline)
				(anchor circle)
			)
			(primitives
				(gr_poly
					(pts
						(arc
							(start 0.3048 0.2032)
							(mid 0.275042 0.275042)
							(end 0.2032 0.3048)
						)
						(arc
							(start -0.2032 0.3048)
							(mid -0.275042 0.275042)
							(end -0.3048 0.2032)
						)
						(arc
							(start -0.3048 -0.2032)
							(mid -0.275042 -0.275042)
							(end -0.2032 -0.3048)
						)
						(arc
							(start 0.2032 -0.3048)
							(mid 0.275042 -0.275042)
							(end 0.3048 -0.2032)
						)
					)
					(width 0)
					(fill yes)
				)
			)
		)
		(pad "2" smd custom
			(at 0 0.4445 90)
			(size 0.1524 0.1524)
			(layers "B.Cu" "B.Mask" "B.Paste")
			(net "GND")
			(options
				(clearance outline)
				(anchor circle)
			)
			(primitives
				(gr_poly
					(pts
						(arc
							(start 0.3048 0.2032)
							(mid 0.275042 0.275042)
							(end 0.2032 0.3048)
						)
						(arc
							(start -0.2032 0.3048)
							(mid -0.275042 0.275042)
							(end -0.3048 0.2032)
						)
						(arc
							(start -0.3048 -0.2032)
							(mid -0.275042 -0.275042)
							(end -0.2032 -0.3048)
						)
						(arc
							(start 0.2032 -0.3048)
							(mid 0.275042 -0.275042)
							(end 0.3048 -0.2032)
						)
					)
					(width 0)
					(fill yes)
				)
			)
		)
	)
	(footprint ""
		(layer "B.Cu")
		(at 14.2748 -8.4836 180)
		(property "Reference" "PR2"
			(at 0 0 0)
			(layer "B.SilkS")
			(hide yes)
			(effects
				(font
					(size 1.27 1.27)
				)
				(justify mirror)
			)
		)
		(property "Value" "10R3F-GP"
			(at 0.0254 -2.5146 180)
			(unlocked yes)
			(layer "B.Fab")
			(hide yes)
			(effects
				(font
					(size 1.016 1.016)
					(thickness 0.1524)
				)
				(justify mirror)
			)
		)
		(property "Device Type" "R603H22"
			(at 0.0254 -4.0386 180)
			(unlocked yes)
			(layer "B.Fab")
			(hide yes)
			(effects
				(font
					(size 1.016 1.016)
					(thickness 0.1524)
				)
				(justify mirror)
			)
		)
		(duplicate_pad_numbers_are_jumpers no)
		(fp_line
			(start 0.4826 0)
			(end 0.2032 0)
			(stroke
				(width 0.2032)
				(type default)
			)
			(layer "B.SilkS")
		)
		(fp_line
			(start -0.2032 0)
			(end -0.4826 0)
			(stroke
				(width 0.2032)
				(type default)
			)
			(layer "B.SilkS")
		)
		(fp_rect
			(start 0.5842 1.3335)
			(end -0.5842 -1.3335)
			(stroke
				(width 0)
				(type default)
			)
			(fill no)
			(layer "B.CrtYd")
		)
		(fp_rect
			(start 0.5842 1.3335)
			(end -0.5842 -1.3335)
			(stroke
				(width 0)
				(type default)
			)
			(fill no)
			(layer "B.Fab")
		)
		(pad "1" smd custom
			(at 0 -0.762)
			(size 0.2159 0.2159)
			(layers "B.Cu" "B.Mask" "B.Paste")
			(net "P3V3_VR")
			(options
				(clearance outline)
				(anchor circle)
			)
			(primitives
				(gr_poly
					(pts
						(arc
							(start -0.3302 0.4318)
							(mid -0.402042 0.402042)
							(end -0.4318 0.3302)
						)
						(arc
							(start -0.4318 -0.3302)
							(mid -0.402042 -0.402042)
							(end -0.3302 -0.4318)
						)
						(arc
							(start 0.3302 -0.4318)
							(mid 0.402042 -0.402042)
							(end 0.4318 -0.3302)
						)
						(arc
							(start 0.4318 0.3302)
							(mid 0.402042 0.402042)
							(end 0.3302 0.4318)
						)
					)
					(width 0)
					(fill yes)
				)
			)
		)
		(pad "2" smd custom
			(at 0 0.762)
			(size 0.2159 0.2159)
			(layers "B.Cu" "B.Mask" "B.Paste")
			(net "P3V3_VFB_R")
			(options
				(clearance outline)
				(anchor circle)
			)
			(primitives
				(gr_poly
					(pts
						(arc
							(start -0.3302 0.4318)
							(mid -0.402042 0.402042)
							(end -0.4318 0.3302)
						)
						(arc
							(start -0.4318 -0.3302)
							(mid -0.402042 -0.402042)
							(end -0.3302 -0.4318)
						)
						(arc
							(start 0.3302 -0.4318)
							(mid 0.402042 -0.402042)
							(end 0.4318 -0.3302)
						)
						(arc
							(start 0.4318 0.3302)
							(mid 0.402042 0.402042)
							(end 0.3302 0.4318)
						)
					)
					(width 0)
					(fill yes)
				)
			)
		)
	)
	(footprint ""
		(layer "B.Cu")
		(at 16.256 -5.969)
		(property "Reference" "PG1"
			(at 0 0 0)
			(layer "B.SilkS")
			(hide yes)
			(effects
				(font
					(size 1.27 1.27)
				)
				(justify mirror)
			)
		)
		(property "Value" "COPPER-CLOSE-GP-U"
			(at -0.0762 -2.8702 0)
			(unlocked yes)
			(layer "B.Fab")
			(hide yes)
			(effects
				(font
					(size 1.016 1.016)
					(thickness 0.1524)
				)
				(justify mirror)
			)
		)
		(property "Device Type" "CON2C-U"
			(at -0.0762 -4.3942 0)
			(unlocked yes)
			(layer "B.Fab")
			(hide yes)
			(effects
				(font
					(size 1.016 1.016)
					(thickness 0.1524)
				)
				(justify mirror)
			)
		)
		(duplicate_pad_numbers_are_jumpers no)
		(fp_rect
			(start 0.9398 0.9652)
			(end -0.9398 -0.9652)
			(stroke
				(width 0)
				(type default)
			)
			(fill no)
			(layer "B.CrtYd")
		)
		(fp_rect
			(start 0.9398 0.9652)
			(end -0.9398 -0.9652)
			(stroke
				(width 0)
				(type default)
			)
			(fill no)
			(layer "B.Fab")
		)
		(pad "1" smd custom
			(at 0 -0.5334 180)
			(size 0.17145 0.17145)
			(layers "B.Cu" "B.Mask" "B.Paste")
			(net "AGND_P3V3")
			(options
				(clearance outline)
				(anchor circle)
			)
			(primitives
				(gr_poly
					(pts
						(xy -0.127 -0.3429) (xy -0.127 -0.1651) (xy -0.635 0.3429) (xy 0.635 0.3429) (xy 0.127 -0.1651)
						(xy 0.127 -0.3429)
					)
					(width 0)
					(fill yes)
				)
			)
		)
		(pad "2" smd custom
			(at 0 0.5334 180)
			(size 0.17145 0.17145)
			(layers "B.Cu" "B.Mask" "B.Paste")
			(net "GND")
			(options
				(clearance outline)
				(anchor circle)
			)
			(primitives
				(gr_poly
					(pts
						(xy -0.635 -0.3429) (xy -0.127 0.1651) (xy -0.127 0.3429) (xy 0.127 0.3429) (xy 0.127 0.1651)
						(xy 0.635 -0.3429)
					)
					(width 0)
					(fill yes)
				)
			)
		)
	)
	(footprint ""
		(layer "B.Cu")
		(at 16.1925 -13.4366 90)
		(property "Reference" "PR8"
			(at 0 0 90)
			(layer "B.SilkS")
			(hide yes)
			(effects
				(font
					(size 1.27 1.27)
				)
				(justify mirror)
			)
		)
		(property "Value" "19K6R2F-GP"
			(at -0.064008 -3.993896 90)
			(unlocked yes)
			(layer "B.Fab")
			(hide yes)
			(effects
				(font
					(size 1.016 1.016)
					(thickness 0.1524)
				)
				(justify mirror)
			)
		)
		(property "Device Type" "R402H16"
			(at -0.064008 -5.517896 90)
			(unlocked yes)
			(layer "B.Fab")
			(hide yes)
			(effects
				(font
					(size 1.016 1.016)
					(thickness 0.1524)
				)
				(justify mirror)
			)
		)
		(duplicate_pad_numbers_are_jumpers no)
		(fp_line
			(start 0.508 -0.9398)
			(end 0.508 0.9398)
			(stroke
				(width 0.1524)
				(type default)
			)
			(layer "B.SilkS")
		)
		(fp_line
			(start -0.508 -0.9398)
			(end 0.508 -0.9398)
			(stroke
				(width 0.1524)
				(type default)
			)
			(layer "B.SilkS")
		)
		(fp_rect
			(start 0.508 0.9398)
			(end -0.508 -0.9398)
			(stroke
				(width 0)
				(type default)
			)
			(fill no)
			(layer "B.CrtYd")
		)
		(fp_rect
			(start 0.508 0.9398)
			(end -0.508 -0.9398)
			(stroke
				(width 0)
				(type default)
			)
			(fill no)
			(layer "B.Fab")
		)
		(pad "1" smd custom
			(at 0 -0.4445 270)
			(size 0.1397 0.1397)
			(layers "B.Cu" "B.Mask" "B.Paste")
			(net "P12V")
			(options
				(clearance outline)
				(anchor circle)
			)
			(primitives
				(gr_poly
					(pts
						(arc
							(start -0.1778 0.2794)
							(mid -0.249642 0.249642)
							(end -0.2794 0.1778)
						)
						(arc
							(start -0.2794 -0.1778)
							(mid -0.249642 -0.249642)
							(end -0.1778 -0.2794)
						)
						(arc
							(start 0.1778 -0.2794)
							(mid 0.249642 -0.249642)
							(end 0.2794 -0.1778)
						)
						(arc
							(start 0.2794 0.1778)
							(mid 0.249642 0.249642)
							(end 0.1778 0.2794)
						)
					)
					(width 0)
					(fill yes)
				)
			)
		)
		(pad "2" smd custom
			(at 0 0.4445 270)
			(size 0.1397 0.1397)
			(layers "B.Cu" "B.Mask" "B.Paste")
			(net "P3V3_EN")
			(options
				(clearance outline)
				(anchor circle)
			)
			(primitives
				(gr_poly
					(pts
						(arc
							(start -0.1778 0.2794)
							(mid -0.249642 0.249642)
							(end -0.2794 0.1778)
						)
						(arc
							(start -0.2794 -0.1778)
							(mid -0.249642 -0.249642)
							(end -0.1778 -0.2794)
						)
						(arc
							(start 0.1778 -0.2794)
							(mid 0.249642 -0.249642)
							(end 0.2794 -0.1778)
						)
						(arc
							(start 0.2794 0.1778)
							(mid 0.249642 0.249642)
							(end 0.1778 0.2794)
						)
					)
					(width 0)
					(fill yes)
				)
			)
		)
	)
	(footprint ""
		(layer "B.Cu")
		(at 34.29 -1.0922 -90)
		(property "Reference" "C18"
			(at 0 0 90)
			(layer "B.SilkS")
			(hide yes)
			(effects
				(font
					(size 1.27 1.27)
				)
				(justify mirror)
			)
		)
		(property "Value" "SCD1U16V2KX-3GP"
			(at -1.1811 -2.7051 270)
			(unlocked yes)
			(layer "B.Fab")
			(hide yes)
			(effects
				(font
					(size 1.016 1.016)
					(thickness 0.1524)
				)
				(justify mirror)
			)
		)
		(property "Device Type" "C402H22"
			(at -1.1811 -4.2291 270)
			(unlocked yes)
			(layer "B.Fab")
			(hide yes)
			(effects
				(font
					(size 1.016 1.016)
					(thickness 0.1524)
				)
				(justify mirror)
			)
		)
		(duplicate_pad_numbers_are_jumpers no)
		(fp_rect
			(start 0.4318 0.9525)
			(end -0.4318 -0.9525)
			(stroke
				(width 0)
				(type default)
			)
			(fill no)
			(layer "B.CrtYd")
		)
		(fp_rect
			(start 0.4318 0.9525)
			(end -0.4318 -0.9525)
			(stroke
				(width 0)
				(type default)
			)
			(fill no)
			(layer "B.Fab")
		)
		(pad "1" smd custom
			(at 0 -0.4445 90)
			(size 0.1524 0.1524)
			(layers "B.Cu" "B.Mask" "B.Paste")
			(net "P3V3")
			(options
				(clearance outline)
				(anchor circle)
			)
			(primitives
				(gr_poly
					(pts
						(arc
							(start 0.3048 0.2032)
							(mid 0.275042 0.275042)
							(end 0.2032 0.3048)
						)
						(arc
							(start -0.2032 0.3048)
							(mid -0.275042 0.275042)
							(end -0.3048 0.2032)
						)
						(arc
							(start -0.3048 -0.2032)
							(mid -0.275042 -0.275042)
							(end -0.2032 -0.3048)
						)
						(arc
							(start 0.2032 -0.3048)
							(mid 0.275042 -0.275042)
							(end 0.3048 -0.2032)
						)
					)
					(width 0)
					(fill yes)
				)
			)
		)
		(pad "2" smd custom
			(at 0 0.4445 90)
			(size 0.1524 0.1524)
			(layers "B.Cu" "B.Mask" "B.Paste")
			(net "GND")
			(options
				(clearance outline)
				(anchor circle)
			)
			(primitives
				(gr_poly
					(pts
						(arc
							(start 0.3048 0.2032)
							(mid 0.275042 0.275042)
							(end 0.2032 0.3048)
						)
						(arc
							(start -0.2032 0.3048)
							(mid -0.275042 0.275042)
							(end -0.3048 0.2032)
						)
						(arc
							(start -0.3048 -0.2032)
							(mid -0.275042 -0.275042)
							(end -0.2032 -0.3048)
						)
						(arc
							(start 0.2032 -0.3048)
							(mid 0.275042 -0.275042)
							(end 0.3048 -0.2032)
						)
					)
					(width 0)
					(fill yes)
				)
			)
		)
	)
	(footprint ""
		(layer "B.Cu")
		(at 130.0988 -24.9936 180)
		(property "Reference" "R168"
			(at 0 0 0)
			(layer "B.SilkS")
			(hide yes)
			(effects
				(font
					(size 1.27 1.27)
				)
				(justify mirror)
			)
		)
		(property "Value" "0R2F-1-GP"
			(at -0.064008 -3.993896 180)
			(unlocked yes)
			(layer "B.Fab")
			(hide yes)
			(effects
				(font
					(size 1.016 1.016)
					(thickness 0.1524)
				)
				(justify mirror)
			)
		)
		(property "Device Type" "R402H16"
			(at -0.064008 -5.517896 180)
			(unlocked yes)
			(layer "B.Fab")
			(hide yes)
			(effects
				(font
					(size 1.016 1.016)
					(thickness 0.1524)
				)
				(justify mirror)
			)
		)
		(duplicate_pad_numbers_are_jumpers no)
		(fp_line
			(start 0.508 -0.9398)
			(end 0.508 0.9398)
			(stroke
				(width 0.1524)
				(type default)
			)
			(layer "B.SilkS")
		)
		(fp_line
			(start -0.508 -0.9398)
			(end 0.508 -0.9398)
			(stroke
				(width 0.1524)
				(type default)
			)
			(layer "B.SilkS")
		)
		(fp_rect
			(start 0.508 0.9398)
			(end -0.508 -0.9398)
			(stroke
				(width 0)
				(type default)
			)
			(fill no)
			(layer "B.CrtYd")
		)
		(fp_rect
			(start 0.508 0.9398)
			(end -0.508 -0.9398)
			(stroke
				(width 0)
				(type default)
			)
			(fill no)
			(layer "B.Fab")
		)
		(pad "1" smd custom
			(at 0 -0.4445)
			(size 0.1397 0.1397)
			(layers "B.Cu" "B.Mask" "B.Paste")
			(net "SMCLK_USB_HUB")
			(options
				(clearance outline)
				(anchor circle)
			)
			(primitives
				(gr_poly
					(pts
						(arc
							(start -0.1778 0.2794)
							(mid -0.249642 0.249642)
							(end -0.2794 0.1778)
						)
						(arc
							(start -0.2794 -0.1778)
							(mid -0.249642 -0.249642)
							(end -0.1778 -0.2794)
						)
						(arc
							(start 0.1778 -0.2794)
							(mid 0.249642 -0.249642)
							(end 0.2794 -0.1778)
						)
						(arc
							(start 0.2794 0.1778)
							(mid 0.249642 0.249642)
							(end 0.1778 0.2794)
						)
					)
					(width 0)
					(fill yes)
				)
			)
		)
		(pad "2" smd custom
			(at 0 0.4445)
			(size 0.1397 0.1397)
			(layers "B.Cu" "B.Mask" "B.Paste")
			(net "SMCLK_PCH_DEVICE")
			(options
				(clearance outline)
				(anchor circle)
			)
			(primitives
				(gr_poly
					(pts
						(arc
							(start -0.1778 0.2794)
							(mid -0.249642 0.249642)
							(end -0.2794 0.1778)
						)
						(arc
							(start -0.2794 -0.1778)
							(mid -0.249642 -0.249642)
							(end -0.1778 -0.2794)
						)
						(arc
							(start 0.1778 -0.2794)
							(mid 0.249642 -0.249642)
							(end 0.2794 -0.1778)
						)
						(arc
							(start 0.2794 0.1778)
							(mid 0.249642 0.249642)
							(end 0.1778 0.2794)
						)
					)
					(width 0)
					(fill yes)
				)
			)
		)
	)
	(footprint ""
		(layer "B.Cu")
		(at 26.7208 -22.1742 90)
		(property "Reference" "R173"
			(at 0 0 90)
			(layer "B.SilkS")
			(hide yes)
			(effects
				(font
					(size 1.27 1.27)
				)
				(justify mirror)
			)
		)
		(property "Value" "0R2F-1-GP"
			(at -0.064008 -3.993896 90)
			(unlocked yes)
			(layer "B.Fab")
			(hide yes)
			(effects
				(font
					(size 1.016 1.016)
					(thickness 0.1524)
				)
				(justify mirror)
			)
		)
		(property "Device Type" "R402H16"
			(at -0.064008 -5.517896 90)
			(unlocked yes)
			(layer "B.Fab")
			(hide yes)
			(effects
				(font
					(size 1.016 1.016)
					(thickness 0.1524)
				)
				(justify mirror)
			)
		)
		(duplicate_pad_numbers_are_jumpers no)
		(fp_line
			(start 0.508 -0.9398)
			(end 0.508 0.9398)
			(stroke
				(width 0.1524)
				(type default)
			)
			(layer "B.SilkS")
		)
		(fp_line
			(start -0.508 -0.9398)
			(end 0.508 -0.9398)
			(stroke
				(width 0.1524)
				(type default)
			)
			(layer "B.SilkS")
		)
		(fp_rect
			(start 0.508 0.9398)
			(end -0.508 -0.9398)
			(stroke
				(width 0)
				(type default)
			)
			(fill no)
			(layer "B.CrtYd")
		)
		(fp_rect
			(start 0.508 0.9398)
			(end -0.508 -0.9398)
			(stroke
				(width 0)
				(type default)
			)
			(fill no)
			(layer "B.Fab")
		)
		(pad "1" smd custom
			(at 0 -0.4445 270)
			(size 0.1397 0.1397)
			(layers "B.Cu" "B.Mask" "B.Paste")
			(net "SMB_VMONITOR_ATX_ALERT_N")
			(options
				(clearance outline)
				(anchor circle)
			)
			(primitives
				(gr_poly
					(pts
						(arc
							(start -0.1778 0.2794)
							(mid -0.249642 0.249642)
							(end -0.2794 0.1778)
						)
						(arc
							(start -0.2794 -0.1778)
							(mid -0.249642 -0.249642)
							(end -0.1778 -0.2794)
						)
						(arc
							(start 0.1778 -0.2794)
							(mid 0.249642 -0.249642)
							(end 0.2794 -0.1778)
						)
						(arc
							(start 0.2794 0.1778)
							(mid 0.249642 0.249642)
							(end 0.1778 0.2794)
						)
					)
					(width 0)
					(fill yes)
				)
			)
		)
		(pad "2" smd custom
			(at 0 0.4445 270)
			(size 0.1397 0.1397)
			(layers "B.Cu" "B.Mask" "B.Paste")
			(net "SMB_BMC_DEVICE_ALERT_N")
			(options
				(clearance outline)
				(anchor circle)
			)
			(primitives
				(gr_poly
					(pts
						(arc
							(start -0.1778 0.2794)
							(mid -0.249642 0.249642)
							(end -0.2794 0.1778)
						)
						(arc
							(start -0.2794 -0.1778)
							(mid -0.249642 -0.249642)
							(end -0.1778 -0.2794)
						)
						(arc
							(start 0.1778 -0.2794)
							(mid 0.249642 -0.249642)
							(end 0.2794 -0.1778)
						)
						(arc
							(start 0.2794 0.1778)
							(mid 0.249642 0.249642)
							(end 0.1778 0.2794)
						)
					)
					(width 0)
					(fill yes)
				)
			)
		)
	)
	(footprint ""
		(layer "B.Cu")
		(at 23.0632 -1.0668)
		(property "Reference" "PL2"
			(at 0 0 0)
			(layer "B.SilkS")
			(hide yes)
			(effects
				(font
					(size 1.27 1.27)
				)
				(justify mirror)
			)
		)
		(property "Value" "COIL-1D5UH-47-GP"
			(at 5.6134 -2.4892 0)
			(unlocked yes)
			(layer "B.Fab")
			(hide yes)
			(effects
				(font
					(size 1.016 1.016)
					(thickness 0.1524)
				)
				(justify mirror)
			)
		)
		(property "Device Type" "L7166-1830-UH197"
			(at 5.6134 -4.0132 0)
			(unlocked yes)
			(layer "B.Fab")
			(hide yes)
			(effects
				(font
					(size 1.016 1.016)
					(thickness 0.1524)
				)
				(justify mirror)
			)
		)
		(duplicate_pad_numbers_are_jumpers no)
		(fp_line
			(start -3.556 -4.5466)
			(end -3.556 4.5466)
			(stroke
				(width 0.1524)
				(type default)
			)
			(layer "B.SilkS")
		)
		(fp_line
			(start -3.556 4.5466)
			(end 3.556 4.5466)
			(stroke
				(width 0.1524)
				(type default)
			)
			(layer "B.SilkS")
		)
		(fp_line
			(start 3.556 -4.5466)
			(end -3.556 -4.5466)
			(stroke
				(width 0.1524)
				(type default)
			)
			(layer "B.SilkS")
		)
		(fp_line
			(start 3.556 4.5466)
			(end 3.556 -4.5466)
			(stroke
				(width 0.1524)
				(type default)
			)
			(layer "B.SilkS")
		)
		(fp_rect
			(start 3.302 3.5306)
			(end -3.302 -3.5306)
			(stroke
				(width 0)
				(type default)
			)
			(fill no)
			(layer "B.CrtYd")
		)
		(fp_poly
			(pts
				(xy 3.81 4.6228) (xy 3.81 -2.3241) (xy 3.302 -2.3241) (xy 3.302 3.5306) (xy -3.302 3.5306) (xy -3.302 -3.5306)
				(xy 3.302 -3.5306) (xy 3.302 -2.3368) (xy 3.81 -2.3368) (xy 3.81 -4.6228) (xy -3.81 -4.6228) (xy -3.81 4.6228)
			)
			(stroke
				(width 0)
				(type default)
			)
			(fill no)
			(layer "B.CrtYd")
		)
		(fp_rect
			(start 3.81 4.6228)
			(end -3.81 -4.6228)
			(stroke
				(width 0)
				(type default)
			)
			(fill no)
			(layer "B.Fab")
		)
		(pad "1" smd rect
			(at 0 -2.804922 180)
			(size 3.5052 2.9718)
			(layers "B.Cu" "B.Mask" "B.Paste")
			(net "P3V3_SW")
		)
		(pad "2" smd rect
			(at 0 2.804922 180)
			(size 3.5052 2.9718)
			(layers "B.Cu" "B.Mask" "B.Paste")
			(net "P3V3_VR")
		)
	)
	(footprint ""
		(layer "B.Cu")
		(at 122.809 -4.6863 -90)
		(property "Reference" "R19"
			(at 0 0 90)
			(layer "B.SilkS")
			(hide yes)
			(effects
				(font
					(size 1.27 1.27)
				)
				(justify mirror)
			)
		)
		(property "Value" "4K7R2F-GP"
			(at -0.064008 -3.993896 270)
			(unlocked yes)
			(layer "B.Fab")
			(hide yes)
			(effects
				(font
					(size 1.016 1.016)
					(thickness 0.1524)
				)
				(justify mirror)
			)
		)
		(property "Device Type" "R402H16"
			(at -0.064008 -5.517896 270)
			(unlocked yes)
			(layer "B.Fab")
			(hide yes)
			(effects
				(font
					(size 1.016 1.016)
					(thickness 0.1524)
				)
				(justify mirror)
			)
		)
		(duplicate_pad_numbers_are_jumpers no)
		(fp_line
			(start -0.508 -0.9398)
			(end 0.508 -0.9398)
			(stroke
				(width 0.1524)
				(type default)
			)
			(layer "B.SilkS")
		)
		(fp_line
			(start 0.508 -0.9398)
			(end 0.508 0.9398)
			(stroke
				(width 0.1524)
				(type default)
			)
			(layer "B.SilkS")
		)
		(fp_rect
			(start 0.508 0.9398)
			(end -0.508 -0.9398)
			(stroke
				(width 0)
				(type default)
			)
			(fill no)
			(layer "B.CrtYd")
		)
		(fp_rect
			(start 0.508 0.9398)
			(end -0.508 -0.9398)
			(stroke
				(width 0)
				(type default)
			)
			(fill no)
			(layer "B.Fab")
		)
		(pad "1" smd custom
			(at 0 -0.4445 90)
			(size 0.1397 0.1397)
			(layers "B.Cu" "B.Mask" "B.Paste")
			(net "P3V3_STBY")
			(options
				(clearance outline)
				(anchor circle)
			)
			(primitives
				(gr_poly
					(pts
						(arc
							(start -0.1778 0.2794)
							(mid -0.249642 0.249642)
							(end -0.2794 0.1778)
						)
						(arc
							(start -0.2794 -0.1778)
							(mid -0.249642 -0.249642)
							(end -0.1778 -0.2794)
						)
						(arc
							(start 0.1778 -0.2794)
							(mid 0.249642 -0.249642)
							(end 0.2794 -0.1778)
						)
						(arc
							(start 0.2794 0.1778)
							(mid 0.249642 0.249642)
							(end 0.1778 0.2794)
						)
					)
					(width 0)
					(fill yes)
				)
			)
		)
		(pad "2" smd custom
			(at 0 0.4445 90)
			(size 0.1397 0.1397)
			(layers "B.Cu" "B.Mask" "B.Paste")
			(net "SMCLK_PCH_SLOT2")
			(options
				(clearance outline)
				(anchor circle)
			)
			(primitives
				(gr_poly
					(pts
						(arc
							(start -0.1778 0.2794)
							(mid -0.249642 0.249642)
							(end -0.2794 0.1778)
						)
						(arc
							(start -0.2794 -0.1778)
							(mid -0.249642 -0.249642)
							(end -0.1778 -0.2794)
						)
						(arc
							(start 0.1778 -0.2794)
							(mid 0.249642 -0.249642)
							(end 0.2794 -0.1778)
						)
						(arc
							(start 0.2794 0.1778)
							(mid 0.249642 0.249642)
							(end 0.1778 0.2794)
						)
					)
					(width 0)
					(fill yes)
				)
			)
		)
	)
	(footprint ""
		(layer "B.Cu")
		(at 26.3652 -23.6474)
		(property "Reference" "R151"
			(at 0 0 0)
			(layer "B.SilkS")
			(hide yes)
			(effects
				(font
					(size 1.27 1.27)
				)
				(justify mirror)
			)
		)
		(property "Value" "10KR2F-2-GP"
			(at -0.064008 -3.993896 0)
			(unlocked yes)
			(layer "B.Fab")
			(hide yes)
			(effects
				(font
					(size 1.016 1.016)
					(thickness 0.1524)
				)
				(justify mirror)
			)
		)
		(property "Device Type" "R402H16"
			(at -0.064008 -5.517896 0)
			(unlocked yes)
			(layer "B.Fab")
			(hide yes)
			(effects
				(font
					(size 1.016 1.016)
					(thickness 0.1524)
				)
				(justify mirror)
			)
		)
		(duplicate_pad_numbers_are_jumpers no)
		(fp_line
			(start -0.508 -0.9398)
			(end 0.508 -0.9398)
			(stroke
				(width 0.1524)
				(type default)
			)
			(layer "B.SilkS")
		)
		(fp_line
			(start 0.508 -0.9398)
			(end 0.508 0.9398)
			(stroke
				(width 0.1524)
				(type default)
			)
			(layer "B.SilkS")
		)
		(fp_rect
			(start 0.508 0.9398)
			(end -0.508 -0.9398)
			(stroke
				(width 0)
				(type default)
			)
			(fill no)
			(layer "B.CrtYd")
		)
		(fp_rect
			(start 0.508 0.9398)
			(end -0.508 -0.9398)
			(stroke
				(width 0)
				(type default)
			)
			(fill no)
			(layer "B.Fab")
		)
		(pad "1" smd custom
			(at 0 -0.4445 180)
			(size 0.1397 0.1397)
			(layers "B.Cu" "B.Mask" "B.Paste")
			(net "P3V3_STBY")
			(options
				(clearance outline)
				(anchor circle)
			)
			(primitives
				(gr_poly
					(pts
						(arc
							(start -0.1778 0.2794)
							(mid -0.249642 0.249642)
							(end -0.2794 0.1778)
						)
						(arc
							(start -0.2794 -0.1778)
							(mid -0.249642 -0.249642)
							(end -0.1778 -0.2794)
						)
						(arc
							(start 0.1778 -0.2794)
							(mid 0.249642 -0.249642)
							(end 0.2794 -0.1778)
						)
						(arc
							(start 0.2794 0.1778)
							(mid 0.249642 0.249642)
							(end 0.1778 0.2794)
						)
					)
					(width 0)
					(fill yes)
				)
			)
		)
		(pad "2" smd custom
			(at 0 0.4445 180)
			(size 0.1397 0.1397)
			(layers "B.Cu" "B.Mask" "B.Paste")
			(net "ATX_VMONITOR_A0")
			(options
				(clearance outline)
				(anchor circle)
			)
			(primitives
				(gr_poly
					(pts
						(arc
							(start -0.1778 0.2794)
							(mid -0.249642 0.249642)
							(end -0.2794 0.1778)
						)
						(arc
							(start -0.2794 -0.1778)
							(mid -0.249642 -0.249642)
							(end -0.1778 -0.2794)
						)
						(arc
							(start 0.1778 -0.2794)
							(mid 0.249642 -0.249642)
							(end 0.2794 -0.1778)
						)
						(arc
							(start 0.2794 0.1778)
							(mid 0.249642 0.249642)
							(end 0.1778 0.2794)
						)
					)
					(width 0)
					(fill yes)
				)
			)
		)
	)
	(footprint ""
		(layer "B.Cu")
		(at 124.587 -11.7094)
		(property "Reference" "R31"
			(at 0 0 0)
			(layer "B.SilkS")
			(hide yes)
			(effects
				(font
					(size 1.27 1.27)
				)
				(justify mirror)
			)
		)
		(property "Value" "10KR2F-2-GP"
			(at -0.064008 -3.993896 0)
			(unlocked yes)
			(layer "B.Fab")
			(hide yes)
			(effects
				(font
					(size 1.016 1.016)
					(thickness 0.1524)
				)
				(justify mirror)
			)
		)
		(property "Device Type" "R402H16"
			(at -0.064008 -5.517896 0)
			(unlocked yes)
			(layer "B.Fab")
			(hide yes)
			(effects
				(font
					(size 1.016 1.016)
					(thickness 0.1524)
				)
				(justify mirror)
			)
		)
		(duplicate_pad_numbers_are_jumpers no)
		(fp_line
			(start -0.508 -0.9398)
			(end 0.508 -0.9398)
			(stroke
				(width 0.1524)
				(type default)
			)
			(layer "B.SilkS")
		)
		(fp_line
			(start 0.508 -0.9398)
			(end 0.508 0.9398)
			(stroke
				(width 0.1524)
				(type default)
			)
			(layer "B.SilkS")
		)
		(fp_rect
			(start 0.508 0.9398)
			(end -0.508 -0.9398)
			(stroke
				(width 0)
				(type default)
			)
			(fill no)
			(layer "B.CrtYd")
		)
		(fp_rect
			(start 0.508 0.9398)
			(end -0.508 -0.9398)
			(stroke
				(width 0)
				(type default)
			)
			(fill no)
			(layer "B.Fab")
		)
		(pad "1" smd custom
			(at 0 -0.4445 180)
			(size 0.1397 0.1397)
			(layers "B.Cu" "B.Mask" "B.Paste")
			(net "P3V3_STBY")
			(options
				(clearance outline)
				(anchor circle)
			)
			(primitives
				(gr_poly
					(pts
						(arc
							(start -0.1778 0.2794)
							(mid -0.249642 0.249642)
							(end -0.2794 0.1778)
						)
						(arc
							(start -0.2794 -0.1778)
							(mid -0.249642 -0.249642)
							(end -0.1778 -0.2794)
						)
						(arc
							(start 0.1778 -0.2794)
							(mid 0.249642 -0.249642)
							(end 0.2794 -0.1778)
						)
						(arc
							(start 0.2794 0.1778)
							(mid 0.249642 0.249642)
							(end 0.1778 0.2794)
						)
					)
					(width 0)
					(fill yes)
				)
			)
		)
		(pad "2" smd custom
			(at 0 0.4445 180)
			(size 0.1397 0.1397)
			(layers "B.Cu" "B.Mask" "B.Paste")
			(net "SMB_P_HUB_A0")
			(options
				(clearance outline)
				(anchor circle)
			)
			(primitives
				(gr_poly
					(pts
						(arc
							(start -0.1778 0.2794)
							(mid -0.249642 0.249642)
							(end -0.2794 0.1778)
						)
						(arc
							(start -0.2794 -0.1778)
							(mid -0.249642 -0.249642)
							(end -0.1778 -0.2794)
						)
						(arc
							(start 0.1778 -0.2794)
							(mid 0.249642 -0.249642)
							(end 0.2794 -0.1778)
						)
						(arc
							(start 0.2794 0.1778)
							(mid 0.249642 0.249642)
							(end 0.1778 0.2794)
						)
					)
					(width 0)
					(fill yes)
				)
			)
		)
	)
	(footprint ""
		(layer "B.Cu")
		(at 15.8623 -26.5811 -45)
		(property "Reference" "R102"
			(at 0 0 135)
			(layer "B.SilkS")
			(hide yes)
			(effects
				(font
					(size 1.27 1.27)
				)
				(justify mirror)
			)
		)
		(property "Value" "10R2F-L-GP"
			(at -0.063939 -3.993984 315)
			(unlocked yes)
			(layer "B.Fab")
			(hide yes)
			(effects
				(font
					(size 1.016 1.016)
					(thickness 0.1524)
				)
				(justify mirror)
			)
		)
		(property "Device Type" "R402H14"
			(at -0.064299 -5.517754 315)
			(unlocked yes)
			(layer "B.Fab")
			(hide yes)
			(effects
				(font
					(size 1.016 1.016)
					(thickness 0.1524)
				)
				(justify mirror)
			)
		)
		(duplicate_pad_numbers_are_jumpers no)
		(fp_line
			(start -0.508103 -0.939874)
			(end 0.508103 -0.939874)
			(stroke
				(width 0.1524)
				(type default)
			)
			(layer "B.SilkS")
		)
		(fp_line
			(start 0.508103 -0.939874)
			(end 0.508103 0.939874)
			(stroke
				(width 0.1524)
				(type default)
			)
			(layer "B.SilkS")
		)
		(fp_poly
			(pts
				(xy -0.507896 0.939874) (xy -0.507897 -0.939726) (xy 0.508103 -0.939727) (xy 0.508103 0.939874)
			)
			(stroke
				(width 0)
				(type default)
			)
			(fill no)
			(layer "B.CrtYd")
		)
		(fp_poly
			(pts
				(xy -0.507896 0.939874) (xy -0.507897 -0.939726) (xy 0.508103 -0.939727) (xy 0.508103 0.939874)
			)
			(stroke
				(width 0)
				(type default)
			)
			(fill no)
			(layer "B.Fab")
		)
		(pad "1" smd custom
			(at 0 -0.4445 135)
			(size 0.1397 0.1397)
			(layers "B.Cu" "B.Mask" "B.Paste")
			(net "P12V")
			(options
				(clearance outline)
				(anchor circle)
			)
			(primitives
				(gr_poly
					(pts
						(arc
							(start -0.1778 0.2794)
							(mid -0.249642 0.249642)
							(end -0.2794 0.1778)
						)
						(arc
							(start -0.2794 -0.1778)
							(mid -0.249642 -0.249642)
							(end -0.1778 -0.2794)
						)
						(arc
							(start 0.1778 -0.2794)
							(mid 0.249642 -0.249642)
							(end 0.2794 -0.1778)
						)
						(arc
							(start 0.2794 0.1778)
							(mid 0.249642 0.249642)
							(end 0.1778 0.2794)
						)
					)
					(width 0)
					(fill yes)
				)
			)
		)
		(pad "2" smd custom
			(at 0 0.4445 135)
			(size 0.1397 0.1397)
			(layers "B.Cu" "B.Mask" "B.Paste")
			(net "ATX_P12V_SENSE_VP_R")
			(options
				(clearance outline)
				(anchor circle)
			)
			(primitives
				(gr_poly
					(pts
						(arc
							(start -0.1778 0.2794)
							(mid -0.249642 0.249642)
							(end -0.2794 0.1778)
						)
						(arc
							(start -0.2794 -0.1778)
							(mid -0.249642 -0.249642)
							(end -0.1778 -0.2794)
						)
						(arc
							(start 0.1778 -0.2794)
							(mid 0.249642 -0.249642)
							(end 0.2794 -0.1778)
						)
						(arc
							(start 0.2794 0.1778)
							(mid 0.249642 0.249642)
							(end 0.1778 0.2794)
						)
					)
					(width 0)
					(fill yes)
				)
			)
		)
	)
	(footprint ""
		(layer "B.Cu")
		(at 122.9106 -18.5674 90)
		(property "Reference" "CU61"
			(at 0 0 90)
			(layer "B.SilkS")
			(hide yes)
			(effects
				(font
					(size 1.27 1.27)
				)
				(justify mirror)
			)
		)
		(property "Value" "SCD1U16V2KX-3GP"
			(at -1.1811 -2.7051 90)
			(unlocked yes)
			(layer "B.Fab")
			(hide yes)
			(effects
				(font
					(size 1.016 1.016)
					(thickness 0.1524)
				)
				(justify mirror)
			)
		)
		(property "Device Type" "C402H22"
			(at -1.1811 -4.2291 90)
			(unlocked yes)
			(layer "B.Fab")
			(hide yes)
			(effects
				(font
					(size 1.016 1.016)
					(thickness 0.1524)
				)
				(justify mirror)
			)
		)
		(duplicate_pad_numbers_are_jumpers no)
		(fp_rect
			(start 0.4318 0.9525)
			(end -0.4318 -0.9525)
			(stroke
				(width 0)
				(type default)
			)
			(fill no)
			(layer "B.CrtYd")
		)
		(fp_rect
			(start 0.4318 0.9525)
			(end -0.4318 -0.9525)
			(stroke
				(width 0)
				(type default)
			)
			(fill no)
			(layer "B.Fab")
		)
		(pad "1" smd custom
			(at 0 -0.4445 270)
			(size 0.1524 0.1524)
			(layers "B.Cu" "B.Mask" "B.Paste")
			(net "P3V3_USB_HUB")
			(options
				(clearance outline)
				(anchor circle)
			)
			(primitives
				(gr_poly
					(pts
						(arc
							(start 0.3048 0.2032)
							(mid 0.275042 0.275042)
							(end 0.2032 0.3048)
						)
						(arc
							(start -0.2032 0.3048)
							(mid -0.275042 0.275042)
							(end -0.3048 0.2032)
						)
						(arc
							(start -0.3048 -0.2032)
							(mid -0.275042 -0.275042)
							(end -0.2032 -0.3048)
						)
						(arc
							(start 0.2032 -0.3048)
							(mid 0.275042 -0.275042)
							(end 0.3048 -0.2032)
						)
					)
					(width 0)
					(fill yes)
				)
			)
		)
		(pad "2" smd custom
			(at 0 0.4445 270)
			(size 0.1524 0.1524)
			(layers "B.Cu" "B.Mask" "B.Paste")
			(net "GND")
			(options
				(clearance outline)
				(anchor circle)
			)
			(primitives
				(gr_poly
					(pts
						(arc
							(start 0.3048 0.2032)
							(mid 0.275042 0.275042)
							(end 0.2032 0.3048)
						)
						(arc
							(start -0.2032 0.3048)
							(mid -0.275042 0.275042)
							(end -0.3048 0.2032)
						)
						(arc
							(start -0.3048 -0.2032)
							(mid -0.275042 -0.275042)
							(end -0.2032 -0.3048)
						)
						(arc
							(start 0.2032 -0.3048)
							(mid 0.275042 -0.275042)
							(end 0.3048 -0.2032)
						)
					)
					(width 0)
					(fill yes)
				)
			)
		)
	)
	(footprint ""
		(layer "B.Cu")
		(at 41.7195 1.9939 -90)
		(property "Reference" "R50"
			(at 0 0 90)
			(layer "B.SilkS")
			(hide yes)
			(effects
				(font
					(size 1.27 1.27)
				)
				(justify mirror)
			)
		)
		(property "Value" "0R2F-1-GP"
			(at -0.064008 -3.993896 270)
			(unlocked yes)
			(layer "B.Fab")
			(hide yes)
			(effects
				(font
					(size 1.016 1.016)
					(thickness 0.1524)
				)
				(justify mirror)
			)
		)
		(property "Device Type" "R402H16"
			(at -0.064008 -5.517896 270)
			(unlocked yes)
			(layer "B.Fab")
			(hide yes)
			(effects
				(font
					(size 1.016 1.016)
					(thickness 0.1524)
				)
				(justify mirror)
			)
		)
		(duplicate_pad_numbers_are_jumpers no)
		(fp_line
			(start -0.508 -0.9398)
			(end 0.508 -0.9398)
			(stroke
				(width 0.1524)
				(type default)
			)
			(layer "B.SilkS")
		)
		(fp_line
			(start 0.508 -0.9398)
			(end 0.508 0.9398)
			(stroke
				(width 0.1524)
				(type default)
			)
			(layer "B.SilkS")
		)
		(fp_rect
			(start 0.508 0.9398)
			(end -0.508 -0.9398)
			(stroke
				(width 0)
				(type default)
			)
			(fill no)
			(layer "B.CrtYd")
		)
		(fp_rect
			(start 0.508 0.9398)
			(end -0.508 -0.9398)
			(stroke
				(width 0)
				(type default)
			)
			(fill no)
			(layer "B.Fab")
		)
		(pad "1" smd custom
			(at 0 -0.4445 90)
			(size 0.1397 0.1397)
			(layers "B.Cu" "B.Mask" "B.Paste")
			(net "SMCLK_PCH_R")
			(options
				(clearance outline)
				(anchor circle)
			)
			(primitives
				(gr_poly
					(pts
						(arc
							(start -0.1778 0.2794)
							(mid -0.249642 0.249642)
							(end -0.2794 0.1778)
						)
						(arc
							(start -0.2794 -0.1778)
							(mid -0.249642 -0.249642)
							(end -0.1778 -0.2794)
						)
						(arc
							(start 0.1778 -0.2794)
							(mid 0.249642 -0.249642)
							(end 0.2794 -0.1778)
						)
						(arc
							(start 0.2794 0.1778)
							(mid 0.249642 0.249642)
							(end 0.1778 0.2794)
						)
					)
					(width 0)
					(fill yes)
				)
			)
		)
		(pad "2" smd custom
			(at 0 0.4445 90)
			(size 0.1397 0.1397)
			(layers "B.Cu" "B.Mask" "B.Paste")
			(net "SMB_HOST_STBY_LVC3_SCL_R5")
			(options
				(clearance outline)
				(anchor circle)
			)
			(primitives
				(gr_poly
					(pts
						(arc
							(start -0.1778 0.2794)
							(mid -0.249642 0.249642)
							(end -0.2794 0.1778)
						)
						(arc
							(start -0.2794 -0.1778)
							(mid -0.249642 -0.249642)
							(end -0.1778 -0.2794)
						)
						(arc
							(start 0.1778 -0.2794)
							(mid 0.249642 -0.249642)
							(end 0.2794 -0.1778)
						)
						(arc
							(start 0.2794 0.1778)
							(mid 0.249642 0.249642)
							(end 0.1778 0.2794)
						)
					)
					(width 0)
					(fill yes)
				)
			)
		)
	)
	(gr_line
		(start 16.667734 -19.952208)
		(end 17.082008 -19.952208)
		(stroke
			(width 0.1016)
			(type default)
		)
		(layer "F.Cu")
	)
	(gr_line
		(start 17.084548 -19.952208)
		(end 17.132808 -19.952208)
		(stroke
			(width 0.1016)
			(type default)
		)
		(layer "F.Cu")
	)
	(gr_line
		(start 17.132808 -19.952208)
		(end 17.3609 -20.1803)
		(stroke
			(width 0.1016)
			(type default)
		)
		(layer "F.Cu")
	)
	(gr_line
		(start 17.3609 -20.60194)
		(end 17.656556 -20.60194)
		(stroke
			(width 0.1016)
			(type default)
		)
		(layer "F.Cu")
	)
	(gr_line
		(start 17.3609 -20.306284)
		(end 17.3609 -20.60194)
		(stroke
			(width 0.1016)
			(type default)
		)
		(layer "F.Cu")
	)
	(gr_line
		(start 17.3609 -20.1803)
		(end 17.3609 -20.303744)
		(stroke
			(width 0.1016)
			(type default)
		)
		(layer "F.Cu")
	)
	(gr_line
		(start 17.414748 -19.726148)
		(end 17.662144 -19.973544)
		(stroke
			(width 0.1016)
			(type default)
		)
		(layer "F.Cu")
	)
	(gr_line
		(start 17.414748 -19.622008)
		(end 17.414748 -19.726148)
		(stroke
			(width 0.1016)
			(type default)
		)
		(layer "F.Cu")
	)
	(gr_line
		(start 17.414748 -19.205448)
		(end 17.414748 -19.619468)
		(stroke
			(width 0.1016)
			(type default)
		)
		(layer "F.Cu")
	)
	(gr_line
		(start 17.6403 -24.003)
		(end 17.9324 -23.7109)
		(stroke
			(width 0.1016)
			(type default)
		)
		(layer "F.Cu")
	)
	(gr_line
		(start 17.6403 -22.9616)
		(end 17.9959 -23.3172)
		(stroke
			(width 0.1016)
			(type default)
		)
		(layer "F.Cu")
	)
	(gr_line
		(start 17.659096 -20.60194)
		(end 17.810734 -20.60194)
		(stroke
			(width 0.1016)
			(type default)
		)
		(layer "F.Cu")
	)
	(gr_line
		(start 17.662144 -19.973544)
		(end 17.6911 -19.973544)
		(stroke
			(width 0.1016)
			(type default)
		)
		(layer "F.Cu")
	)
	(gr_line
		(start 17.69364 -19.973544)
		(end 17.989296 -19.973544)
		(stroke
			(width 0.1016)
			(type default)
		)
		(layer "F.Cu")
	)
	(gr_line
		(start 17.9324 -23.7109)
		(end 18.3896 -23.7109)
		(stroke
			(width 0.1016)
			(type default)
		)
		(layer "F.Cu")
	)
	(gr_line
		(start 17.989296 -20.27174)
		(end 17.989296 -20.313396)
		(stroke
			(width 0.1016)
			(type default)
		)
		(layer "F.Cu")
	)
	(gr_line
		(start 17.989296 -19.973544)
		(end 17.989296 -20.2692)
		(stroke
			(width 0.1016)
			(type default)
		)
		(layer "F.Cu")
	)
	(gr_line
		(start 17.9959 -23.3172)
		(end 18.3007 -23.3172)
		(stroke
			(width 0.1016)
			(type default)
		)
		(layer "F.Cu")
	)
	(gr_line
		(start 18.3007 -23.3172)
		(end 18.5928 -23.0251)
		(stroke
			(width 0.1016)
			(type default)
		)
		(layer "F.Cu")
	)
	(gr_line
		(start 18.3896 -23.7109)
		(end 18.5928 -23.9141)
		(stroke
			(width 0.1016)
			(type default)
		)
		(layer "F.Cu")
	)
	(gr_line
		(start 18.5928 -23.9141)
		(end 18.802096 -23.704804)
		(stroke
			(width 0.1016)
			(type default)
		)
		(layer "F.Cu")
	)
	(gr_line
		(start 18.5928 -23.0251)
		(end 18.802096 -23.234396)
		(stroke
			(width 0.1016)
			(type default)
		)
		(layer "F.Cu")
	)
	(gr_line
		(start 20.013676 -20.499324)
		(end 20.013676 -20.654518)
		(stroke
			(width 0.1016)
			(type default)
		)
		(layer "F.Cu")
	)
	(gr_line
		(start 20.013676 -20.028662)
		(end 20.013676 -20.496784)
		(stroke
			(width 0.1016)
			(type default)
		)
		(layer "F.Cu")
	)
	(gr_line
		(start 20.305776 -20.829524)
		(end 20.343876 -20.829524)
		(stroke
			(width 0.1016)
			(type default)
		)
		(layer "F.Cu")
	)
	(gr_line
		(start 20.346416 -20.829524)
		(end 20.814538 -20.829524)
		(stroke
			(width 0.1016)
			(type default)
		)
		(layer "F.Cu")
	)
	(gr_line
		(start 20.699476 -25.782016)
		(end 20.699476 -26.250138)
		(stroke
			(width 0.1016)
			(type default)
		)
		(layer "F.Cu")
	)
	(gr_line
		(start 20.699476 -25.687782)
		(end 20.699476 -25.779476)
		(stroke
			(width 0.1016)
			(type default)
		)
		(layer "F.Cu")
	)
	(gr_line
		(start 20.928076 -25.449276)
		(end 21.029676 -25.449276)
		(stroke
			(width 0.1016)
			(type default)
		)
		(layer "F.Cu")
	)
	(gr_line
		(start 21.032216 -25.449276)
		(end 21.500338 -25.449276)
		(stroke
			(width 0.1016)
			(type default)
		)
		(layer "F.Cu")
	)
	(gr_arc
		(start 28.379928 10.9474)
		(mid 28.402433 10.834257)
		(end 28.466542 10.738358)
		(stroke
			(width 0.0635)
			(type default)
		)
		(layer "F.Cu")
	)
	(gr_line
		(start 28.379928 12.133072)
		(end 28.379928 10.9474)
		(stroke
			(width 0.0635)
			(type default)
		)
		(layer "F.Cu")
	)
	(gr_line
		(start 28.466542 10.738358)
		(end 28.503626 10.701274)
		(stroke
			(width 0.0635)
			(type default)
		)
		(layer "F.Cu")
	)
	(gr_arc
		(start 28.627324 10.157206)
		(mid 28.629496 10.107868)
		(end 28.63596 10.058908)
		(stroke
			(width 0.0635)
			(type default)
		)
		(layer "F.Cu")
	)
	(gr_arc
		(start 28.627324 10.40257)
		(mid 28.595203 10.564234)
		(end 28.503626 10.701274)
		(stroke
			(width 0.0635)
			(type default)
		)
		(layer "F.Cu")
	)
	(gr_line
		(start 28.767532 9.311894)
		(end 28.772612 9.2837)
		(stroke
			(width 0.0635)
			(type default)
		)
		(layer "F.Cu")
	)
	(gr_line
		(start 28.772612 9.2837)
		(end 28.788868 9.260332)
		(stroke
			(width 0.0635)
			(type default)
		)
		(layer "F.Cu")
	)
	(gr_arc
		(start 29.056076 10.808716)
		(mid 28.964319 10.671581)
		(end 28.932124 10.509758)
		(stroke
			(width 0.0635)
			(type default)
		)
		(layer "F.Cu")
	)
	(gr_arc
		(start 29.056076 10.808716)
		(mid 29.147637 10.945767)
		(end 29.179774 11.10742)
		(stroke
			(width 0.0635)
			(type default)
		)
		(layer "F.Cu")
	)
	(gr_line
		(start 29.179774 12.133072)
		(end 29.179774 11.10742)
		(stroke
			(width 0.0635)
			(type default)
		)
		(layer "F.Cu")
	)
	(gr_line
		(start 29.183076 8.697214)
		(end 29.191966 8.684514)
		(stroke
			(width 0.0635)
			(type default)
		)
		(layer "F.Cu")
	)
	(gr_line
		(start 29.191966 8.684514)
		(end 29.204666 8.675624)
		(stroke
			(width 0.0635)
			(type default)
		)
		(layer "F.Cu")
	)
	(gr_line
		(start 29.826712 8.240268)
		(end 29.854398 8.22071)
		(stroke
			(width 0.0635)
			(type default)
		)
		(layer "F.Cu")
	)
	(gr_line
		(start 29.854398 8.22071)
		(end 29.888942 8.215884)
		(stroke
			(width 0.0635)
			(type default)
		)
		(layer "F.Cu")
	)
	(gr_arc
		(start 35.579812 11.039856)
		(mid 35.61199 10.878017)
		(end 35.703764 10.740898)
		(stroke
			(width 0.0635)
			(type default)
		)
		(layer "F.Cu")
	)
	(gr_line
		(start 35.579812 12.133072)
		(end 35.579812 11.039856)
		(stroke
			(width 0.0635)
			(type default)
		)
		(layer "F.Cu")
	)
	(gr_arc
		(start 35.827462 10.442194)
		(mid 35.795309 10.60384)
		(end 35.703764 10.740898)
		(stroke
			(width 0.0635)
			(type default)
		)
		(layer "F.Cu")
	)
	(gr_line
		(start 35.862006 9.721596)
		(end 35.867086 9.692894)
		(stroke
			(width 0.0635)
			(type default)
		)
		(layer "F.Cu")
	)
	(gr_line
		(start 35.867086 9.692894)
		(end 35.883596 9.669526)
		(stroke
			(width 0.0635)
			(type default)
		)
		(layer "F.Cu")
	)
	(gr_arc
		(start 36.25596 10.729214)
		(mid 36.164406 10.592027)
		(end 36.132262 10.430256)
		(stroke
			(width 0.0635)
			(type default)
		)
		(layer "F.Cu")
	)
	(gr_line
		(start 36.25596 10.729214)
		(end 36.293044 10.766298)
		(stroke
			(width 0.0635)
			(type default)
		)
		(layer "F.Cu")
	)
	(gr_arc
		(start 36.293044 10.766298)
		(mid 36.357314 10.862295)
		(end 36.379912 10.975594)
		(stroke
			(width 0.0635)
			(type default)
		)
		(layer "F.Cu")
	)
	(gr_line
		(start 36.379912 12.133072)
		(end 36.379912 10.975594)
		(stroke
			(width 0.0635)
			(type default)
		)
		(layer "F.Cu")
	)
	(gr_line
		(start 36.41852 7.611618)
		(end 36.449 7.6073)
		(stroke
			(width 0.0635)
			(type default)
		)
		(layer "F.Cu")
	)
	(gr_line
		(start 36.449 7.6073)
		(end 36.474654 7.590282)
		(stroke
			(width 0.0635)
			(type default)
		)
		(layer "F.Cu")
	)
	(gr_line
		(start 36.49726 8.793226)
		(end 36.50615 8.780526)
		(stroke
			(width 0.0635)
			(type default)
		)
		(layer "F.Cu")
	)
	(gr_line
		(start 36.50615 8.780526)
		(end 36.51885 8.771636)
		(stroke
			(width 0.0635)
			(type default)
		)
		(layer "F.Cu")
	)
	(gr_arc
		(start 37.979858 11.039348)
		(mid 38.012001 10.877576)
		(end 38.103556 10.74039)
		(stroke
			(width 0.0635)
			(type default)
		)
		(layer "F.Cu")
	)
	(gr_line
		(start 37.979858 12.133072)
		(end 37.979858 11.039348)
		(stroke
			(width 0.0635)
			(type default)
		)
		(layer "F.Cu")
	)
	(gr_line
		(start 38.103556 10.74039)
		(end 38.14064 10.703306)
		(stroke
			(width 0.0635)
			(type default)
		)
		(layer "F.Cu")
	)
	(gr_arc
		(start 38.227508 10.49401)
		(mid 38.204907 10.607304)
		(end 38.14064 10.703306)
		(stroke
			(width 0.0635)
			(type default)
		)
		(layer "F.Cu")
	)
	(gr_line
		(start 38.272212 9.675368)
		(end 38.277292 9.647174)
		(stroke
			(width 0.0635)
			(type default)
		)
		(layer "F.Cu")
	)
	(gr_line
		(start 38.277292 9.647174)
		(end 38.293294 9.624568)
		(stroke
			(width 0.0635)
			(type default)
		)
		(layer "F.Cu")
	)
	(gr_arc
		(start 38.65626 10.76706)
		(mid 38.564543 10.629915)
		(end 38.532308 10.468102)
		(stroke
			(width 0.0635)
			(type default)
		)
		(layer "F.Cu")
	)
	(gr_arc
		(start 38.65626 10.76706)
		(mid 38.747832 10.904107)
		(end 38.779958 11.065764)
		(stroke
			(width 0.0635)
			(type default)
		)
		(layer "F.Cu")
	)
	(gr_line
		(start 38.779958 12.133072)
		(end 38.779958 11.065764)
		(stroke
			(width 0.0635)
			(type default)
		)
		(layer "F.Cu")
	)
	(gr_line
		(start 38.902132 8.754618)
		(end 38.93693 8.705088)
		(stroke
			(width 0.0635)
			(type default)
		)
		(layer "F.Cu")
	)
	(gr_line
		(start 38.947852 8.68934)
		(end 38.94836 8.688578)
		(stroke
			(width 0.0635)
			(type default)
		)
		(layer "F.Cu")
	)
	(gr_line
		(start 38.94836 8.688578)
		(end 38.948614 8.688324)
		(stroke
			(width 0.0635)
			(type default)
		)
		(layer "F.Cu")
	)
	(gr_line
		(start 38.948614 8.688324)
		(end 38.95217 8.688324)
		(stroke
			(width 0.0635)
			(type default)
		)
		(layer "F.Cu")
	)
	(gr_line
		(start 39.167816 8.90397)
		(end 39.173912 8.897874)
		(stroke
			(width 0.0635)
			(type default)
		)
		(layer "F.Cu")
	)
	(gr_line
		(start 39.167816 8.907018)
		(end 39.167816 8.90397)
		(stroke
			(width 0.0635)
			(type default)
		)
		(layer "F.Cu")
	)
	(gr_line
		(start 40.18661 4.75361)
		(end 40.198548 4.745482)
		(stroke
			(width 0.0635)
			(type default)
		)
		(layer "F.Cu")
	)
	(gr_line
		(start 40.198548 4.745482)
		(end 40.21328 4.741926)
		(stroke
			(width 0.0635)
			(type default)
		)
		(layer "F.Cu")
	)
	(gr_line
		(start 40.624252 5.89661)
		(end 40.650922 5.878068)
		(stroke
			(width 0.0635)
			(type default)
		)
		(layer "F.Cu")
	)
	(gr_line
		(start 40.650922 5.878068)
		(end 40.682164 5.873496)
		(stroke
			(width 0.0635)
			(type default)
		)
		(layer "F.Cu")
	)
	(gr_line
		(start 41.50868 6.988048)
		(end 41.534588 6.971284)
		(stroke
			(width 0.0635)
			(type default)
		)
		(layer "F.Cu")
	)
	(gr_line
		(start 41.534588 6.971284)
		(end 41.56456 6.96722)
		(stroke
			(width 0.0635)
			(type default)
		)
		(layer "F.Cu")
	)
	(gr_line
		(start 44.331382 6.901942)
		(end 44.339002 6.900926)
		(stroke
			(width 0.0635)
			(type default)
		)
		(layer "F.Cu")
	)
	(gr_line
		(start 44.339002 6.900926)
		(end 44.346622 6.89737)
		(stroke
			(width 0.0635)
			(type default)
		)
		(layer "F.Cu")
	)
	(gr_line
		(start 44.387516 -6.4008)
		(end 44.42587 -6.378194)
		(stroke
			(width 0.0635)
			(type default)
		)
		(layer "F.Cu")
	)
	(gr_line
		(start 44.411138 3.848608)
		(end 44.415456 3.847084)
		(stroke
			(width 0.0635)
			(type default)
		)
		(layer "F.Cu")
	)
	(gr_line
		(start 44.415456 3.847084)
		(end 44.419266 3.844544)
		(stroke
			(width 0.0635)
			(type default)
		)
		(layer "F.Cu")
	)
	(gr_line
		(start 44.632626 -5.898896)
		(end 44.693586 -5.662168)
		(stroke
			(width 0.0635)
			(type default)
		)
		(layer "F.Cu")
	)
	(gr_line
		(start 44.693586 -5.662168)
		(end 45.021754 -5.468366)
		(stroke
			(width 0.0635)
			(type default)
		)
		(layer "F.Cu")
	)
	(gr_line
		(start 44.821094 -6.14426)
		(end 45.381418 -5.813298)
		(stroke
			(width 0.0635)
			(type default)
		)
		(layer "F.Cu")
	)
	(gr_line
		(start 45.021754 -5.468366)
		(end 45.258228 -5.529072)
		(stroke
			(width 0.0635)
			(type default)
		)
		(layer "F.Cu")
	)
	(gr_line
		(start 45.079412 -11.749786)
		(end 45.454824 -12.499848)
		(stroke
			(width 0.0635)
			(type default)
		)
		(layer "F.Cu")
	)
	(gr_arc
		(start 45.179996 11.02741)
		(mid 45.212149 10.865764)
		(end 45.303694 10.728706)
		(stroke
			(width 0.0635)
			(type default)
		)
		(layer "F.Cu")
	)
	(gr_line
		(start 45.179996 12.133072)
		(end 45.179996 11.02741)
		(stroke
			(width 0.0635)
			(type default)
		)
		(layer "F.Cu")
	)
	(gr_line
		(start 45.261784 -5.530088)
		(end 45.305472 -5.50418)
		(stroke
			(width 0.0635)
			(type default)
		)
		(layer "F.Cu")
	)
	(gr_line
		(start 45.390054 3.177794)
		(end 45.392848 3.176016)
		(stroke
			(width 0.0635)
			(type default)
		)
		(layer "F.Cu")
	)
	(gr_line
		(start 45.392848 3.176016)
		(end 45.395134 3.173476)
		(stroke
			(width 0.0635)
			(type default)
		)
		(layer "F.Cu")
	)
	(gr_line
		(start 45.408596 -5.797042)
		(end 45.577506 -5.697474)
		(stroke
			(width 0.0635)
			(type default)
		)
		(layer "F.Cu")
	)
	(gr_arc
		(start 45.427392 10.430002)
		(mid 45.395258 10.591657)
		(end 45.303694 10.728706)
		(stroke
			(width 0.0635)
			(type default)
		)
		(layer "F.Cu")
	)
	(gr_arc
		(start 45.454824 -12.499848)
		(mid 45.52831 -12.563515)
		(end 45.625258 -12.55649)
		(stroke
			(width 0.0635)
			(type default)
		)
		(layer "F.Cu")
	)
	(gr_line
		(start 45.554138 4.636008)
		(end 45.562774 4.637278)
		(stroke
			(width 0.0635)
			(type default)
		)
		(layer "F.Cu")
	)
	(gr_line
		(start 45.562774 4.637278)
		(end 45.564044 4.636262)
		(stroke
			(width 0.0635)
			(type default)
		)
		(layer "F.Cu")
	)
	(gr_line
		(start 45.564044 4.636262)
		(end 45.564806 4.635754)
		(stroke
			(width 0.0635)
			(type default)
		)
		(layer "F.Cu")
	)
	(gr_line
		(start 45.564806 4.635754)
		(end 45.574712 4.628134)
		(stroke
			(width 0.0635)
			(type default)
		)
		(layer "F.Cu")
	)
	(gr_line
		(start 45.573442 9.32688)
		(end 45.578522 9.298686)
		(stroke
			(width 0.0635)
			(type default)
		)
		(layer "F.Cu")
	)
	(gr_line
		(start 45.578522 9.298686)
		(end 45.594524 9.27608)
		(stroke
			(width 0.0635)
			(type default)
		)
		(layer "F.Cu")
	)
	(gr_line
		(start 45.59046 -5.33273)
		(end 45.65142 -5.096002)
		(stroke
			(width 0.0635)
			(type default)
		)
		(layer "F.Cu")
	)
	(gr_line
		(start 45.622718 4.936236)
		(end 45.716952 4.900168)
		(stroke
			(width 0.0635)
			(type default)
		)
		(layer "F.Cu")
	)
	(gr_line
		(start 45.625258 -12.55649)
		(end 45.625512 -12.55649)
		(stroke
			(width 0.0635)
			(type default)
		)
		(layer "F.Cu")
	)
	(gr_line
		(start 45.625512 -12.55649)
		(end 45.62856 -12.554966)
		(stroke
			(width 0.0635)
			(type default)
		)
		(layer "F.Cu")
	)
	(gr_line
		(start 45.65142 -5.096002)
		(end 45.979334 -4.9022)
		(stroke
			(width 0.0635)
			(type default)
		)
		(layer "F.Cu")
	)
	(gr_line
		(start 45.668946 9.169654)
		(end 45.84192 8.922512)
		(stroke
			(width 0.0635)
			(type default)
		)
		(layer "F.Cu")
	)
	(gr_line
		(start 45.70476 -12.99972)
		(end 46.080172 -13.750036)
		(stroke
			(width 0.0635)
			(type default)
		)
		(layer "F.Cu")
	)
	(gr_line
		(start 45.729398 4.895342)
		(end 45.7454 4.8895)
		(stroke
			(width 0.0635)
			(type default)
		)
		(layer "F.Cu")
	)
	(gr_line
		(start 45.7454 4.8895)
		(end 45.746416 4.883658)
		(stroke
			(width 0.0635)
			(type default)
		)
		(layer "F.Cu")
	)
	(gr_arc
		(start 45.761402 -12.829286)
		(mid 45.697783 -12.902772)
		(end 45.70476 -12.99972)
		(stroke
			(width 0.0635)
			(type default)
		)
		(layer "F.Cu")
	)
	(gr_line
		(start 45.761402 -12.829286)
		(end 45.761656 -12.829286)
		(stroke
			(width 0.0635)
			(type default)
		)
		(layer "F.Cu")
	)
	(gr_line
		(start 45.778928 -5.578094)
		(end 46.340268 -5.246624)
		(stroke
			(width 0.0635)
			(type default)
		)
		(layer "F.Cu")
	)
	(gr_arc
		(start 45.856144 10.804144)
		(mid 45.764387 10.667009)
		(end 45.732192 10.505186)
		(stroke
			(width 0.0635)
			(type default)
		)
		(layer "F.Cu")
	)
	(gr_arc
		(start 45.856144 10.804144)
		(mid 45.947703 10.941195)
		(end 45.979842 11.102848)
		(stroke
			(width 0.0635)
			(type default)
		)
		(layer "F.Cu")
	)
	(gr_line
		(start 45.8597 8.897366)
		(end 46.232064 8.36549)
		(stroke
			(width 0.0635)
			(type default)
		)
		(layer "F.Cu")
	)
	(gr_line
		(start 45.923962 9.336532)
		(end 46.085506 9.1059)
		(stroke
			(width 0.0635)
			(type default)
		)
		(layer "F.Cu")
	)
	(gr_line
		(start 45.979334 -4.9022)
		(end 46.216062 -4.96316)
		(stroke
			(width 0.0635)
			(type default)
		)
		(layer "F.Cu")
	)
	(gr_line
		(start 45.979842 12.133072)
		(end 45.979842 11.102848)
		(stroke
			(width 0.0635)
			(type default)
		)
		(layer "F.Cu")
	)
	(gr_line
		(start 46.080172 -7.250176)
		(end 46.454568 -7.999984)
		(stroke
			(width 0.0635)
			(type default)
		)
		(layer "F.Cu")
	)
	(gr_line
		(start 46.083982 4.625086)
		(end 46.091348 4.619498)
		(stroke
			(width 0.0635)
			(type default)
		)
		(layer "F.Cu")
	)
	(gr_line
		(start 46.085506 9.1059)
		(end 46.08576 9.1059)
		(stroke
			(width 0.0635)
			(type default)
		)
		(layer "F.Cu")
	)
	(gr_line
		(start 46.089062 9.105138)
		(end 46.3296 9.062974)
		(stroke
			(width 0.0635)
			(type default)
		)
		(layer "F.Cu")
	)
	(gr_line
		(start 46.091348 4.619498)
		(end 46.096682 4.612132)
		(stroke
			(width 0.0635)
			(type default)
		)
		(layer "F.Cu")
	)
	(gr_line
		(start 46.251622 8.337296)
		(end 46.323758 8.234426)
		(stroke
			(width 0.0635)
			(type default)
		)
		(layer "F.Cu")
	)
	(gr_line
		(start 46.3296 9.062974)
		(end 46.548294 8.750808)
		(stroke
			(width 0.0635)
			(type default)
		)
		(layer "F.Cu")
	)
	(gr_arc
		(start 46.454568 -7.999984)
		(mid 46.527982 -8.063713)
		(end 46.625002 -8.05688)
		(stroke
			(width 0.0635)
			(type default)
		)
		(layer "F.Cu")
	)
	(gr_line
		(start 46.496732 7.987792)
		(end 46.870874 7.453376)
		(stroke
			(width 0.0635)
			(type default)
		)
		(layer "F.Cu")
	)
	(gr_line
		(start 46.505114 8.506714)
		(end 46.57344 8.409432)
		(stroke
			(width 0.0635)
			(type default)
		)
		(layer "F.Cu")
	)
	(gr_line
		(start 46.505876 8.51027)
		(end 46.548294 8.750808)
		(stroke
			(width 0.0635)
			(type default)
		)
		(layer "F.Cu")
	)
	(gr_line
		(start 46.625002 -8.05688)
		(end 46.625256 -8.05688)
		(stroke
			(width 0.0635)
			(type default)
		)
		(layer "F.Cu")
	)
	(gr_line
		(start 46.625256 -8.05688)
		(end 46.626272 -8.056372)
		(stroke
			(width 0.0635)
			(type default)
		)
		(layer "F.Cu")
	)
	(gr_line
		(start 46.626272 -8.056372)
		(end 46.633638 -8.052816)
		(stroke
			(width 0.0635)
			(type default)
		)
		(layer "F.Cu")
	)
	(gr_line
		(start 46.698408 5.808472)
		(end 46.735746 5.7912)
		(stroke
			(width 0.0635)
			(type default)
		)
		(layer "F.Cu")
	)
	(gr_line
		(start 46.704758 -8.499856)
		(end 47.079662 -9.250426)
		(stroke
			(width 0.0635)
			(type default)
		)
		(layer "F.Cu")
	)
	(gr_line
		(start 46.72711 8.194294)
		(end 46.967902 8.151622)
		(stroke
			(width 0.0635)
			(type default)
		)
		(layer "F.Cu")
	)
	(gr_line
		(start 46.735746 5.7912)
		(end 46.759876 5.757926)
		(stroke
			(width 0.0635)
			(type default)
		)
		(layer "F.Cu")
	)
	(gr_arc
		(start 46.761654 -8.329422)
		(mid 46.698026 -8.402891)
		(end 46.704758 -8.499856)
		(stroke
			(width 0.0635)
			(type default)
		)
		(layer "F.Cu")
	)
	(gr_line
		(start 46.761654 -8.329422)
		(end 46.761908 -8.329422)
		(stroke
			(width 0.0635)
			(type default)
		)
		(layer "F.Cu")
	)
	(gr_line
		(start 46.9519 -6.994652)
		(end 46.963076 -6.970522)
		(stroke
			(width 0.0635)
			(type default)
		)
		(layer "F.Cu")
	)
	(gr_line
		(start 46.967902 8.151622)
		(end 47.186342 7.839456)
		(stroke
			(width 0.0635)
			(type default)
		)
		(layer "F.Cu")
	)
	(gr_line
		(start 46.977046 -6.939788)
		(end 46.980856 -6.931152)
		(stroke
			(width 0.0635)
			(type default)
		)
		(layer "F.Cu")
	)
	(gr_line
		(start 47.143924 7.598918)
		(end 47.186342 7.839456)
		(stroke
			(width 0.0635)
			(type default)
		)
		(layer "F.Cu")
	)
	(gr_line
		(start 47.20082 -6.451346)
		(end 47.209202 -6.43382)
		(stroke
			(width 0.0635)
			(type default)
		)
		(layer "F.Cu")
	)
	(gr_line
		(start 47.209202 -6.43382)
		(end 47.223172 -6.420612)
		(stroke
			(width 0.0635)
			(type default)
		)
		(layer "F.Cu")
	)
	(gr_line
		(start 47.2567 -7.060946)
		(end 47.264066 -7.04469)
		(stroke
			(width 0.0635)
			(type default)
		)
		(layer "F.Cu")
	)
	(gr_line
		(start 47.458376 -4.585716)
		(end 47.470314 -4.578858)
		(stroke
			(width 0.0635)
			(type default)
		)
		(layer "F.Cu")
	)
	(gr_line
		(start 47.466504 -6.188964)
		(end 47.474378 -5.944362)
		(stroke
			(width 0.0635)
			(type default)
		)
		(layer "F.Cu")
	)
	(gr_line
		(start 47.470314 -4.578858)
		(end 47.479458 -4.567682)
		(stroke
			(width 0.0635)
			(type default)
		)
		(layer "F.Cu")
	)
	(gr_line
		(start 47.474378 -5.944362)
		(end 47.752 -5.683758)
		(stroke
			(width 0.0635)
			(type default)
		)
		(layer "F.Cu")
	)
	(gr_arc
		(start 47.579788 11.065256)
		(mid 47.61197 10.903421)
		(end 47.70374 10.766298)
		(stroke
			(width 0.0635)
			(type default)
		)
		(layer "F.Cu")
	)
	(gr_line
		(start 47.579788 12.133072)
		(end 47.579788 11.065256)
		(stroke
			(width 0.0635)
			(type default)
		)
		(layer "F.Cu")
	)
	(gr_line
		(start 47.702724 -6.389116)
		(end 48.182276 -5.938774)
		(stroke
			(width 0.0635)
			(type default)
		)
		(layer "F.Cu")
	)
	(gr_line
		(start 47.752 -5.683758)
		(end 47.996602 -5.691378)
		(stroke
			(width 0.0635)
			(type default)
		)
		(layer "F.Cu")
	)
	(gr_arc
		(start 47.827438 10.467594)
		(mid 47.795285 10.62924)
		(end 47.70374 10.766298)
		(stroke
			(width 0.0635)
			(type default)
		)
		(layer "F.Cu")
	)
	(gr_line
		(start 47.967646 9.359392)
		(end 47.981362 9.28243)
		(stroke
			(width 0.0635)
			(type default)
		)
		(layer "F.Cu")
	)
	(gr_line
		(start 47.981362 9.281922)
		(end 47.981362 9.28243)
		(stroke
			(width 0.0635)
			(type default)
		)
		(layer "F.Cu")
	)
	(gr_line
		(start 47.984156 9.266174)
		(end 47.985426 9.258808)
		(stroke
			(width 0.0635)
			(type default)
		)
		(layer "F.Cu")
	)
	(gr_line
		(start 47.985426 9.258808)
		(end 47.987204 9.258046)
		(stroke
			(width 0.0635)
			(type default)
		)
		(layer "F.Cu")
	)
	(gr_line
		(start 48.201326 -3.696462)
		(end 48.224186 -3.668776)
		(stroke
			(width 0.0635)
			(type default)
		)
		(layer "F.Cu")
	)
	(gr_line
		(start 48.224186 -3.668776)
		(end 48.23206 -3.633724)
		(stroke
			(width 0.0635)
			(type default)
		)
		(layer "F.Cu")
	)
	(gr_arc
		(start 48.255936 10.790936)
		(mid 48.164364 10.653889)
		(end 48.132238 10.492232)
		(stroke
			(width 0.0635)
			(type default)
		)
		(layer "F.Cu")
	)
	(gr_arc
		(start 48.255936 10.790936)
		(mid 48.347664 10.928214)
		(end 48.379888 11.090148)
		(stroke
			(width 0.0635)
			(type default)
		)
		(layer "F.Cu")
	)
	(gr_line
		(start 48.272192 9.373362)
		(end 48.27651 9.362694)
		(stroke
			(width 0.0635)
			(type default)
		)
		(layer "F.Cu")
	)
	(gr_line
		(start 48.27397 9.378188)
		(end 48.272192 9.373362)
		(stroke
			(width 0.0635)
			(type default)
		)
		(layer "F.Cu")
	)
	(gr_line
		(start 48.277526 -5.427472)
		(end 48.2854 -5.183124)
		(stroke
			(width 0.0635)
			(type default)
		)
		(layer "F.Cu")
	)
	(gr_line
		(start 48.2854 -5.183124)
		(end 48.563276 -4.922266)
		(stroke
			(width 0.0635)
			(type default)
		)
		(layer "F.Cu")
	)
	(gr_line
		(start 48.313594 8.733282)
		(end 48.688244 8.198104)
		(stroke
			(width 0.0635)
			(type default)
		)
		(layer "F.Cu")
	)
	(gr_line
		(start 48.31842 -0.649478)
		(end 48.3362 -0.672846)
		(stroke
			(width 0.0635)
			(type default)
		)
		(layer "F.Cu")
	)
	(gr_line
		(start 48.3362 -0.6731)
		(end 48.34255 -0.700786)
		(stroke
			(width 0.0635)
			(type default)
		)
		(layer "F.Cu")
	)
	(gr_line
		(start 48.3362 -0.672846)
		(end 48.3362 -0.6731)
		(stroke
			(width 0.0635)
			(type default)
		)
		(layer "F.Cu")
	)
	(gr_line
		(start 48.379888 12.133072)
		(end 48.379888 11.090148)
		(stroke
			(width 0.0635)
			(type default)
		)
		(layer "F.Cu")
	)
	(gr_line
		(start 48.513492 -5.627878)
		(end 48.992282 -5.178298)
		(stroke
			(width 0.0635)
			(type default)
		)
		(layer "F.Cu")
	)
	(gr_line
		(start 48.544226 8.939784)
		(end 48.784764 8.897366)
		(stroke
			(width 0.0635)
			(type default)
		)
		(layer "F.Cu")
	)
	(gr_line
		(start 48.563276 -4.922266)
		(end 48.807624 -4.93014)
		(stroke
			(width 0.0635)
			(type default)
		)
		(layer "F.Cu")
	)
	(gr_line
		(start 48.784764 8.897366)
		(end 49.003458 8.5852)
		(stroke
			(width 0.0635)
			(type default)
		)
		(layer "F.Cu")
	)
	(gr_line
		(start 48.950372 7.823454)
		(end 49.327054 7.285482)
		(stroke
			(width 0.0635)
			(type default)
		)
		(layer "F.Cu")
	)
	(gr_line
		(start 48.960786 8.344408)
		(end 49.003458 8.5852)
		(stroke
			(width 0.0635)
			(type default)
		)
		(layer "F.Cu")
	)
	(gr_line
		(start 49.182274 8.028432)
		(end 49.423066 7.986014)
		(stroke
			(width 0.0635)
			(type default)
		)
		(layer "F.Cu")
	)
	(gr_line
		(start 49.423066 7.986014)
		(end 49.641506 7.673848)
		(stroke
			(width 0.0635)
			(type default)
		)
		(layer "F.Cu")
	)
	(gr_line
		(start 49.599088 7.432802)
		(end 49.641506 7.673848)
		(stroke
			(width 0.0635)
			(type default)
		)
		(layer "F.Cu")
	)
	(gr_line
		(start 49.655984 -4.55549)
		(end 49.68367 -4.529328)
		(stroke
			(width 0.0635)
			(type default)
		)
		(layer "F.Cu")
	)
	(gr_line
		(start 49.68367 -4.529328)
		(end 49.696116 -4.493514)
		(stroke
			(width 0.0635)
			(type default)
		)
		(layer "F.Cu")
	)
	(gr_arc
		(start 49.979834 11.028172)
		(mid 50.01198 10.8664)
		(end 50.103532 10.729214)
		(stroke
			(width 0.0635)
			(type default)
		)
		(layer "F.Cu")
	)
	(gr_line
		(start 49.979834 12.133072)
		(end 49.979834 11.028172)
		(stroke
			(width 0.0635)
			(type default)
		)
		(layer "F.Cu")
	)
	(gr_line
		(start 50.035206 -0.963422)
		(end 50.044604 -0.978408)
		(stroke
			(width 0.0635)
			(type default)
		)
		(layer "F.Cu")
	)
	(gr_line
		(start 50.044604 -0.978408)
		(end 50.047906 -0.99568)
		(stroke
			(width 0.0635)
			(type default)
		)
		(layer "F.Cu")
	)
	(gr_line
		(start 50.103532 10.729214)
		(end 50.140616 10.69213)
		(stroke
			(width 0.0635)
			(type default)
		)
		(layer "F.Cu")
	)
	(gr_arc
		(start 50.227484 10.482834)
		(mid 50.20491 10.596143)
		(end 50.140616 10.69213)
		(stroke
			(width 0.0635)
			(type default)
		)
		(layer "F.Cu")
	)
	(gr_line
		(start 50.307748 -2.378202)
		(end 50.30851 -2.382774)
		(stroke
			(width 0.0635)
			(type default)
		)
		(layer "F.Cu")
	)
	(gr_line
		(start 50.308002 -2.387346)
		(end 50.30851 -2.382774)
		(stroke
			(width 0.0635)
			(type default)
		)
		(layer "F.Cu")
	)
	(gr_line
		(start 50.39233 9.218676)
		(end 50.39741 9.190482)
		(stroke
			(width 0.0635)
			(type default)
		)
		(layer "F.Cu")
	)
	(gr_line
		(start 50.39741 9.190482)
		(end 50.413666 9.167114)
		(stroke
			(width 0.0635)
			(type default)
		)
		(layer "F.Cu")
	)
	(gr_line
		(start 50.50155 9.041638)
		(end 50.658776 8.817102)
		(stroke
			(width 0.0635)
			(type default)
		)
		(layer "F.Cu")
	)
	(gr_arc
		(start 50.656236 10.747248)
		(mid 50.564513 10.610235)
		(end 50.532284 10.448544)
		(stroke
			(width 0.0635)
			(type default)
		)
		(layer "F.Cu")
	)
	(gr_line
		(start 50.656236 10.747248)
		(end 50.65649 10.747502)
		(stroke
			(width 0.0635)
			(type default)
		)
		(layer "F.Cu")
	)
	(gr_arc
		(start 50.65649 10.747502)
		(mid 50.747876 10.88446)
		(end 50.779934 11.045952)
		(stroke
			(width 0.0635)
			(type default)
		)
		(layer "F.Cu")
	)
	(gr_line
		(start 50.677064 8.790686)
		(end 51.051968 8.255508)
		(stroke
			(width 0.0635)
			(type default)
		)
		(layer "F.Cu")
	)
	(gr_line
		(start 50.751232 9.21639)
		(end 50.904394 8.997696)
		(stroke
			(width 0.0635)
			(type default)
		)
		(layer "F.Cu")
	)
	(gr_line
		(start 50.779934 12.133072)
		(end 50.779934 11.045952)
		(stroke
			(width 0.0635)
			(type default)
		)
		(layer "F.Cu")
	)
	(gr_line
		(start 50.90795 8.996934)
		(end 51.148488 8.95477)
		(stroke
			(width 0.0635)
			(type default)
		)
		(layer "F.Cu")
	)
	(gr_arc
		(start 50.921412 -7.392924)
		(mid 50.921088 -7.406131)
		(end 50.920904 -7.41934)
		(stroke
			(width 0.0635)
			(type default)
		)
		(layer "F.Cu")
	)
	(gr_line
		(start 51.080162 -9.250426)
		(end 51.252628 -8.929878)
		(stroke
			(width 0.0635)
			(type default)
		)
		(layer "F.Cu")
	)
	(gr_line
		(start 51.086766 -6.377432)
		(end 51.181762 -5.793994)
		(stroke
			(width 0.0635)
			(type default)
		)
		(layer "F.Cu")
	)
	(gr_line
		(start 51.148488 8.95477)
		(end 51.367182 8.642604)
		(stroke
			(width 0.0635)
			(type default)
		)
		(layer "F.Cu")
	)
	(gr_line
		(start 51.181762 -5.793994)
		(end 51.19243 -5.728716)
		(stroke
			(width 0.0635)
			(type default)
		)
		(layer "F.Cu")
	)
	(gr_line
		(start 51.252628 -8.929878)
		(end 51.455066 -8.524748)
		(stroke
			(width 0.0635)
			(type default)
		)
		(layer "F.Cu")
	)
	(gr_line
		(start 51.265836 -5.278374)
		(end 51.3715 -4.631436)
		(stroke
			(width 0.0635)
			(type default)
		)
		(layer "F.Cu")
	)
	(gr_line
		(start 51.284632 -8.297926)
		(end 51.29784 -8.30453)
		(stroke
			(width 0.0635)
			(type default)
		)
		(layer "F.Cu")
	)
	(gr_line
		(start 51.314096 7.880858)
		(end 51.691286 7.342124)
		(stroke
			(width 0.0635)
			(type default)
		)
		(layer "F.Cu")
	)
	(gr_line
		(start 51.324002 8.39851)
		(end 51.418236 8.26389)
		(stroke
			(width 0.0635)
			(type default)
		)
		(layer "F.Cu")
	)
	(gr_line
		(start 51.324764 8.402066)
		(end 51.367182 8.642604)
		(stroke
			(width 0.0635)
			(type default)
		)
		(layer "F.Cu")
	)
	(gr_line
		(start 51.384454 -6.461506)
		(end 51.583082 -6.318504)
		(stroke
			(width 0.0635)
			(type default)
		)
		(layer "F.Cu")
	)
	(gr_line
		(start 51.397916 -8.354314)
		(end 51.39817 -8.354314)
		(stroke
			(width 0.0635)
			(type default)
		)
		(layer "F.Cu")
	)
	(gr_line
		(start 51.414934 -0.701548)
		(end 51.429412 -0.72136)
		(stroke
			(width 0.0635)
			(type default)
		)
		(layer "F.Cu")
	)
	(gr_line
		(start 51.429412 -0.72136)
		(end 51.435 -0.745744)
		(stroke
			(width 0.0635)
			(type default)
		)
		(layer "F.Cu")
	)
	(gr_arc
		(start 51.455066 -8.524748)
		(mid 51.461903 -8.427758)
		(end 51.39817 -8.354314)
		(stroke
			(width 0.0635)
			(type default)
		)
		(layer "F.Cu")
	)
	(gr_line
		(start 51.501294 -5.743702)
		(end 51.644296 -5.94233)
		(stroke
			(width 0.0635)
			(type default)
		)
		(layer "F.Cu")
	)
	(gr_line
		(start 51.521106 -2.526284)
		(end 51.532536 -2.57683)
		(stroke
			(width 0.0635)
			(type default)
		)
		(layer "F.Cu")
	)
	(gr_line
		(start 51.53406 -8.081518)
		(end 51.534568 -8.081772)
		(stroke
			(width 0.0635)
			(type default)
		)
		(layer "F.Cu")
	)
	(gr_line
		(start 51.534568 -8.081772)
		(end 51.534822 -8.081772)
		(stroke
			(width 0.0635)
			(type default)
		)
		(layer "F.Cu")
	)
	(gr_arc
		(start 51.534822 -8.081772)
		(mid 51.631828 -8.088627)
		(end 51.705256 -8.024876)
		(stroke
			(width 0.0635)
			(type default)
		)
		(layer "F.Cu")
	)
	(gr_line
		(start 51.546252 8.085836)
		(end 51.78679 8.043418)
		(stroke
			(width 0.0635)
			(type default)
		)
		(layer "F.Cu")
	)
	(gr_line
		(start 51.563524 -5.36321)
		(end 51.761898 -5.220462)
		(stroke
			(width 0.0635)
			(type default)
		)
		(layer "F.Cu")
	)
	(gr_line
		(start 51.583082 -6.318504)
		(end 51.644296 -5.94233)
		(stroke
			(width 0.0635)
			(type default)
		)
		(layer "F.Cu")
	)
	(gr_line
		(start 51.680364 -4.64566)
		(end 51.823366 -4.844288)
		(stroke
			(width 0.0635)
			(type default)
		)
		(layer "F.Cu")
	)
	(gr_line
		(start 51.705256 -8.024876)
		(end 51.84521 -7.74446)
		(stroke
			(width 0.0635)
			(type default)
		)
		(layer "F.Cu")
	)
	(gr_line
		(start 51.761898 -5.220462)
		(end 51.823366 -4.844288)
		(stroke
			(width 0.0635)
			(type default)
		)
		(layer "F.Cu")
	)
	(gr_line
		(start 51.78679 8.043418)
		(end 52.00523 7.731252)
		(stroke
			(width 0.0635)
			(type default)
		)
		(layer "F.Cu")
	)
	(gr_line
		(start 51.84267 -2.455418)
		(end 51.846734 -2.536444)
		(stroke
			(width 0.0635)
			(type default)
		)
		(layer "F.Cu")
	)
	(gr_line
		(start 51.84521 -7.74446)
		(end 52.079652 -7.250176)
		(stroke
			(width 0.0635)
			(type default)
		)
		(layer "F.Cu")
	)
	(gr_line
		(start 51.962812 7.49046)
		(end 52.00523 7.731252)
		(stroke
			(width 0.0635)
			(type default)
		)
		(layer "F.Cu")
	)
	(gr_arc
		(start 52.37988 11.090656)
		(mid 52.412136 10.928966)
		(end 52.503832 10.791952)
		(stroke
			(width 0.0635)
			(type default)
		)
		(layer "F.Cu")
	)
	(gr_line
		(start 52.37988 12.133072)
		(end 52.37988 11.090656)
		(stroke
			(width 0.0635)
			(type default)
		)
		(layer "F.Cu")
	)
	(gr_line
		(start 52.503832 10.791952)
		(end 52.504086 10.791698)
		(stroke
			(width 0.0635)
			(type default)
		)
		(layer "F.Cu")
	)
	(gr_arc
		(start 52.62753 10.493248)
		(mid 52.595485 10.654751)
		(end 52.504086 10.791698)
		(stroke
			(width 0.0635)
			(type default)
		)
		(layer "F.Cu")
	)
	(gr_line
		(start 52.80787 9.131554)
		(end 52.81295 9.10336)
		(stroke
			(width 0.0635)
			(type default)
		)
		(layer "F.Cu")
	)
	(gr_line
		(start 52.81295 9.10336)
		(end 52.829206 9.079992)
		(stroke
			(width 0.0635)
			(type default)
		)
		(layer "F.Cu")
	)
	(gr_line
		(start 52.920392 8.949944)
		(end 53.076094 8.727694)
		(stroke
			(width 0.0635)
			(type default)
		)
		(layer "F.Cu")
	)
	(gr_arc
		(start 53.056028 10.765282)
		(mid 52.964458 10.628097)
		(end 52.93233 10.466324)
		(stroke
			(width 0.0635)
			(type default)
		)
		(layer "F.Cu")
	)
	(gr_line
		(start 53.056028 10.765282)
		(end 53.093112 10.802366)
		(stroke
			(width 0.0635)
			(type default)
		)
		(layer "F.Cu")
	)
	(gr_line
		(start 53.092604 8.703564)
		(end 53.467508 8.168386)
		(stroke
			(width 0.0635)
			(type default)
		)
		(layer "F.Cu")
	)
	(gr_arc
		(start 53.093112 10.802366)
		(mid 53.157382 10.898363)
		(end 53.17998 11.011662)
		(stroke
			(width 0.0635)
			(type default)
		)
		(layer "F.Cu")
	)
	(gr_line
		(start 53.170074 9.124696)
		(end 53.319934 8.910574)
		(stroke
			(width 0.0635)
			(type default)
		)
		(layer "F.Cu")
	)
	(gr_line
		(start 53.17998 12.133072)
		(end 53.17998 11.011662)
		(stroke
			(width 0.0635)
			(type default)
		)
		(layer "F.Cu")
	)
	(gr_line
		(start 53.32349 8.909812)
		(end 53.564028 8.867648)
		(stroke
			(width 0.0635)
			(type default)
		)
		(layer "F.Cu")
	)
	(gr_line
		(start 53.485288 8.14324)
		(end 53.494432 8.130032)
		(stroke
			(width 0.0635)
			(type default)
		)
		(layer "F.Cu")
	)
	(gr_line
		(start 53.564028 8.867648)
		(end 53.782722 8.555482)
		(stroke
			(width 0.0635)
			(type default)
		)
		(layer "F.Cu")
	)
	(gr_line
		(start 53.729636 7.793736)
		(end 54.106826 7.255002)
		(stroke
			(width 0.0635)
			(type default)
		)
		(layer "F.Cu")
	)
	(gr_line
		(start 53.739542 8.311388)
		(end 53.805328 8.217662)
		(stroke
			(width 0.0635)
			(type default)
		)
		(layer "F.Cu")
	)
	(gr_line
		(start 53.74005 8.314944)
		(end 53.782722 8.555482)
		(stroke
			(width 0.0635)
			(type default)
		)
		(layer "F.Cu")
	)
	(gr_line
		(start 53.961792 7.998714)
		(end 54.20233 7.956296)
		(stroke
			(width 0.0635)
			(type default)
		)
		(layer "F.Cu")
	)
	(gr_line
		(start 54.20233 7.956296)
		(end 54.42077 7.64413)
		(stroke
			(width 0.0635)
			(type default)
		)
		(layer "F.Cu")
	)
	(gr_line
		(start 54.378352 7.403338)
		(end 54.42077 7.64413)
		(stroke
			(width 0.0635)
			(type default)
		)
		(layer "F.Cu")
	)
	(gr_line
		(start 54.493668 -2.901188)
		(end 54.509924 -2.924556)
		(stroke
			(width 0.0635)
			(type default)
		)
		(layer "F.Cu")
	)
	(gr_line
		(start 54.509924 -2.924556)
		(end 54.515004 -2.95275)
		(stroke
			(width 0.0635)
			(type default)
		)
		(layer "F.Cu")
	)
	(gr_arc
		(start 54.779926 11.02868)
		(mid 54.812148 10.866868)
		(end 54.903878 10.729722)
		(stroke
			(width 0.0635)
			(type default)
		)
		(layer "F.Cu")
	)
	(gr_line
		(start 54.779926 12.133072)
		(end 54.779926 11.02868)
		(stroke
			(width 0.0635)
			(type default)
		)
		(layer "F.Cu")
	)
	(gr_line
		(start 54.939438 2.70383)
		(end 54.948328 2.69113)
		(stroke
			(width 0.0635)
			(type default)
		)
		(layer "F.Cu")
	)
	(gr_line
		(start 54.948328 2.69113)
		(end 54.961028 2.68224)
		(stroke
			(width 0.0635)
			(type default)
		)
		(layer "F.Cu")
	)
	(gr_arc
		(start 55.027576 10.431018)
		(mid 54.995442 10.592675)
		(end 54.903878 10.729722)
		(stroke
			(width 0.0635)
			(type default)
		)
		(layer "F.Cu")
	)
	(gr_line
		(start 55.079392 -9.250426)
		(end 55.325518 -8.784082)
		(stroke
			(width 0.0635)
			(type default)
		)
		(layer "F.Cu")
	)
	(gr_line
		(start 55.254144 8.89762)
		(end 55.259478 8.868664)
		(stroke
			(width 0.0635)
			(type default)
		)
		(layer "F.Cu")
	)
	(gr_line
		(start 55.259478 8.868664)
		(end 55.275988 8.845042)
		(stroke
			(width 0.0635)
			(type default)
		)
		(layer "F.Cu")
	)
	(gr_line
		(start 55.285132 -8.297926)
		(end 55.298086 -8.304276)
		(stroke
			(width 0.0635)
			(type default)
		)
		(layer "F.Cu")
	)
	(gr_line
		(start 55.325518 -8.784082)
		(end 55.455566 -8.524748)
		(stroke
			(width 0.0635)
			(type default)
		)
		(layer "F.Cu")
	)
	(gr_line
		(start 55.398416 -8.354314)
		(end 55.39867 -8.354314)
		(stroke
			(width 0.0635)
			(type default)
		)
		(layer "F.Cu")
	)
	(gr_arc
		(start 55.455566 -8.524748)
		(mid 55.462403 -8.427758)
		(end 55.39867 -8.354314)
		(stroke
			(width 0.0635)
			(type default)
		)
		(layer "F.Cu")
	)
	(gr_arc
		(start 55.456328 10.777728)
		(mid 55.364595 10.640585)
		(end 55.332376 10.47877)
		(stroke
			(width 0.0635)
			(type default)
		)
		(layer "F.Cu")
	)
	(gr_arc
		(start 55.456328 10.777728)
		(mid 55.5479 10.914775)
		(end 55.580026 11.076432)
		(stroke
			(width 0.0635)
			(type default)
		)
		(layer "F.Cu")
	)
	(gr_line
		(start 55.53456 -8.081518)
		(end 55.535068 -8.081772)
		(stroke
			(width 0.0635)
			(type default)
		)
		(layer "F.Cu")
	)
	(gr_line
		(start 55.535068 -8.081772)
		(end 55.535322 -8.081772)
		(stroke
			(width 0.0635)
			(type default)
		)
		(layer "F.Cu")
	)
	(gr_arc
		(start 55.535322 -8.081772)
		(mid 55.632378 -8.088713)
		(end 55.705756 -8.024876)
		(stroke
			(width 0.0635)
			(type default)
		)
		(layer "F.Cu")
	)
	(gr_line
		(start 55.538116 8.470646)
		(end 55.91429 7.933436)
		(stroke
			(width 0.0635)
			(type default)
		)
		(layer "F.Cu")
	)
	(gr_line
		(start 55.580026 12.133072)
		(end 55.580026 11.076432)
		(stroke
			(width 0.0635)
			(type default)
		)
		(layer "F.Cu")
	)
	(gr_line
		(start 55.705756 -8.024876)
		(end 55.846218 -7.743698)
		(stroke
			(width 0.0635)
			(type default)
		)
		(layer "F.Cu")
	)
	(gr_line
		(start 55.76951 8.676132)
		(end 56.010302 8.633714)
		(stroke
			(width 0.0635)
			(type default)
		)
		(layer "F.Cu")
	)
	(gr_line
		(start 55.846218 -7.743698)
		(end 56.080152 -7.250176)
		(stroke
			(width 0.0635)
			(type default)
		)
		(layer "F.Cu")
	)
	(gr_line
		(start 56.010302 8.633714)
		(end 56.228996 8.321548)
		(stroke
			(width 0.0635)
			(type default)
		)
		(layer "F.Cu")
	)
	(gr_line
		(start 56.176164 7.559548)
		(end 56.552846 7.021576)
		(stroke
			(width 0.0635)
			(type default)
		)
		(layer "F.Cu")
	)
	(gr_line
		(start 56.186324 8.080756)
		(end 56.228996 8.321548)
		(stroke
			(width 0.0635)
			(type default)
		)
		(layer "F.Cu")
	)
	(gr_line
		(start 56.407558 7.76478)
		(end 56.648604 7.722362)
		(stroke
			(width 0.0635)
			(type default)
		)
		(layer "F.Cu")
	)
	(gr_line
		(start 56.648604 7.722362)
		(end 56.867044 7.410196)
		(stroke
			(width 0.0635)
			(type default)
		)
		(layer "F.Cu")
	)
	(gr_line
		(start 56.824626 7.16915)
		(end 56.867044 7.410196)
		(stroke
			(width 0.0635)
			(type default)
		)
		(layer "F.Cu")
	)
	(gr_arc
		(start 57.179972 11.041634)
		(mid 57.212092 10.879969)
		(end 57.30367 10.74293)
		(stroke
			(width 0.0635)
			(type default)
		)
		(layer "F.Cu")
	)
	(gr_line
		(start 57.179972 12.133072)
		(end 57.179972 11.041634)
		(stroke
			(width 0.0635)
			(type default)
		)
		(layer "F.Cu")
	)
	(gr_arc
		(start 57.427368 10.444226)
		(mid 57.395215 10.605872)
		(end 57.30367 10.74293)
		(stroke
			(width 0.0635)
			(type default)
		)
		(layer "F.Cu")
	)
	(gr_line
		(start 57.4929 2.419604)
		(end 57.50179 2.406904)
		(stroke
			(width 0.0635)
			(type default)
		)
		(layer "F.Cu")
	)
	(gr_line
		(start 57.50179 2.406904)
		(end 57.51449 2.398014)
		(stroke
			(width 0.0635)
			(type default)
		)
		(layer "F.Cu")
	)
	(gr_line
		(start 57.751472 8.316722)
		(end 57.756552 8.288528)
		(stroke
			(width 0.0635)
			(type default)
		)
		(layer "F.Cu")
	)
	(gr_line
		(start 57.756552 8.288528)
		(end 57.772808 8.26516)
		(stroke
			(width 0.0635)
			(type default)
		)
		(layer "F.Cu")
	)
	(gr_arc
		(start 57.855866 10.738866)
		(mid 57.764323 10.60181)
		(end 57.732168 10.440162)
		(stroke
			(width 0.0635)
			(type default)
		)
		(layer "F.Cu")
	)
	(gr_arc
		(start 57.855866 10.738866)
		(mid 57.947593 10.876146)
		(end 57.979818 11.038078)
		(stroke
			(width 0.0635)
			(type default)
		)
		(layer "F.Cu")
	)
	(gr_line
		(start 57.875678 8.118348)
		(end 58.01741 7.91591)
		(stroke
			(width 0.0635)
			(type default)
		)
		(layer "F.Cu")
	)
	(gr_line
		(start 57.979818 12.133072)
		(end 57.979818 11.038078)
		(stroke
			(width 0.0635)
			(type default)
		)
		(layer "F.Cu")
	)
	(gr_line
		(start 58.03646 7.888732)
		(end 58.410856 7.354316)
		(stroke
			(width 0.0635)
			(type default)
		)
		(layer "F.Cu")
	)
	(gr_line
		(start 58.12536 8.293354)
		(end 58.263536 8.095742)
		(stroke
			(width 0.0635)
			(type default)
		)
		(layer "F.Cu")
	)
	(gr_line
		(start 58.267092 8.09498)
		(end 58.50763 8.052816)
		(stroke
			(width 0.0635)
			(type default)
		)
		(layer "F.Cu")
	)
	(gr_line
		(start 58.50763 8.052816)
		(end 58.726324 7.74065)
		(stroke
			(width 0.0635)
			(type default)
		)
		(layer "F.Cu")
	)
	(gr_line
		(start 58.674762 6.97738)
		(end 59.049158 6.442456)
		(stroke
			(width 0.0635)
			(type default)
		)
		(layer "F.Cu")
	)
	(gr_line
		(start 58.683652 7.500112)
		(end 58.726324 7.74065)
		(stroke
			(width 0.0635)
			(type default)
		)
		(layer "F.Cu")
	)
	(gr_line
		(start 58.90514 7.183882)
		(end 59.145932 7.141464)
		(stroke
			(width 0.0635)
			(type default)
		)
		(layer "F.Cu")
	)
	(gr_line
		(start 59.065668 -6.069838)
		(end 59.075828 -6.127496)
		(stroke
			(width 0.0635)
			(type default)
		)
		(layer "F.Cu")
	)
	(gr_line
		(start 59.079892 -9.250426)
		(end 59.20486 -9.025128)
		(stroke
			(width 0.0635)
			(type default)
		)
		(layer "F.Cu")
	)
	(gr_line
		(start 59.145932 7.141464)
		(end 59.364372 6.829298)
		(stroke
			(width 0.0635)
			(type default)
		)
		(layer "F.Cu")
	)
	(gr_line
		(start 59.20486 -9.025128)
		(end 59.454796 -8.524748)
		(stroke
			(width 0.0635)
			(type default)
		)
		(layer "F.Cu")
	)
	(gr_line
		(start 59.284362 -8.297926)
		(end 59.297316 -8.304276)
		(stroke
			(width 0.0635)
			(type default)
		)
		(layer "F.Cu")
	)
	(gr_line
		(start 59.321954 6.588506)
		(end 59.364372 6.829298)
		(stroke
			(width 0.0635)
			(type default)
		)
		(layer "F.Cu")
	)
	(gr_line
		(start 59.397646 -8.354314)
		(end 59.3979 -8.354314)
		(stroke
			(width 0.0635)
			(type default)
		)
		(layer "F.Cu")
	)
	(gr_arc
		(start 59.454796 -8.524748)
		(mid 59.461555 -8.427803)
		(end 59.3979 -8.354314)
		(stroke
			(width 0.0635)
			(type default)
		)
		(layer "F.Cu")
	)
	(gr_line
		(start 59.53379 -8.081518)
		(end 59.534298 -8.081772)
		(stroke
			(width 0.0635)
			(type default)
		)
		(layer "F.Cu")
	)
	(gr_line
		(start 59.534298 -8.081772)
		(end 59.534552 -8.081772)
		(stroke
			(width 0.0635)
			(type default)
		)
		(layer "F.Cu")
	)
	(gr_arc
		(start 59.534552 -8.081772)
		(mid 59.631608 -8.088713)
		(end 59.704986 -8.024876)
		(stroke
			(width 0.0635)
			(type default)
		)
		(layer "F.Cu")
	)
	(gr_arc
		(start 59.580018 11.054588)
		(mid 59.61215 10.89293)
		(end 59.703716 10.755884)
		(stroke
			(width 0.0635)
			(type default)
		)
		(layer "F.Cu")
	)
	(gr_line
		(start 59.580018 12.133072)
		(end 59.580018 11.054588)
		(stroke
			(width 0.0635)
			(type default)
		)
		(layer "F.Cu")
	)
	(gr_line
		(start 59.704986 -8.024876)
		(end 59.892184 -7.649972)
		(stroke
			(width 0.0635)
			(type default)
		)
		(layer "F.Cu")
	)
	(gr_arc
		(start 59.827414 10.45718)
		(mid 59.795261 10.618826)
		(end 59.703716 10.755884)
		(stroke
			(width 0.0635)
			(type default)
		)
		(layer "F.Cu")
	)
	(gr_line
		(start 59.861704 2.29616)
		(end 59.870594 2.28346)
		(stroke
			(width 0.0635)
			(type default)
		)
		(layer "F.Cu")
	)
	(gr_line
		(start 59.870594 2.28346)
		(end 59.883294 2.27457)
		(stroke
			(width 0.0635)
			(type default)
		)
		(layer "F.Cu")
	)
	(gr_line
		(start 59.892184 -7.649972)
		(end 60.079382 -7.250176)
		(stroke
			(width 0.0635)
			(type default)
		)
		(layer "F.Cu")
	)
	(gr_line
		(start 60.043568 8.829548)
		(end 60.048648 8.801354)
		(stroke
			(width 0.0635)
			(type default)
		)
		(layer "F.Cu")
	)
	(gr_line
		(start 60.048648 8.801354)
		(end 60.06465 8.778748)
		(stroke
			(width 0.0635)
			(type default)
		)
		(layer "F.Cu")
	)
	(gr_line
		(start 60.224162 8.245094)
		(end 60.26658 8.485886)
		(stroke
			(width 0.0635)
			(type default)
		)
		(layer "F.Cu")
	)
	(gr_line
		(start 60.224162 8.245094)
		(end 60.442602 7.933182)
		(stroke
			(width 0.0635)
			(type default)
		)
		(layer "F.Cu")
	)
	(gr_arc
		(start 60.256166 10.827766)
		(mid 60.164437 10.690488)
		(end 60.132214 10.528554)
		(stroke
			(width 0.0635)
			(type default)
		)
		(layer "F.Cu")
	)
	(gr_arc
		(start 60.256166 10.827766)
		(mid 60.347738 10.964813)
		(end 60.379864 11.12647)
		(stroke
			(width 0.0635)
			(type default)
		)
		(layer "F.Cu")
	)
	(gr_line
		(start 60.379864 12.133072)
		(end 60.379864 11.12647)
		(stroke
			(width 0.0635)
			(type default)
		)
		(layer "F.Cu")
	)
	(gr_line
		(start 60.442602 7.933182)
		(end 60.683394 7.89051)
		(stroke
			(width 0.0635)
			(type default)
		)
		(layer "F.Cu")
	)
	(gr_line
		(start 60.539122 8.632444)
		(end 60.914788 8.095996)
		(stroke
			(width 0.0635)
			(type default)
		)
		(layer "F.Cu")
	)
	(gr_line
		(start 60.86221 7.333742)
		(end 60.904882 7.57428)
		(stroke
			(width 0.0635)
			(type default)
		)
		(layer "F.Cu")
	)
	(gr_line
		(start 60.86221 7.333742)
		(end 61.080904 7.02183)
		(stroke
			(width 0.0635)
			(type default)
		)
		(layer "F.Cu")
	)
	(gr_line
		(start 61.080904 7.02183)
		(end 61.321442 6.979158)
		(stroke
			(width 0.0635)
			(type default)
		)
		(layer "F.Cu")
	)
	(gr_line
		(start 61.177678 7.720076)
		(end 61.55055 7.187438)
		(stroke
			(width 0.0635)
			(type default)
		)
		(layer "F.Cu")
	)
	(gr_arc
		(start 61.97981 11.067796)
		(mid 62.011945 10.906141)
		(end 62.103508 10.769092)
		(stroke
			(width 0.0635)
			(type default)
		)
		(layer "F.Cu")
	)
	(gr_line
		(start 61.97981 12.133072)
		(end 61.97981 11.067796)
		(stroke
			(width 0.0635)
			(type default)
		)
		(layer "F.Cu")
	)
	(gr_line
		(start 62.023498 2.241804)
		(end 62.023498 2.238756)
		(stroke
			(width 0.0635)
			(type default)
		)
		(layer "F.Cu")
	)
	(gr_line
		(start 62.037214 2.229104)
		(end 62.09284 2.189988)
		(stroke
			(width 0.0635)
			(type default)
		)
		(layer "F.Cu")
	)
	(gr_arc
		(start 62.22746 10.46988)
		(mid 62.195249 10.631818)
		(end 62.103508 10.769092)
		(stroke
			(width 0.0635)
			(type default)
		)
		(layer "F.Cu")
	)
	(gr_line
		(start 62.231524 2.46507)
		(end 62.239144 2.45745)
		(stroke
			(width 0.0635)
			(type default)
		)
		(layer "F.Cu")
	)
	(gr_line
		(start 62.239144 2.45745)
		(end 62.2427 2.45745)
		(stroke
			(width 0.0635)
			(type default)
		)
		(layer "F.Cu")
	)
	(gr_line
		(start 62.55639 8.28929)
		(end 62.56147 8.261096)
		(stroke
			(width 0.0635)
			(type default)
		)
		(layer "F.Cu")
	)
	(gr_line
		(start 62.56147 8.261096)
		(end 62.577472 8.23849)
		(stroke
			(width 0.0635)
			(type default)
		)
		(layer "F.Cu")
	)
	(gr_arc
		(start 62.656212 10.814558)
		(mid 62.564523 10.677538)
		(end 62.53226 10.515854)
		(stroke
			(width 0.0635)
			(type default)
		)
		(layer "F.Cu")
	)
	(gr_line
		(start 62.656212 10.814558)
		(end 62.656466 10.814812)
		(stroke
			(width 0.0635)
			(type default)
		)
		(layer "F.Cu")
	)
	(gr_arc
		(start 62.656466 10.814812)
		(mid 62.747852 10.95177)
		(end 62.77991 11.113262)
		(stroke
			(width 0.0635)
			(type default)
		)
		(layer "F.Cu")
	)
	(gr_line
		(start 62.736984 7.704836)
		(end 62.779402 7.945628)
		(stroke
			(width 0.0635)
			(type default)
		)
		(layer "F.Cu")
	)
	(gr_line
		(start 62.736984 7.704836)
		(end 62.955424 7.392924)
		(stroke
			(width 0.0635)
			(type default)
		)
		(layer "F.Cu")
	)
	(gr_line
		(start 62.77991 12.133072)
		(end 62.77991 11.113262)
		(stroke
			(width 0.0635)
			(type default)
		)
		(layer "F.Cu")
	)
	(gr_line
		(start 62.955424 7.392924)
		(end 63.196216 7.350252)
		(stroke
			(width 0.0635)
			(type default)
		)
		(layer "F.Cu")
	)
	(gr_line
		(start 63.051944 8.091932)
		(end 63.42634 7.557262)
		(stroke
			(width 0.0635)
			(type default)
		)
		(layer "F.Cu")
	)
	(gr_line
		(start 63.375032 6.793484)
		(end 63.417704 7.034022)
		(stroke
			(width 0.0635)
			(type default)
		)
		(layer "F.Cu")
	)
	(gr_line
		(start 63.375032 6.793484)
		(end 63.593472 6.481572)
		(stroke
			(width 0.0635)
			(type default)
		)
		(layer "F.Cu")
	)
	(gr_line
		(start 63.412116 7.046214)
		(end 63.418212 7.037578)
		(stroke
			(width 0.0635)
			(type default)
		)
		(layer "F.Cu")
	)
	(gr_line
		(start 63.593472 6.481572)
		(end 63.834264 6.4389)
		(stroke
			(width 0.0635)
			(type default)
		)
		(layer "F.Cu")
	)
	(gr_line
		(start 63.661798 7.22122)
		(end 63.668656 7.211314)
		(stroke
			(width 0.0635)
			(type default)
		)
		(layer "F.Cu")
	)
	(gr_line
		(start 63.6905 7.180326)
		(end 64.066166 6.643878)
		(stroke
			(width 0.0635)
			(type default)
		)
		(layer "F.Cu")
	)
	(gr_line
		(start 64.011048 -3.282188)
		(end 64.023748 -3.291078)
		(stroke
			(width 0.0635)
			(type default)
		)
		(layer "F.Cu")
	)
	(gr_line
		(start 64.023748 -3.291078)
		(end 64.032638 -3.303778)
		(stroke
			(width 0.0635)
			(type default)
		)
		(layer "F.Cu")
	)
	(gr_arc
		(start 64.379856 10.97915)
		(mid 64.412159 10.817485)
		(end 64.503808 10.680446)
		(stroke
			(width 0.0635)
			(type default)
		)
		(layer "F.Cu")
	)
	(gr_line
		(start 64.379856 12.133072)
		(end 64.379856 10.97915)
		(stroke
			(width 0.0635)
			(type default)
		)
		(layer "F.Cu")
	)
	(gr_line
		(start 64.503808 10.680446)
		(end 64.504062 10.680192)
		(stroke
			(width 0.0635)
			(type default)
		)
		(layer "F.Cu")
	)
	(gr_arc
		(start 64.627506 10.381742)
		(mid 64.595421 10.543222)
		(end 64.504062 10.680192)
		(stroke
			(width 0.0635)
			(type default)
		)
		(layer "F.Cu")
	)
	(gr_line
		(start 64.994028 -4.676648)
		(end 65.010284 -4.700016)
		(stroke
			(width 0.0635)
			(type default)
		)
		(layer "F.Cu")
	)
	(gr_line
		(start 65.010284 -4.700016)
		(end 65.015364 -4.72821)
		(stroke
			(width 0.0635)
			(type default)
		)
		(layer "F.Cu")
	)
	(gr_line
		(start 65.040002 7.814818)
		(end 65.045082 7.786624)
		(stroke
			(width 0.0635)
			(type default)
		)
		(layer "F.Cu")
	)
	(gr_line
		(start 65.045082 7.786624)
		(end 65.061084 7.764018)
		(stroke
			(width 0.0635)
			(type default)
		)
		(layer "F.Cu")
	)
	(gr_arc
		(start 65.056004 10.725658)
		(mid 64.964447 10.58847)
		(end 64.932306 10.4267)
		(stroke
			(width 0.0635)
			(type default)
		)
		(layer "F.Cu")
	)
	(gr_line
		(start 65.056004 10.725658)
		(end 65.093088 10.762742)
		(stroke
			(width 0.0635)
			(type default)
		)
		(layer "F.Cu")
	)
	(gr_line
		(start 65.079372 -9.250426)
		(end 65.171828 -9.09066)
		(stroke
			(width 0.0635)
			(type default)
		)
		(layer "F.Cu")
	)
	(gr_arc
		(start 65.093088 10.762742)
		(mid 65.157358 10.858739)
		(end 65.179956 10.972038)
		(stroke
			(width 0.0635)
			(type default)
		)
		(layer "F.Cu")
	)
	(gr_line
		(start 65.14084 1.529334)
		(end 65.14973 1.516634)
		(stroke
			(width 0.0635)
			(type default)
		)
		(layer "F.Cu")
	)
	(gr_line
		(start 65.14973 1.516634)
		(end 65.16243 1.507744)
		(stroke
			(width 0.0635)
			(type default)
		)
		(layer "F.Cu")
	)
	(gr_line
		(start 65.171828 -9.09066)
		(end 65.455546 -8.524748)
		(stroke
			(width 0.0635)
			(type default)
		)
		(layer "F.Cu")
	)
	(gr_line
		(start 65.179956 12.133072)
		(end 65.179956 10.972038)
		(stroke
			(width 0.0635)
			(type default)
		)
		(layer "F.Cu")
	)
	(gr_line
		(start 65.220596 7.230364)
		(end 65.263014 7.471156)
		(stroke
			(width 0.0635)
			(type default)
		)
		(layer "F.Cu")
	)
	(gr_line
		(start 65.220596 7.230364)
		(end 65.439036 6.918452)
		(stroke
			(width 0.0635)
			(type default)
		)
		(layer "F.Cu")
	)
	(gr_line
		(start 65.285112 -8.297926)
		(end 65.29832 -8.30453)
		(stroke
			(width 0.0635)
			(type default)
		)
		(layer "F.Cu")
	)
	(gr_line
		(start 65.398396 -8.354314)
		(end 65.39865 -8.354314)
		(stroke
			(width 0.0635)
			(type default)
		)
		(layer "F.Cu")
	)
	(gr_line
		(start 65.439036 6.918452)
		(end 65.679828 6.87578)
		(stroke
			(width 0.0635)
			(type default)
		)
		(layer "F.Cu")
	)
	(gr_arc
		(start 65.455546 -8.524748)
		(mid 65.462305 -8.427803)
		(end 65.39865 -8.354314)
		(stroke
			(width 0.0635)
			(type default)
		)
		(layer "F.Cu")
	)
	(gr_line
		(start 65.53454 -8.081518)
		(end 65.535048 -8.081772)
		(stroke
			(width 0.0635)
			(type default)
		)
		(layer "F.Cu")
	)
	(gr_line
		(start 65.535048 -8.081772)
		(end 65.535302 -8.081772)
		(stroke
			(width 0.0635)
			(type default)
		)
		(layer "F.Cu")
	)
	(gr_arc
		(start 65.535302 -8.081772)
		(mid 65.632318 -8.08864)
		(end 65.705736 -8.024876)
		(stroke
			(width 0.0635)
			(type default)
		)
		(layer "F.Cu")
	)
	(gr_line
		(start 65.535556 7.617714)
		(end 65.911222 7.08152)
		(stroke
			(width 0.0635)
			(type default)
		)
		(layer "F.Cu")
	)
	(gr_line
		(start 65.705736 -8.024876)
		(end 65.991232 -7.453122)
		(stroke
			(width 0.0635)
			(type default)
		)
		(layer "F.Cu")
	)
	(gr_line
		(start 65.858644 6.319012)
		(end 65.901316 6.55955)
		(stroke
			(width 0.0635)
			(type default)
		)
		(layer "F.Cu")
	)
	(gr_line
		(start 65.858644 6.319012)
		(end 66.077338 6.0071)
		(stroke
			(width 0.0635)
			(type default)
		)
		(layer "F.Cu")
	)
	(gr_line
		(start 65.991232 -7.453122)
		(end 66.080132 -7.250176)
		(stroke
			(width 0.0635)
			(type default)
		)
		(layer "F.Cu")
	)
	(gr_line
		(start 66.077338 6.0071)
		(end 66.317876 5.964428)
		(stroke
			(width 0.0635)
			(type default)
		)
		(layer "F.Cu")
	)
	(gr_line
		(start 66.17335 6.707124)
		(end 66.549524 6.169914)
		(stroke
			(width 0.0635)
			(type default)
		)
		(layer "F.Cu")
	)
	(gr_arc
		(start 66.779902 11.065256)
		(mid 66.812055 10.90361)
		(end 66.9036 10.766552)
		(stroke
			(width 0.0635)
			(type default)
		)
		(layer "F.Cu")
	)
	(gr_line
		(start 66.779902 12.133072)
		(end 66.779902 11.065256)
		(stroke
			(width 0.0635)
			(type default)
		)
		(layer "F.Cu")
	)
	(gr_arc
		(start 67.027552 10.46734)
		(mid 66.995333 10.629274)
		(end 66.9036 10.766552)
		(stroke
			(width 0.0635)
			(type default)
		)
		(layer "F.Cu")
	)
	(gr_line
		(start 67.303142 1.488948)
		(end 67.312032 1.476248)
		(stroke
			(width 0.0635)
			(type default)
		)
		(layer "F.Cu")
	)
	(gr_line
		(start 67.312032 1.476248)
		(end 67.324732 1.467358)
		(stroke
			(width 0.0635)
			(type default)
		)
		(layer "F.Cu")
	)
	(gr_arc
		(start 67.456304 10.712704)
		(mid 67.364547 10.575569)
		(end 67.332352 10.413746)
		(stroke
			(width 0.0635)
			(type default)
		)
		(layer "F.Cu")
	)
	(gr_arc
		(start 67.456304 10.712704)
		(mid 67.547831 10.849762)
		(end 67.580002 11.011408)
		(stroke
			(width 0.0635)
			(type default)
		)
		(layer "F.Cu")
	)
	(gr_line
		(start 67.540378 7.247382)
		(end 67.545458 7.219188)
		(stroke
			(width 0.0635)
			(type default)
		)
		(layer "F.Cu")
	)
	(gr_line
		(start 67.545458 7.219188)
		(end 67.56146 7.196582)
		(stroke
			(width 0.0635)
			(type default)
		)
		(layer "F.Cu")
	)
	(gr_line
		(start 67.580002 12.133072)
		(end 67.580002 11.011408)
		(stroke
			(width 0.0635)
			(type default)
		)
		(layer "F.Cu")
	)
	(gr_line
		(start 67.720972 6.662928)
		(end 67.76339 6.90372)
		(stroke
			(width 0.0635)
			(type default)
		)
		(layer "F.Cu")
	)
	(gr_line
		(start 67.720972 6.662928)
		(end 67.939412 6.351016)
		(stroke
			(width 0.0635)
			(type default)
		)
		(layer "F.Cu")
	)
	(gr_line
		(start 67.939412 6.351016)
		(end 68.180204 6.308344)
		(stroke
			(width 0.0635)
			(type default)
		)
		(layer "F.Cu")
	)
	(gr_line
		(start 68.035678 7.050786)
		(end 68.411344 6.514084)
		(stroke
			(width 0.0635)
			(type default)
		)
		(layer "F.Cu")
	)
	(gr_line
		(start 68.11899 -5.111242)
		(end 68.12661 -5.118608)
		(stroke
			(width 0.0635)
			(type default)
		)
		(layer "F.Cu")
	)
	(gr_line
		(start 68.12661 -5.118608)
		(end 68.12661 -5.122164)
		(stroke
			(width 0.0635)
			(type default)
		)
		(layer "F.Cu")
	)
	(gr_line
		(start 68.342256 -4.902962)
		(end 68.345304 -4.902962)
		(stroke
			(width 0.0635)
			(type default)
		)
		(layer "F.Cu")
	)
	(gr_line
		(start 68.354956 -4.916678)
		(end 68.394072 -4.972304)
		(stroke
			(width 0.0635)
			(type default)
		)
		(layer "F.Cu")
	)
	(gr_line
		(start 68.35902 5.751576)
		(end 68.401692 5.992114)
		(stroke
			(width 0.0635)
			(type default)
		)
		(layer "F.Cu")
	)
	(gr_line
		(start 68.35902 5.751576)
		(end 68.57746 5.439664)
		(stroke
			(width 0.0635)
			(type default)
		)
		(layer "F.Cu")
	)
	(gr_line
		(start 68.57746 5.439664)
		(end 68.818252 5.396992)
		(stroke
			(width 0.0635)
			(type default)
		)
		(layer "F.Cu")
	)
	(gr_line
		(start 68.674488 6.13791)
		(end 69.049392 5.602732)
		(stroke
			(width 0.0635)
			(type default)
		)
		(layer "F.Cu")
	)
	(gr_line
		(start 69.023992 -5.871972)
		(end 69.040248 -5.89534)
		(stroke
			(width 0.0635)
			(type default)
		)
		(layer "F.Cu")
	)
	(gr_line
		(start 69.040248 -5.89534)
		(end 69.045328 -5.923534)
		(stroke
			(width 0.0635)
			(type default)
		)
		(layer "F.Cu")
	)
	(gr_line
		(start 69.079872 -9.250426)
		(end 69.139562 -9.155684)
		(stroke
			(width 0.0635)
			(type default)
		)
		(layer "F.Cu")
	)
	(gr_line
		(start 69.139562 -9.155684)
		(end 69.379846 -8.674862)
		(stroke
			(width 0.0635)
			(type default)
		)
		(layer "F.Cu")
	)
	(gr_arc
		(start 69.179948 11.055858)
		(mid 69.212204 10.894168)
		(end 69.3039 10.757154)
		(stroke
			(width 0.0635)
			(type default)
		)
		(layer "F.Cu")
	)
	(gr_line
		(start 69.179948 12.133072)
		(end 69.179948 11.055858)
		(stroke
			(width 0.0635)
			(type default)
		)
		(layer "F.Cu")
	)
	(gr_line
		(start 69.284342 -8.297926)
		(end 69.353176 -8.372094)
		(stroke
			(width 0.0635)
			(type default)
		)
		(layer "F.Cu")
	)
	(gr_line
		(start 69.3039 10.757154)
		(end 69.304154 10.7569)
		(stroke
			(width 0.0635)
			(type default)
		)
		(layer "F.Cu")
	)
	(gr_arc
		(start 69.379846 -8.674862)
		(mid 69.395818 -8.637093)
		(end 69.407024 -8.597646)
		(stroke
			(width 0.0635)
			(type default)
		)
		(layer "F.Cu")
	)
	(gr_arc
		(start 69.390006 -7.949946)
		(mid 69.542025 -8.039073)
		(end 69.70776 -7.979156)
		(stroke
			(width 0.0635)
			(type default)
		)
		(layer "F.Cu")
	)
	(gr_line
		(start 69.393054 9.242806)
		(end 69.459348 8.867648)
		(stroke
			(width 0.0635)
			(type default)
		)
		(layer "F.Cu")
	)
	(gr_line
		(start 69.393054 9.242806)
		(end 69.533262 9.443212)
		(stroke
			(width 0.0635)
			(type default)
		)
		(layer "F.Cu")
	)
	(gr_arc
		(start 69.407024 -8.502142)
		(mid 69.393035 -8.431763)
		(end 69.353176 -8.372094)
		(stroke
			(width 0.0635)
			(type default)
		)
		(layer "F.Cu")
	)
	(gr_line
		(start 69.407024 -8.502142)
		(end 69.407024 -8.597646)
		(stroke
			(width 0.0635)
			(type default)
		)
		(layer "F.Cu")
	)
	(gr_arc
		(start 69.427598 10.45845)
		(mid 69.39555 10.619951)
		(end 69.304154 10.7569)
		(stroke
			(width 0.0635)
			(type default)
		)
		(layer "F.Cu")
	)
	(gr_line
		(start 69.459348 8.867648)
		(end 69.6595 8.72744)
		(stroke
			(width 0.0635)
			(type default)
		)
		(layer "F.Cu")
	)
	(gr_line
		(start 69.511926 1.407414)
		(end 69.520816 1.394714)
		(stroke
			(width 0.0635)
			(type default)
		)
		(layer "F.Cu")
	)
	(gr_line
		(start 69.520816 1.394714)
		(end 69.533516 1.385824)
		(stroke
			(width 0.0635)
			(type default)
		)
		(layer "F.Cu")
	)
	(gr_line
		(start 69.586348 8.147304)
		(end 69.652388 7.772146)
		(stroke
			(width 0.0635)
			(type default)
		)
		(layer "F.Cu")
	)
	(gr_line
		(start 69.586348 8.147304)
		(end 69.726556 8.347202)
		(stroke
			(width 0.0635)
			(type default)
		)
		(layer "F.Cu")
	)
	(gr_line
		(start 69.652388 7.772146)
		(end 69.85254 7.631938)
		(stroke
			(width 0.0635)
			(type default)
		)
		(layer "F.Cu")
	)
	(gr_line
		(start 69.70776 -7.979156)
		(end 69.747892 -7.939024)
		(stroke
			(width 0.0635)
			(type default)
		)
		(layer "F.Cu")
	)
	(gr_line
		(start 69.717412 8.413242)
		(end 69.728588 8.35025)
		(stroke
			(width 0.0635)
			(type default)
		)
		(layer "F.Cu")
	)
	(gr_line
		(start 69.747892 -7.939024)
		(end 70.079362 -7.250176)
		(stroke
			(width 0.0635)
			(type default)
		)
		(layer "F.Cu")
	)
	(gr_line
		(start 69.84238 9.460738)
		(end 69.955918 8.81634)
		(stroke
			(width 0.0635)
			(type default)
		)
		(layer "F.Cu")
	)
	(gr_line
		(start 69.855588 7.629906)
		(end 69.907404 7.336028)
		(stroke
			(width 0.0635)
			(type default)
		)
		(layer "F.Cu")
	)
	(gr_arc
		(start 69.856096 10.775696)
		(mid 69.764524 10.638649)
		(end 69.732398 10.476992)
		(stroke
			(width 0.0635)
			(type default)
		)
		(layer "F.Cu")
	)
	(gr_arc
		(start 69.856096 10.775696)
		(mid 69.947627 10.912753)
		(end 69.979794 11.0744)
		(stroke
			(width 0.0635)
			(type default)
		)
		(layer "F.Cu")
	)
	(gr_line
		(start 69.979794 12.133072)
		(end 69.979794 11.0744)
		(stroke
			(width 0.0635)
			(type default)
		)
		(layer "F.Cu")
	)
	(gr_line
		(start 70.006972 8.526526)
		(end 70.030086 8.394954)
		(stroke
			(width 0.0635)
			(type default)
		)
		(layer "F.Cu")
	)
	(gr_line
		(start 70.030086 8.3947)
		(end 70.030086 8.394954)
		(stroke
			(width 0.0635)
			(type default)
		)
		(layer "F.Cu")
	)
	(gr_line
		(start 70.035674 8.364728)
		(end 70.148958 7.721854)
		(stroke
			(width 0.0635)
			(type default)
		)
		(layer "F.Cu")
	)
	(gr_line
		(start 70.075806 6.38048)
		(end 70.075806 6.380734)
		(stroke
			(width 0.0635)
			(type default)
		)
		(layer "F.Cu")
	)
	(gr_line
		(start 70.075806 6.38048)
		(end 70.09003 6.299454)
		(stroke
			(width 0.0635)
			(type default)
		)
		(layer "F.Cu")
	)
	(gr_line
		(start 70.092824 6.283706)
		(end 70.09384 6.278118)
		(stroke
			(width 0.0635)
			(type default)
		)
		(layer "F.Cu")
	)
	(gr_line
		(start 70.09384 6.278118)
		(end 70.095364 6.277356)
		(stroke
			(width 0.0635)
			(type default)
		)
		(layer "F.Cu")
	)
	(gr_line
		(start 70.155054 7.68604)
		(end 70.17893 7.551674)
		(stroke
			(width 0.0635)
			(type default)
		)
		(layer "F.Cu")
	)
	(gr_line
		(start 70.380352 6.392418)
		(end 70.385178 6.38048)
		(stroke
			(width 0.0635)
			(type default)
		)
		(layer "F.Cu")
	)
	(gr_line
		(start 70.382384 6.397244)
		(end 70.380352 6.392418)
		(stroke
			(width 0.0635)
			(type default)
		)
		(layer "F.Cu")
	)
	(gr_line
		(start 71.45909 1.629664)
		(end 71.46798 1.616964)
		(stroke
			(width 0.0635)
			(type default)
		)
		(layer "F.Cu")
	)
	(gr_line
		(start 71.46798 1.616964)
		(end 71.48068 1.608074)
		(stroke
			(width 0.0635)
			(type default)
		)
		(layer "F.Cu")
	)
	(gr_arc
		(start 71.579994 10.992866)
		(mid 71.612205 10.830928)
		(end 71.703946 10.693654)
		(stroke
			(width 0.0635)
			(type default)
		)
		(layer "F.Cu")
	)
	(gr_line
		(start 71.579994 12.133072)
		(end 71.579994 10.992866)
		(stroke
			(width 0.0635)
			(type default)
		)
		(layer "F.Cu")
	)
	(gr_line
		(start 71.751698 7.849362)
		(end 71.817738 7.474204)
		(stroke
			(width 0.0635)
			(type default)
		)
		(layer "F.Cu")
	)
	(gr_line
		(start 71.751698 7.849362)
		(end 71.891652 8.049768)
		(stroke
			(width 0.0635)
			(type default)
		)
		(layer "F.Cu")
	)
	(gr_line
		(start 71.817738 7.474204)
		(end 72.01789 7.33425)
		(stroke
			(width 0.0635)
			(type default)
		)
		(layer "F.Cu")
	)
	(gr_arc
		(start 71.827644 10.39495)
		(mid 71.79553 10.556619)
		(end 71.703946 10.693654)
		(stroke
			(width 0.0635)
			(type default)
		)
		(layer "F.Cu")
	)
	(gr_line
		(start 71.944738 6.75386)
		(end 72.011032 6.378702)
		(stroke
			(width 0.0635)
			(type default)
		)
		(layer "F.Cu")
	)
	(gr_line
		(start 71.944738 6.75386)
		(end 72.084946 6.954012)
		(stroke
			(width 0.0635)
			(type default)
		)
		(layer "F.Cu")
	)
	(gr_line
		(start 72.011032 6.378702)
		(end 72.211184 6.238494)
		(stroke
			(width 0.0635)
			(type default)
		)
		(layer "F.Cu")
	)
	(gr_line
		(start 72.020938 7.332218)
		(end 72.063102 7.093204)
		(stroke
			(width 0.0635)
			(type default)
		)
		(layer "F.Cu")
	)
	(gr_line
		(start 72.20077 8.06704)
		(end 72.314308 7.424166)
		(stroke
			(width 0.0635)
			(type default)
		)
		(layer "F.Cu")
	)
	(gr_arc
		(start 72.256142 10.737342)
		(mid 72.16457 10.600295)
		(end 72.132444 10.438638)
		(stroke
			(width 0.0635)
			(type default)
		)
		(layer "F.Cu")
	)
	(gr_arc
		(start 72.256142 10.737342)
		(mid 72.347681 10.874399)
		(end 72.37984 11.036046)
		(stroke
			(width 0.0635)
			(type default)
		)
		(layer "F.Cu")
	)
	(gr_line
		(start 72.291448 5.796534)
		(end 72.296528 5.76834)
		(stroke
			(width 0.0635)
			(type default)
		)
		(layer "F.Cu")
	)
	(gr_line
		(start 72.296528 5.76834)
		(end 72.312784 5.744972)
		(stroke
			(width 0.0635)
			(type default)
		)
		(layer "F.Cu")
	)
	(gr_line
		(start 72.319642 7.392924)
		(end 72.363076 7.146036)
		(stroke
			(width 0.0635)
			(type default)
		)
		(layer "F.Cu")
	)
	(gr_line
		(start 72.37984 12.133072)
		(end 72.37984 11.036046)
		(stroke
			(width 0.0635)
			(type default)
		)
		(layer "F.Cu")
	)
	(gr_line
		(start 72.394064 6.971792)
		(end 72.507602 6.327394)
		(stroke
			(width 0.0635)
			(type default)
		)
		(layer "F.Cu")
	)
	(gr_line
		(start 72.832468 -6.41985)
		(end 72.845168 -6.42874)
		(stroke
			(width 0.0635)
			(type default)
		)
		(layer "F.Cu")
	)
	(gr_line
		(start 72.845168 -6.42874)
		(end 72.854058 -6.44144)
		(stroke
			(width 0.0635)
			(type default)
		)
		(layer "F.Cu")
	)
	(gr_line
		(start 73.058782 1.985772)
		(end 73.067672 1.973072)
		(stroke
			(width 0.0635)
			(type default)
		)
		(layer "F.Cu")
	)
	(gr_line
		(start 73.067672 1.973072)
		(end 73.080372 1.964182)
		(stroke
			(width 0.0635)
			(type default)
		)
		(layer "F.Cu")
	)
	(gr_line
		(start 73.080372 -9.250426)
		(end 73.259696 -8.916162)
		(stroke
			(width 0.0635)
			(type default)
		)
		(layer "F.Cu")
	)
	(gr_line
		(start 73.152 -6.866636)
		(end 73.176892 -6.902196)
		(stroke
			(width 0.0635)
			(type default)
		)
		(layer "F.Cu")
	)
	(gr_line
		(start 73.176892 -6.902196)
		(end 73.180956 -6.945376)
		(stroke
			(width 0.0635)
			(type default)
		)
		(layer "F.Cu")
	)
	(gr_line
		(start 73.259696 -8.916162)
		(end 73.455276 -8.524748)
		(stroke
			(width 0.0635)
			(type default)
		)
		(layer "F.Cu")
	)
	(gr_line
		(start 73.284842 -8.297926)
		(end 73.29805 -8.30453)
		(stroke
			(width 0.0635)
			(type default)
		)
		(layer "F.Cu")
	)
	(gr_line
		(start 73.398126 -8.354314)
		(end 73.39838 -8.354314)
		(stroke
			(width 0.0635)
			(type default)
		)
		(layer "F.Cu")
	)
	(gr_arc
		(start 73.455276 -8.524748)
		(mid 73.462112 -8.427757)
		(end 73.39838 -8.354314)
		(stroke
			(width 0.0635)
			(type default)
		)
		(layer "F.Cu")
	)
	(gr_line
		(start 73.484232 -4.31927)
		(end 73.5076 -4.335526)
		(stroke
			(width 0.0635)
			(type default)
		)
		(layer "F.Cu")
	)
	(gr_line
		(start 73.5076 -4.335526)
		(end 73.535794 -4.340606)
		(stroke
			(width 0.0635)
			(type default)
		)
		(layer "F.Cu")
	)
	(gr_line
		(start 73.53427 -8.081518)
		(end 73.534778 -8.081772)
		(stroke
			(width 0.0635)
			(type default)
		)
		(layer "F.Cu")
	)
	(gr_line
		(start 73.534778 -8.081772)
		(end 73.535032 -8.081772)
		(stroke
			(width 0.0635)
			(type default)
		)
		(layer "F.Cu")
	)
	(gr_arc
		(start 73.535032 -8.081772)
		(mid 73.632033 -8.088621)
		(end 73.705466 -8.024876)
		(stroke
			(width 0.0635)
			(type default)
		)
		(layer "F.Cu")
	)
	(gr_line
		(start 73.578974 -5.851652)
		(end 73.602342 -5.867908)
		(stroke
			(width 0.0635)
			(type default)
		)
		(layer "F.Cu")
	)
	(gr_line
		(start 73.602342 -5.867908)
		(end 73.630536 -5.872988)
		(stroke
			(width 0.0635)
			(type default)
		)
		(layer "F.Cu")
	)
	(gr_line
		(start 73.705466 -8.024876)
		(end 74.079862 -7.275068)
		(stroke
			(width 0.0635)
			(type default)
		)
		(layer "F.Cu")
	)
	(gr_line
		(start 73.912222 6.953758)
		(end 73.978516 7.328916)
		(stroke
			(width 0.0635)
			(type default)
		)
		(layer "F.Cu")
	)
	(gr_line
		(start 73.912222 6.953758)
		(end 74.05243 6.753352)
		(stroke
			(width 0.0635)
			(type default)
		)
		(layer "F.Cu")
	)
	(gr_line
		(start 73.95464 6.185408)
		(end 73.95718 6.170422)
		(stroke
			(width 0.0635)
			(type default)
		)
		(layer "F.Cu")
	)
	(gr_line
		(start 73.95464 6.185408)
		(end 73.957434 6.201156)
		(stroke
			(width 0.0635)
			(type default)
		)
		(layer "F.Cu")
	)
	(gr_line
		(start 73.973944 -3.188462)
		(end 73.997312 -3.204718)
		(stroke
			(width 0.0635)
			(type default)
		)
		(layer "F.Cu")
	)
	(gr_line
		(start 73.978516 7.328916)
		(end 74.178922 7.469124)
		(stroke
			(width 0.0635)
			(type default)
		)
		(layer "F.Cu")
	)
	(gr_arc
		(start 73.979786 11.031474)
		(mid 74.011997 10.869536)
		(end 74.103738 10.732262)
		(stroke
			(width 0.0635)
			(type default)
		)
		(layer "F.Cu")
	)
	(gr_line
		(start 73.979786 12.133072)
		(end 73.979786 11.031474)
		(stroke
			(width 0.0635)
			(type default)
		)
		(layer "F.Cu")
	)
	(gr_line
		(start 73.997312 -3.204718)
		(end 74.025506 -3.209798)
		(stroke
			(width 0.0635)
			(type default)
		)
		(layer "F.Cu")
	)
	(gr_line
		(start 74.026776 5.776468)
		(end 74.031856 5.74802)
		(stroke
			(width 0.0635)
			(type default)
		)
		(layer "F.Cu")
	)
	(gr_line
		(start 74.031856 5.74802)
		(end 74.048112 5.724652)
		(stroke
			(width 0.0635)
			(type default)
		)
		(layer "F.Cu")
	)
	(gr_line
		(start 74.079862 -7.250176)
		(end 74.079862 -7.275068)
		(stroke
			(width 0.0635)
			(type default)
		)
		(layer "F.Cu")
	)
	(gr_line
		(start 74.10577 8.04926)
		(end 74.172064 8.424418)
		(stroke
			(width 0.0635)
			(type default)
		)
		(layer "F.Cu")
	)
	(gr_line
		(start 74.10577 8.04926)
		(end 74.245978 7.849108)
		(stroke
			(width 0.0635)
			(type default)
		)
		(layer "F.Cu")
	)
	(gr_line
		(start 74.172064 8.424418)
		(end 74.372216 8.564626)
		(stroke
			(width 0.0635)
			(type default)
		)
		(layer "F.Cu")
	)
	(gr_arc
		(start 74.227436 10.433558)
		(mid 74.195319 10.595225)
		(end 74.103738 10.732262)
		(stroke
			(width 0.0635)
			(type default)
		)
		(layer "F.Cu")
	)
	(gr_line
		(start 74.361548 6.735826)
		(end 74.47534 7.380224)
		(stroke
			(width 0.0635)
			(type default)
		)
		(layer "F.Cu")
	)
	(gr_line
		(start 74.429366 2.722118)
		(end 74.464164 2.672588)
		(stroke
			(width 0.0635)
			(type default)
		)
		(layer "F.Cu")
	)
	(gr_line
		(start 74.448924 -2.05613)
		(end 74.472292 -2.072386)
		(stroke
			(width 0.0635)
			(type default)
		)
		(layer "F.Cu")
	)
	(gr_line
		(start 74.472292 -2.072386)
		(end 74.500486 -2.077466)
		(stroke
			(width 0.0635)
			(type default)
		)
		(layer "F.Cu")
	)
	(gr_line
		(start 74.475086 2.65684)
		(end 74.475594 2.656078)
		(stroke
			(width 0.0635)
			(type default)
		)
		(layer "F.Cu")
	)
	(gr_line
		(start 74.475594 2.656078)
		(end 74.475848 2.655824)
		(stroke
			(width 0.0635)
			(type default)
		)
		(layer "F.Cu")
	)
	(gr_line
		(start 74.475848 2.655824)
		(end 74.479404 2.655824)
		(stroke
			(width 0.0635)
			(type default)
		)
		(layer "F.Cu")
	)
	(gr_line
		(start 74.554588 7.82955)
		(end 74.66838 8.475472)
		(stroke
			(width 0.0635)
			(type default)
		)
		(layer "F.Cu")
	)
	(gr_arc
		(start 74.656188 10.698988)
		(mid 74.564461 10.561708)
		(end 74.532236 10.399776)
		(stroke
			(width 0.0635)
			(type default)
		)
		(layer "F.Cu")
	)
	(gr_arc
		(start 74.656188 10.698988)
		(mid 74.747723 10.836044)
		(end 74.779886 10.997692)
		(stroke
			(width 0.0635)
			(type default)
		)
		(layer "F.Cu")
	)
	(gr_line
		(start 74.69505 2.87147)
		(end 74.701146 2.865374)
		(stroke
			(width 0.0635)
			(type default)
		)
		(layer "F.Cu")
	)
	(gr_line
		(start 74.69505 2.874518)
		(end 74.69505 2.87147)
		(stroke
			(width 0.0635)
			(type default)
		)
		(layer "F.Cu")
	)
	(gr_line
		(start 74.748136 8.957564)
		(end 74.75093 8.941816)
		(stroke
			(width 0.0635)
			(type default)
		)
		(layer "F.Cu")
	)
	(gr_line
		(start 74.74839 8.92683)
		(end 74.75093 8.941816)
		(stroke
			(width 0.0635)
			(type default)
		)
		(layer "F.Cu")
	)
	(gr_line
		(start 74.779886 12.133072)
		(end 74.779886 10.997692)
		(stroke
			(width 0.0635)
			(type default)
		)
		(layer "F.Cu")
	)
	(gr_line
		(start 74.916538 -0.79756)
		(end 74.939906 -0.813816)
		(stroke
			(width 0.0635)
			(type default)
		)
		(layer "F.Cu")
	)
	(gr_line
		(start 74.939906 -0.813816)
		(end 74.9681 -0.818896)
		(stroke
			(width 0.0635)
			(type default)
		)
		(layer "F.Cu")
	)
	(gr_line
		(start 75.303126 0.408178)
		(end 75.325732 0.392176)
		(stroke
			(width 0.0635)
			(type default)
		)
		(layer "F.Cu")
	)
	(gr_line
		(start 75.325732 0.392176)
		(end 75.353926 0.387096)
		(stroke
			(width 0.0635)
			(type default)
		)
		(layer "F.Cu")
	)
	(gr_line
		(start 75.687174 6.6294)
		(end 75.689714 6.614414)
		(stroke
			(width 0.0635)
			(type default)
		)
		(layer "F.Cu")
	)
	(gr_line
		(start 75.687174 6.6294)
		(end 75.689968 6.645148)
		(stroke
			(width 0.0635)
			(type default)
		)
		(layer "F.Cu")
	)
	(gr_line
		(start 75.795632 3.228848)
		(end 75.804522 3.216148)
		(stroke
			(width 0.0635)
			(type default)
		)
		(layer "F.Cu")
	)
	(gr_line
		(start 75.79741 6.003544)
		(end 75.80249 5.97535)
		(stroke
			(width 0.0635)
			(type default)
		)
		(layer "F.Cu")
	)
	(gr_line
		(start 75.80249 5.97535)
		(end 75.818492 5.952744)
		(stroke
			(width 0.0635)
			(type default)
		)
		(layer "F.Cu")
	)
	(gr_line
		(start 75.804522 3.216148)
		(end 75.817222 3.207258)
		(stroke
			(width 0.0635)
			(type default)
		)
		(layer "F.Cu")
	)
	(gr_line
		(start 75.91425 7.918196)
		(end 75.91933 7.94639)
		(stroke
			(width 0.0635)
			(type default)
		)
		(layer "F.Cu")
	)
	(gr_line
		(start 75.91933 7.94639)
		(end 75.935586 7.969758)
		(stroke
			(width 0.0635)
			(type default)
		)
		(layer "F.Cu")
	)
	(gr_line
		(start 76.04125 1.529588)
		(end 76.063856 1.513586)
		(stroke
			(width 0.0635)
			(type default)
		)
		(layer "F.Cu")
	)
	(gr_line
		(start 76.063856 1.513586)
		(end 76.09205 1.508506)
		(stroke
			(width 0.0635)
			(type default)
		)
		(layer "F.Cu")
	)
	(gr_arc
		(start 76.379832 10.967974)
		(mid 76.412054 10.806162)
		(end 76.503784 10.669016)
		(stroke
			(width 0.0635)
			(type default)
		)
		(layer "F.Cu")
	)
	(gr_line
		(start 76.379832 12.133072)
		(end 76.379832 10.967974)
		(stroke
			(width 0.0635)
			(type default)
		)
		(layer "F.Cu")
	)
	(gr_line
		(start 76.399898 -6.384544)
		(end 76.400406 -6.385814)
		(stroke
			(width 0.0635)
			(type default)
		)
		(layer "F.Cu")
	)
	(gr_line
		(start 76.400406 -6.385814)
		(end 76.5048 -6.429248)
		(stroke
			(width 0.0635)
			(type default)
		)
		(layer "F.Cu")
	)
	(gr_line
		(start 76.518262 -6.09854)
		(end 76.520548 -6.097524)
		(stroke
			(width 0.0635)
			(type default)
		)
		(layer "F.Cu")
	)
	(gr_line
		(start 76.520548 -6.097524)
		(end 76.634594 -6.145022)
		(stroke
			(width 0.0635)
			(type default)
		)
		(layer "F.Cu")
	)
	(gr_arc
		(start 76.627482 10.370312)
		(mid 76.59535 10.53197)
		(end 76.503784 10.669016)
		(stroke
			(width 0.0635)
			(type default)
		)
		(layer "F.Cu")
	)
	(gr_line
		(start 76.63434 2.634996)
		(end 76.657708 2.61874)
		(stroke
			(width 0.0635)
			(type default)
		)
		(layer "F.Cu")
	)
	(gr_line
		(start 76.634594 -6.145022)
		(end 76.657962 -6.161532)
		(stroke
			(width 0.0635)
			(type default)
		)
		(layer "F.Cu")
	)
	(gr_line
		(start 76.657708 2.61874)
		(end 76.685902 2.61366)
		(stroke
			(width 0.0635)
			(type default)
		)
		(layer "F.Cu")
	)
	(gr_line
		(start 76.882498 4.432554)
		(end 76.921614 4.376928)
		(stroke
			(width 0.0635)
			(type default)
		)
		(layer "F.Cu")
	)
	(gr_line
		(start 76.887832 8.797798)
		(end 76.904088 8.821166)
		(stroke
			(width 0.0635)
			(type default)
		)
		(layer "F.Cu")
	)
	(gr_line
		(start 76.904088 8.821166)
		(end 76.909168 8.84936)
		(stroke
			(width 0.0635)
			(type default)
		)
		(layer "F.Cu")
	)
	(gr_line
		(start 76.931266 4.363212)
		(end 76.934314 4.363212)
		(stroke
			(width 0.0635)
			(type default)
		)
		(layer "F.Cu")
	)
	(gr_line
		(start 76.935838 -6.356096)
		(end 76.948538 -6.364986)
		(stroke
			(width 0.0635)
			(type default)
		)
		(layer "F.Cu")
	)
	(gr_line
		(start 76.948538 -6.364986)
		(end 76.957428 -6.377432)
		(stroke
			(width 0.0635)
			(type default)
		)
		(layer "F.Cu")
	)
	(gr_line
		(start 77.035406 9.59739)
		(end 77.0382 9.581642)
		(stroke
			(width 0.0635)
			(type default)
		)
		(layer "F.Cu")
	)
	(gr_line
		(start 77.03566 9.566656)
		(end 77.0382 9.581642)
		(stroke
			(width 0.0635)
			(type default)
		)
		(layer "F.Cu")
	)
	(gr_arc
		(start 77.05598 10.686034)
		(mid 76.964438 10.548842)
		(end 76.932282 10.387076)
		(stroke
			(width 0.0635)
			(type default)
		)
		(layer "F.Cu")
	)
	(gr_line
		(start 77.05598 10.686034)
		(end 77.093064 10.723118)
		(stroke
			(width 0.0635)
			(type default)
		)
		(layer "F.Cu")
	)
	(gr_line
		(start 77.079602 -9.275318)
		(end 77.391514 -8.652764)
		(stroke
			(width 0.0635)
			(type default)
		)
		(layer "F.Cu")
	)
	(gr_line
		(start 77.079602 -9.250426)
		(end 77.079602 -9.275318)
		(stroke
			(width 0.0635)
			(type default)
		)
		(layer "F.Cu")
	)
	(gr_arc
		(start 77.093064 10.723118)
		(mid 77.157356 10.819109)
		(end 77.179932 10.932414)
		(stroke
			(width 0.0635)
			(type default)
		)
		(layer "F.Cu")
	)
	(gr_line
		(start 77.14996 4.578858)
		(end 77.15758 4.571238)
		(stroke
			(width 0.0635)
			(type default)
		)
		(layer "F.Cu")
	)
	(gr_line
		(start 77.14996 4.582414)
		(end 77.14996 4.578858)
		(stroke
			(width 0.0635)
			(type default)
		)
		(layer "F.Cu")
	)
	(gr_line
		(start 77.15758 -6.663944)
		(end 77.173582 -6.68655)
		(stroke
			(width 0.0635)
			(type default)
		)
		(layer "F.Cu")
	)
	(gr_line
		(start 77.173582 -6.68655)
		(end 77.178662 -6.714744)
		(stroke
			(width 0.0635)
			(type default)
		)
		(layer "F.Cu")
	)
	(gr_line
		(start 77.179932 12.133072)
		(end 77.179932 10.932414)
		(stroke
			(width 0.0635)
			(type default)
		)
		(layer "F.Cu")
	)
	(gr_line
		(start 77.285342 -8.297926)
		(end 77.343508 -8.356092)
		(stroke
			(width 0.0635)
			(type default)
		)
		(layer "F.Cu")
	)
	(gr_arc
		(start 77.305154 7.702042)
		(mid 77.558594 7.806999)
		(end 77.663548 8.060436)
		(stroke
			(width 0.0635)
			(type default)
		)
		(layer "F.Cu")
	)
	(gr_arc
		(start 77.391514 -8.652764)
		(mid 77.415432 -8.496674)
		(end 77.343508 -8.356092)
		(stroke
			(width 0.0635)
			(type default)
		)
		(layer "F.Cu")
	)
	(gr_arc
		(start 77.468984 -8.048752)
		(mid 77.50132 -8.075424)
		(end 77.53985 -8.091932)
		(stroke
			(width 0.0635)
			(type default)
		)
		(layer "F.Cu")
	)
	(gr_arc
		(start 77.53985 -8.091932)
		(mid 77.541118 -8.092319)
		(end 77.54239 -8.092694)
		(stroke
			(width 0.0635)
			(type default)
		)
		(layer "F.Cu")
	)
	(gr_line
		(start 77.54239 -8.092694)
		(end 77.542644 -8.092694)
		(stroke
			(width 0.0635)
			(type default)
		)
		(layer "F.Cu")
	)
	(gr_arc
		(start 77.542644 -8.092694)
		(mid 77.635573 -8.085913)
		(end 77.705966 -8.024876)
		(stroke
			(width 0.0635)
			(type default)
		)
		(layer "F.Cu")
	)
	(gr_line
		(start 77.705966 -8.024876)
		(end 78.001622 -7.432802)
		(stroke
			(width 0.0635)
			(type default)
		)
		(layer "F.Cu")
	)
	(gr_line
		(start 77.78369 3.735578)
		(end 77.806296 3.719576)
		(stroke
			(width 0.0635)
			(type default)
		)
		(layer "F.Cu")
	)
	(gr_line
		(start 77.806296 3.719576)
		(end 77.83449 3.714496)
		(stroke
			(width 0.0635)
			(type default)
		)
		(layer "F.Cu")
	)
	(gr_arc
		(start 77.968348 8.054848)
		(mid 78.071682 7.805376)
		(end 78.321154 7.702042)
		(stroke
			(width 0.0635)
			(type default)
		)
		(layer "F.Cu")
	)
	(gr_line
		(start 78.001622 -7.432802)
		(end 78.080362 -7.250176)
		(stroke
			(width 0.0635)
			(type default)
		)
		(layer "F.Cu")
	)
	(gr_arc
		(start 78.779878 10.980674)
		(mid 78.811963 10.819194)
		(end 78.903322 10.682224)
		(stroke
			(width 0.0635)
			(type default)
		)
		(layer "F.Cu")
	)
	(gr_line
		(start 78.779878 12.133072)
		(end 78.779878 10.980674)
		(stroke
			(width 0.0635)
			(type default)
		)
		(layer "F.Cu")
	)
	(gr_line
		(start 78.903322 10.682224)
		(end 78.903576 10.68197)
		(stroke
			(width 0.0635)
			(type default)
		)
		(layer "F.Cu")
	)
	(gr_arc
		(start 79.027528 10.383266)
		(mid 78.995219 10.544926)
		(end 78.903576 10.68197)
		(stroke
			(width 0.0635)
			(type default)
		)
		(layer "F.Cu")
	)
	(gr_arc
		(start 79.45628 10.67308)
		(mid 79.364553 10.5358)
		(end 79.332328 10.373868)
		(stroke
			(width 0.0635)
			(type default)
		)
		(layer "F.Cu")
	)
	(gr_arc
		(start 79.45628 10.67308)
		(mid 79.54782 10.810135)
		(end 79.579978 10.971784)
		(stroke
			(width 0.0635)
			(type default)
		)
		(layer "F.Cu")
	)
	(gr_line
		(start 79.579978 12.133072)
		(end 79.579978 10.971784)
		(stroke
			(width 0.0635)
			(type default)
		)
		(layer "F.Cu")
	)
	(gr_line
		(start 79.895954 7.702042)
		(end 79.965042 7.702042)
		(stroke
			(width 0.0635)
			(type default)
		)
		(layer "F.Cu")
	)
	(gr_arc
		(start 79.965042 7.702042)
		(mid 80.17641 7.78962)
		(end 80.264 8.001)
		(stroke
			(width 0.0635)
			(type default)
		)
		(layer "F.Cu")
	)
	(gr_arc
		(start 80.5688 8.001)
		(mid 80.656363 7.789605)
		(end 80.867758 7.702042)
		(stroke
			(width 0.0635)
			(type default)
		)
		(layer "F.Cu")
	)
	(gr_line
		(start 80.867758 7.702042)
		(end 80.911954 7.702042)
		(stroke
			(width 0.0635)
			(type default)
		)
		(layer "F.Cu")
	)
	(gr_arc
		(start 81.179924 10.980674)
		(mid 81.212009 10.819194)
		(end 81.303368 10.682224)
		(stroke
			(width 0.0635)
			(type default)
		)
		(layer "F.Cu")
	)
	(gr_line
		(start 81.179924 12.133072)
		(end 81.179924 10.980674)
		(stroke
			(width 0.0635)
			(type default)
		)
		(layer "F.Cu")
	)
	(gr_line
		(start 81.303368 10.682224)
		(end 81.303622 10.68197)
		(stroke
			(width 0.0635)
			(type default)
		)
		(layer "F.Cu")
	)
	(gr_arc
		(start 81.427574 10.383266)
		(mid 81.395262 10.544923)
		(end 81.303622 10.68197)
		(stroke
			(width 0.0635)
			(type default)
		)
		(layer "F.Cu")
	)
	(gr_arc
		(start 81.856326 10.67308)
		(mid 81.764599 10.5358)
		(end 81.732374 10.373868)
		(stroke
			(width 0.0635)
			(type default)
		)
		(layer "F.Cu")
	)
	(gr_arc
		(start 81.856326 10.67308)
		(mid 81.947856 10.810138)
		(end 81.980024 10.971784)
		(stroke
			(width 0.0635)
			(type default)
		)
		(layer "F.Cu")
	)
	(gr_line
		(start 81.980024 12.133072)
		(end 81.980024 10.971784)
		(stroke
			(width 0.0635)
			(type default)
		)
		(layer "F.Cu")
	)
	(gr_line
		(start 82.079592 -7.250176)
		(end 82.237834 -7.591298)
		(stroke
			(width 0.0635)
			(type default)
		)
		(layer "F.Cu")
	)
	(gr_line
		(start 82.201004 -5.55879)
		(end 82.229198 -5.56387)
		(stroke
			(width 0.0635)
			(type default)
		)
		(layer "F.Cu")
	)
	(gr_line
		(start 82.229198 -5.56387)
		(end 82.252566 -5.580126)
		(stroke
			(width 0.0635)
			(type default)
		)
		(layer "F.Cu")
	)
	(gr_line
		(start 82.237834 -7.591298)
		(end 82.455004 -8.02513)
		(stroke
			(width 0.0635)
			(type default)
		)
		(layer "F.Cu")
	)
	(gr_arc
		(start 82.455004 -8.02513)
		(mid 82.52849 -8.088749)
		(end 82.625438 -8.081772)
		(stroke
			(width 0.0635)
			(type default)
		)
		(layer "F.Cu")
	)
	(gr_line
		(start 82.486754 7.702042)
		(end 82.555842 7.702042)
		(stroke
			(width 0.0635)
			(type default)
		)
		(layer "F.Cu")
	)
	(gr_arc
		(start 82.555842 7.702042)
		(mid 82.76721 7.78962)
		(end 82.8548 8.001)
		(stroke
			(width 0.0635)
			(type default)
		)
		(layer "F.Cu")
	)
	(gr_line
		(start 82.70494 -8.525002)
		(end 82.838798 -8.792464)
		(stroke
			(width 0.0635)
			(type default)
		)
		(layer "F.Cu")
	)
	(gr_arc
		(start 82.761582 -8.354568)
		(mid 82.697978 -8.428055)
		(end 82.70494 -8.525002)
		(stroke
			(width 0.0635)
			(type default)
		)
		(layer "F.Cu")
	)
	(gr_line
		(start 82.838798 -8.792464)
		(end 83.080352 -9.250426)
		(stroke
			(width 0.0635)
			(type default)
		)
		(layer "F.Cu")
	)
	(gr_line
		(start 82.861912 -8.30453)
		(end 82.875374 -8.297672)
		(stroke
			(width 0.0635)
			(type default)
		)
		(layer "F.Cu")
	)
	(gr_line
		(start 82.878422 -6.01853)
		(end 82.891122 -6.02742)
		(stroke
			(width 0.0635)
			(type default)
		)
		(layer "F.Cu")
	)
	(gr_line
		(start 82.891122 -6.02742)
		(end 82.900012 -6.04012)
		(stroke
			(width 0.0635)
			(type default)
		)
		(layer "F.Cu")
	)
	(gr_arc
		(start 83.1596 8.001)
		(mid 83.247163 7.789605)
		(end 83.458558 7.702042)
		(stroke
			(width 0.0635)
			(type default)
		)
		(layer "F.Cu")
	)
	(gr_line
		(start 83.185762 -6.448552)
		(end 83.201764 -6.471158)
		(stroke
			(width 0.0635)
			(type default)
		)
		(layer "F.Cu")
	)
	(gr_line
		(start 83.201764 -6.471158)
		(end 83.206844 -6.499352)
		(stroke
			(width 0.0635)
			(type default)
		)
		(layer "F.Cu")
	)
	(gr_line
		(start 83.458558 7.702042)
		(end 83.502754 7.702042)
		(stroke
			(width 0.0635)
			(type default)
		)
		(layer "F.Cu")
	)
	(gr_arc
		(start 83.57997 10.980674)
		(mid 83.612055 10.819194)
		(end 83.703414 10.682224)
		(stroke
			(width 0.0635)
			(type default)
		)
		(layer "F.Cu")
	)
	(gr_line
		(start 83.57997 12.133072)
		(end 83.57997 10.980674)
		(stroke
			(width 0.0635)
			(type default)
		)
		(layer "F.Cu")
	)
	(gr_line
		(start 83.703414 10.682224)
		(end 83.703668 10.68197)
		(stroke
			(width 0.0635)
			(type default)
		)
		(layer "F.Cu")
	)
	(gr_line
		(start 83.827366 10.373868)
		(end 83.82762 10.373868)
		(stroke
			(width 0.0635)
			(type default)
		)
		(layer "F.Cu")
	)
	(gr_arc
		(start 83.82762 10.383266)
		(mid 83.795311 10.544926)
		(end 83.703668 10.68197)
		(stroke
			(width 0.0635)
			(type default)
		)
		(layer "F.Cu")
	)
	(gr_line
		(start 83.82762 10.383266)
		(end 83.82762 10.373868)
		(stroke
			(width 0.0635)
			(type default)
		)
		(layer "F.Cu")
	)
	(gr_line
		(start 84.132166 10.373868)
		(end 84.132166 10.069068)
		(stroke
			(width 0.0635)
			(type default)
		)
		(layer "F.Cu")
	)
	(gr_arc
		(start 84.256118 10.67308)
		(mid 84.164391 10.5358)
		(end 84.132166 10.373868)
		(stroke
			(width 0.0635)
			(type default)
		)
		(layer "F.Cu")
	)
	(gr_arc
		(start 84.256118 10.67308)
		(mid 84.34765 10.810138)
		(end 84.379816 10.971784)
		(stroke
			(width 0.0635)
			(type default)
		)
		(layer "F.Cu")
	)
	(gr_line
		(start 84.379816 12.133072)
		(end 84.379816 10.971784)
		(stroke
			(width 0.0635)
			(type default)
		)
		(layer "F.Cu")
	)
	(gr_line
		(start 85.018118 -4.838192)
		(end 85.046312 -4.843272)
		(stroke
			(width 0.0635)
			(type default)
		)
		(layer "F.Cu")
	)
	(gr_line
		(start 85.046312 -4.843272)
		(end 85.068918 -4.859274)
		(stroke
			(width 0.0635)
			(type default)
		)
		(layer "F.Cu")
	)
	(gr_line
		(start 85.077554 7.702042)
		(end 85.146642 7.702042)
		(stroke
			(width 0.0635)
			(type default)
		)
		(layer "F.Cu")
	)
	(gr_arc
		(start 85.146642 7.702042)
		(mid 85.35801 7.78962)
		(end 85.4456 8.001)
		(stroke
			(width 0.0635)
			(type default)
		)
		(layer "F.Cu")
	)
	(gr_arc
		(start 85.7504 8.001)
		(mid 85.837963 7.789605)
		(end 86.049358 7.702042)
		(stroke
			(width 0.0635)
			(type default)
		)
		(layer "F.Cu")
	)
	(gr_arc
		(start 85.980016 10.980674)
		(mid 86.012101 10.819194)
		(end 86.10346 10.682224)
		(stroke
			(width 0.0635)
			(type default)
		)
		(layer "F.Cu")
	)
	(gr_line
		(start 85.980016 12.133072)
		(end 85.980016 10.980674)
		(stroke
			(width 0.0635)
			(type default)
		)
		(layer "F.Cu")
	)
	(gr_line
		(start 86.049358 7.702042)
		(end 86.093554 7.702042)
		(stroke
			(width 0.0635)
			(type default)
		)
		(layer "F.Cu")
	)
	(gr_line
		(start 86.080092 -7.250176)
		(end 86.213696 -7.54253)
		(stroke
			(width 0.0635)
			(type default)
		)
		(layer "F.Cu")
	)
	(gr_line
		(start 86.10346 10.682224)
		(end 86.103714 10.68197)
		(stroke
			(width 0.0635)
			(type default)
		)
		(layer "F.Cu")
	)
	(gr_line
		(start 86.213696 -7.54253)
		(end 86.454488 -8.024876)
		(stroke
			(width 0.0635)
			(type default)
		)
		(layer "F.Cu")
	)
	(gr_arc
		(start 86.227666 10.383266)
		(mid 86.195354 10.544923)
		(end 86.103714 10.68197)
		(stroke
			(width 0.0635)
			(type default)
		)
		(layer "F.Cu")
	)
	(gr_line
		(start 86.227666 10.383266)
		(end 86.227666 9.475978)
		(stroke
			(width 0.0635)
			(type default)
		)
		(layer "F.Cu")
	)
	(gr_arc
		(start 86.454488 -8.024876)
		(mid 86.527902 -8.088605)
		(end 86.624922 -8.081772)
		(stroke
			(width 0.0635)
			(type default)
		)
		(layer "F.Cu")
	)
	(gr_line
		(start 86.532212 10.373868)
		(end 86.532212 9.474962)
		(stroke
			(width 0.0635)
			(type default)
		)
		(layer "F.Cu")
	)
	(gr_line
		(start 86.624922 -8.081772)
		(end 86.625176 -8.081772)
		(stroke
			(width 0.0635)
			(type default)
		)
		(layer "F.Cu")
	)
	(gr_line
		(start 86.625176 -8.081772)
		(end 86.62924 -8.07974)
		(stroke
			(width 0.0635)
			(type default)
		)
		(layer "F.Cu")
	)
	(gr_arc
		(start 86.656164 10.67308)
		(mid 86.564437 10.5358)
		(end 86.532212 10.373868)
		(stroke
			(width 0.0635)
			(type default)
		)
		(layer "F.Cu")
	)
	(gr_arc
		(start 86.656164 10.67308)
		(mid 86.747707 10.810135)
		(end 86.779862 10.971784)
		(stroke
			(width 0.0635)
			(type default)
		)
		(layer "F.Cu")
	)
	(gr_line
		(start 86.704678 -8.524748)
		(end 86.954614 -9.025128)
		(stroke
			(width 0.0635)
			(type default)
		)
		(layer "F.Cu")
	)
	(gr_line
		(start 86.712552 -6.00964)
		(end 86.748366 -6.034786)
		(stroke
			(width 0.0635)
			(type default)
		)
		(layer "F.Cu")
	)
	(gr_line
		(start 86.748366 -6.034786)
		(end 86.766654 -6.073394)
		(stroke
			(width 0.0635)
			(type default)
		)
		(layer "F.Cu")
	)
	(gr_arc
		(start 86.761574 -8.354314)
		(mid 86.697931 -8.427782)
		(end 86.704678 -8.524748)
		(stroke
			(width 0.0635)
			(type default)
		)
		(layer "F.Cu")
	)
	(gr_line
		(start 86.761574 -8.354314)
		(end 86.761828 -8.354314)
		(stroke
			(width 0.0635)
			(type default)
		)
		(layer "F.Cu")
	)
	(gr_line
		(start 86.779862 12.133072)
		(end 86.779862 10.971784)
		(stroke
			(width 0.0635)
			(type default)
		)
		(layer "F.Cu")
	)
	(gr_line
		(start 86.860888 -8.305038)
		(end 86.875112 -8.297926)
		(stroke
			(width 0.0635)
			(type default)
		)
		(layer "F.Cu")
	)
	(gr_line
		(start 86.91118 -7.089394)
		(end 86.923372 -7.115302)
		(stroke
			(width 0.0635)
			(type default)
		)
		(layer "F.Cu")
	)
	(gr_line
		(start 86.954614 -9.025128)
		(end 87.079582 -9.250426)
		(stroke
			(width 0.0635)
			(type default)
		)
		(layer "F.Cu")
	)
	(gr_line
		(start 87.186516 -6.958838)
		(end 87.20074 -6.988556)
		(stroke
			(width 0.0635)
			(type default)
		)
		(layer "F.Cu")
	)
	(gr_line
		(start 87.215726 -7.020306)
		(end 87.228172 -7.046722)
		(stroke
			(width 0.0635)
			(type default)
		)
		(layer "F.Cu")
	)
	(gr_line
		(start 87.585042 -4.074922)
		(end 87.613236 -4.080002)
		(stroke
			(width 0.0635)
			(type default)
		)
		(layer "F.Cu")
	)
	(gr_line
		(start 87.613236 -4.080002)
		(end 87.636604 -4.096258)
		(stroke
			(width 0.0635)
			(type default)
		)
		(layer "F.Cu")
	)
	(gr_line
		(start 87.668354 7.702042)
		(end 87.737442 7.702042)
		(stroke
			(width 0.0635)
			(type default)
		)
		(layer "F.Cu")
	)
	(gr_arc
		(start 87.737442 7.702042)
		(mid 87.94881 7.78962)
		(end 88.0364 8.001)
		(stroke
			(width 0.0635)
			(type default)
		)
		(layer "F.Cu")
	)
	(gr_arc
		(start 88.3412 8.001)
		(mid 88.428763 7.789605)
		(end 88.640158 7.702042)
		(stroke
			(width 0.0635)
			(type default)
		)
		(layer "F.Cu")
	)
	(gr_arc
		(start 88.379808 10.980674)
		(mid 88.411893 10.819194)
		(end 88.503252 10.682224)
		(stroke
			(width 0.0635)
			(type default)
		)
		(layer "F.Cu")
	)
	(gr_line
		(start 88.379808 12.133072)
		(end 88.379808 10.980674)
		(stroke
			(width 0.0635)
			(type default)
		)
		(layer "F.Cu")
	)
	(gr_line
		(start 88.503252 10.682224)
		(end 88.503506 10.68197)
		(stroke
			(width 0.0635)
			(type default)
		)
		(layer "F.Cu")
	)
	(gr_arc
		(start 88.627458 10.383266)
		(mid 88.595145 10.544922)
		(end 88.503506 10.68197)
		(stroke
			(width 0.0635)
			(type default)
		)
		(layer "F.Cu")
	)
	(gr_line
		(start 88.640158 7.702042)
		(end 88.684354 7.702042)
		(stroke
			(width 0.0635)
			(type default)
		)
		(layer "F.Cu")
	)
	(gr_arc
		(start 89.05621 10.67308)
		(mid 88.964483 10.5358)
		(end 88.932258 10.373868)
		(stroke
			(width 0.0635)
			(type default)
		)
		(layer "F.Cu")
	)
	(gr_arc
		(start 89.05621 10.67308)
		(mid 89.147743 10.810137)
		(end 89.179908 10.971784)
		(stroke
			(width 0.0635)
			(type default)
		)
		(layer "F.Cu")
	)
	(gr_line
		(start 89.179908 12.133072)
		(end 89.179908 10.971784)
		(stroke
			(width 0.0635)
			(type default)
		)
		(layer "F.Cu")
	)
	(gr_line
		(start 90.079322 -7.250176)
		(end 90.1827 -7.48157)
		(stroke
			(width 0.0635)
			(type default)
		)
		(layer "F.Cu")
	)
	(gr_line
		(start 90.1827 -7.48157)
		(end 90.454734 -8.02513)
		(stroke
			(width 0.0635)
			(type default)
		)
		(layer "F.Cu")
	)
	(gr_line
		(start 90.259154 7.702042)
		(end 90.328242 7.702042)
		(stroke
			(width 0.0635)
			(type default)
		)
		(layer "F.Cu")
	)
	(gr_arc
		(start 90.328242 7.702042)
		(mid 90.53961 7.78962)
		(end 90.6272 8.001)
		(stroke
			(width 0.0635)
			(type default)
		)
		(layer "F.Cu")
	)
	(gr_arc
		(start 90.454734 -8.02513)
		(mid 90.52822 -8.088749)
		(end 90.625168 -8.081772)
		(stroke
			(width 0.0635)
			(type default)
		)
		(layer "F.Cu")
	)
	(gr_line
		(start 90.625168 -8.081772)
		(end 90.625422 -8.081772)
		(stroke
			(width 0.0635)
			(type default)
		)
		(layer "F.Cu")
	)
	(gr_line
		(start 90.625422 -8.081772)
		(end 90.626946 -8.08101)
		(stroke
			(width 0.0635)
			(type default)
		)
		(layer "F.Cu")
	)
	(gr_arc
		(start 90.6272 8.2296)
		(mid 90.63153 8.289626)
		(end 90.628724 8.349742)
		(stroke
			(width 0.0635)
			(type default)
		)
		(layer "F.Cu")
	)
	(gr_line
		(start 90.694764 -3.282188)
		(end 90.722958 -3.287268)
		(stroke
			(width 0.0635)
			(type default)
		)
		(layer "F.Cu")
	)
	(gr_line
		(start 90.70467 -8.525002)
		(end 90.892376 -8.90016)
		(stroke
			(width 0.0635)
			(type default)
		)
		(layer "F.Cu")
	)
	(gr_line
		(start 90.722958 -3.287268)
		(end 90.746326 -3.303524)
		(stroke
			(width 0.0635)
			(type default)
		)
		(layer "F.Cu")
	)
	(gr_arc
		(start 90.761312 -8.354568)
		(mid 90.697693 -8.428053)
		(end 90.70467 -8.525002)
		(stroke
			(width 0.0635)
			(type default)
		)
		(layer "F.Cu")
	)
	(gr_line
		(start 90.761312 -8.354568)
		(end 90.761566 -8.354568)
		(stroke
			(width 0.0635)
			(type default)
		)
		(layer "F.Cu")
	)
	(gr_line
		(start 90.763852 -8.353298)
		(end 90.764868 -8.35279)
		(stroke
			(width 0.0635)
			(type default)
		)
		(layer "F.Cu")
	)
	(gr_line
		(start 90.764868 -8.35279)
		(end 90.769948 -8.349996)
		(stroke
			(width 0.0635)
			(type default)
		)
		(layer "F.Cu")
	)
	(gr_arc
		(start 90.779854 10.980674)
		(mid 90.811939 10.819194)
		(end 90.903298 10.682224)
		(stroke
			(width 0.0635)
			(type default)
		)
		(layer "F.Cu")
	)
	(gr_line
		(start 90.779854 12.133072)
		(end 90.779854 10.980674)
		(stroke
			(width 0.0635)
			(type default)
		)
		(layer "F.Cu")
	)
	(gr_line
		(start 90.869516 -6.359906)
		(end 90.883486 -6.369558)
		(stroke
			(width 0.0635)
			(type default)
		)
		(layer "F.Cu")
	)
	(gr_line
		(start 90.883486 -6.369558)
		(end 90.89263 -6.38302)
		(stroke
			(width 0.0635)
			(type default)
		)
		(layer "F.Cu")
	)
	(gr_line
		(start 90.892376 -8.90016)
		(end 91.080082 -9.250426)
		(stroke
			(width 0.0635)
			(type default)
		)
		(layer "F.Cu")
	)
	(gr_line
		(start 90.903298 10.682224)
		(end 90.903552 10.68197)
		(stroke
			(width 0.0635)
			(type default)
		)
		(layer "F.Cu")
	)
	(gr_arc
		(start 90.932 8.001)
		(mid 91.019563 7.789605)
		(end 91.230958 7.702042)
		(stroke
			(width 0.0635)
			(type default)
		)
		(layer "F.Cu")
	)
	(gr_arc
		(start 91.027504 10.383266)
		(mid 90.995194 10.544925)
		(end 90.903552 10.68197)
		(stroke
			(width 0.0635)
			(type default)
		)
		(layer "F.Cu")
	)
	(gr_line
		(start 91.230958 7.702042)
		(end 91.275154 7.702042)
		(stroke
			(width 0.0635)
			(type default)
		)
		(layer "F.Cu")
	)
	(gr_arc
		(start 91.456256 10.67308)
		(mid 91.364529 10.5358)
		(end 91.332304 10.373868)
		(stroke
			(width 0.0635)
			(type default)
		)
		(layer "F.Cu")
	)
	(gr_arc
		(start 91.456256 10.67308)
		(mid 91.547801 10.810134)
		(end 91.579954 10.971784)
		(stroke
			(width 0.0635)
			(type default)
		)
		(layer "F.Cu")
	)
	(gr_line
		(start 91.579954 12.133072)
		(end 91.579954 10.971784)
		(stroke
			(width 0.0635)
			(type default)
		)
		(layer "F.Cu")
	)
	(gr_line
		(start 92.278962 -2.283968)
		(end 92.307156 -2.289048)
		(stroke
			(width 0.0635)
			(type default)
		)
		(layer "F.Cu")
	)
	(gr_line
		(start 92.307156 -2.289048)
		(end 92.330524 -2.305304)
		(stroke
			(width 0.0635)
			(type default)
		)
		(layer "F.Cu")
	)
	(gr_line
		(start 92.849954 7.702042)
		(end 92.919042 7.702042)
		(stroke
			(width 0.0635)
			(type default)
		)
		(layer "F.Cu")
	)
	(gr_arc
		(start 92.919042 7.702042)
		(mid 93.13041 7.78962)
		(end 93.218 8.001)
		(stroke
			(width 0.0635)
			(type default)
		)
		(layer "F.Cu")
	)
	(gr_arc
		(start 93.1799 10.980674)
		(mid 93.211985 10.819194)
		(end 93.303344 10.682224)
		(stroke
			(width 0.0635)
			(type default)
		)
		(layer "F.Cu")
	)
	(gr_line
		(start 93.1799 12.133072)
		(end 93.1799 10.980674)
		(stroke
			(width 0.0635)
			(type default)
		)
		(layer "F.Cu")
	)
	(gr_arc
		(start 93.224858 8.491474)
		(mid 93.219674 8.459402)
		(end 93.218 8.426958)
		(stroke
			(width 0.0635)
			(type default)
		)
		(layer "F.Cu")
	)
	(gr_line
		(start 93.303344 10.682224)
		(end 93.303598 10.68197)
		(stroke
			(width 0.0635)
			(type default)
		)
		(layer "F.Cu")
	)
	(gr_line
		(start 93.395038 -1.232916)
		(end 93.423232 -1.237996)
		(stroke
			(width 0.0635)
			(type default)
		)
		(layer "F.Cu")
	)
	(gr_line
		(start 93.423232 -1.237996)
		(end 93.4466 -1.254252)
		(stroke
			(width 0.0635)
			(type default)
		)
		(layer "F.Cu")
	)
	(gr_arc
		(start 93.42755 10.383266)
		(mid 93.395243 10.544927)
		(end 93.303598 10.68197)
		(stroke
			(width 0.0635)
			(type default)
		)
		(layer "F.Cu")
	)
	(gr_line
		(start 93.42755 10.383266)
		(end 93.42755 10.373868)
		(stroke
			(width 0.0635)
			(type default)
		)
		(layer "F.Cu")
	)
	(gr_arc
		(start 93.5228 8.001)
		(mid 93.610363 7.789605)
		(end 93.821758 7.702042)
		(stroke
			(width 0.0635)
			(type default)
		)
		(layer "F.Cu")
	)
	(gr_line
		(start 93.821758 7.702042)
		(end 93.865954 7.702042)
		(stroke
			(width 0.0635)
			(type default)
		)
		(layer "F.Cu")
	)
	(gr_arc
		(start 93.856302 10.67308)
		(mid 93.764575 10.5358)
		(end 93.73235 10.373868)
		(stroke
			(width 0.0635)
			(type default)
		)
		(layer "F.Cu")
	)
	(gr_arc
		(start 93.856302 10.67308)
		(mid 93.947837 10.810137)
		(end 93.98 10.971784)
		(stroke
			(width 0.0635)
			(type default)
		)
		(layer "F.Cu")
	)
	(gr_line
		(start 93.91142 -0.113538)
		(end 93.939614 -0.118618)
		(stroke
			(width 0.0635)
			(type default)
		)
		(layer "F.Cu")
	)
	(gr_line
		(start 93.939614 -0.118618)
		(end 93.962982 -0.134874)
		(stroke
			(width 0.0635)
			(type default)
		)
		(layer "F.Cu")
	)
	(gr_line
		(start 93.98 12.133072)
		(end 93.98 10.971784)
		(stroke
			(width 0.0635)
			(type default)
		)
		(layer "F.Cu")
	)
	(gr_line
		(start 94.079822 -7.250176)
		(end 94.26702 -7.649972)
		(stroke
			(width 0.0635)
			(type default)
		)
		(layer "F.Cu")
	)
	(gr_line
		(start 94.260416 1.128268)
		(end 94.28861 1.123188)
		(stroke
			(width 0.0635)
			(type default)
		)
		(layer "F.Cu")
	)
	(gr_line
		(start 94.26702 -7.649972)
		(end 94.454218 -8.024876)
		(stroke
			(width 0.0635)
			(type default)
		)
		(layer "F.Cu")
	)
	(gr_line
		(start 94.28861 1.123188)
		(end 94.311978 1.106932)
		(stroke
			(width 0.0635)
			(type default)
		)
		(layer "F.Cu")
	)
	(gr_arc
		(start 94.454218 -8.024876)
		(mid 94.527624 -8.088717)
		(end 94.624652 -8.081772)
		(stroke
			(width 0.0635)
			(type default)
		)
		(layer "F.Cu")
	)
	(gr_line
		(start 94.624652 -8.081772)
		(end 94.624906 -8.081772)
		(stroke
			(width 0.0635)
			(type default)
		)
		(layer "F.Cu")
	)
	(gr_line
		(start 94.624906 -8.081772)
		(end 94.62897 -8.07974)
		(stroke
			(width 0.0635)
			(type default)
		)
		(layer "F.Cu")
	)
	(gr_line
		(start 94.704408 -8.524748)
		(end 94.8944 -8.904986)
		(stroke
			(width 0.0635)
			(type default)
		)
		(layer "F.Cu")
	)
	(gr_arc
		(start 94.761304 -8.354314)
		(mid 94.697541 -8.427767)
		(end 94.704408 -8.524748)
		(stroke
			(width 0.0635)
			(type default)
		)
		(layer "F.Cu")
	)
	(gr_line
		(start 94.761304 -8.354314)
		(end 94.761558 -8.354314)
		(stroke
			(width 0.0635)
			(type default)
		)
		(layer "F.Cu")
	)
	(gr_line
		(start 94.861126 -8.304784)
		(end 94.874842 -8.297926)
		(stroke
			(width 0.0635)
			(type default)
		)
		(layer "F.Cu")
	)
	(gr_line
		(start 94.874842 -8.297926)
		(end 94.875096 -8.297672)
		(stroke
			(width 0.0635)
			(type default)
		)
		(layer "F.Cu")
	)
	(gr_line
		(start 94.8944 -8.904986)
		(end 95.079312 -9.250426)
		(stroke
			(width 0.0635)
			(type default)
		)
		(layer "F.Cu")
	)
	(gr_arc
		(start 95.440754 7.702042)
		(mid 95.720311 7.902597)
		(end 95.827342 8.2296)
		(stroke
			(width 0.0635)
			(type default)
		)
		(layer "F.Cu")
	)
	(gr_arc
		(start 95.579946 10.980674)
		(mid 95.612031 10.819194)
		(end 95.70339 10.682224)
		(stroke
			(width 0.0635)
			(type default)
		)
		(layer "F.Cu")
	)
	(gr_line
		(start 95.579946 12.133072)
		(end 95.579946 10.980674)
		(stroke
			(width 0.0635)
			(type default)
		)
		(layer "F.Cu")
	)
	(gr_line
		(start 95.70339 10.682224)
		(end 95.703644 10.68197)
		(stroke
			(width 0.0635)
			(type default)
		)
		(layer "F.Cu")
	)
	(gr_line
		(start 95.827342 10.373868)
		(end 95.827596 10.373868)
		(stroke
			(width 0.0635)
			(type default)
		)
		(layer "F.Cu")
	)
	(gr_arc
		(start 95.827596 10.383266)
		(mid 95.795285 10.544924)
		(end 95.703644 10.68197)
		(stroke
			(width 0.0635)
			(type default)
		)
		(layer "F.Cu")
	)
	(gr_line
		(start 95.827596 10.383266)
		(end 95.827596 10.373868)
		(stroke
			(width 0.0635)
			(type default)
		)
		(layer "F.Cu")
	)
	(gr_arc
		(start 96.132142 8.2296)
		(mid 96.21979 7.919878)
		(end 96.456754 7.702042)
		(stroke
			(width 0.0635)
			(type default)
		)
		(layer "F.Cu")
	)
	(gr_line
		(start 96.132142 10.373868)
		(end 96.132142 10.069068)
		(stroke
			(width 0.0635)
			(type default)
		)
		(layer "F.Cu")
	)
	(gr_arc
		(start 96.256094 10.67308)
		(mid 96.164367 10.5358)
		(end 96.132142 10.373868)
		(stroke
			(width 0.0635)
			(type default)
		)
		(layer "F.Cu")
	)
	(gr_arc
		(start 96.256094 10.67308)
		(mid 96.347631 10.810136)
		(end 96.379792 10.971784)
		(stroke
			(width 0.0635)
			(type default)
		)
		(layer "F.Cu")
	)
	(gr_line
		(start 96.379792 12.133072)
		(end 96.379792 10.971784)
		(stroke
			(width 0.0635)
			(type default)
		)
		(layer "F.Cu")
	)
	(gr_line
		(start 97.388172 -6.219444)
		(end 97.413826 -6.237224)
		(stroke
			(width 0.0635)
			(type default)
		)
		(layer "F.Cu")
	)
	(gr_line
		(start 97.413826 -6.237224)
		(end 97.44456 -6.242558)
		(stroke
			(width 0.0635)
			(type default)
		)
		(layer "F.Cu")
	)
	(gr_line
		(start 98.080322 -7.250176)
		(end 98.26752 -7.649972)
		(stroke
			(width 0.0635)
			(type default)
		)
		(layer "F.Cu")
	)
	(gr_line
		(start 98.26752 -7.649972)
		(end 98.454718 -8.024876)
		(stroke
			(width 0.0635)
			(type default)
		)
		(layer "F.Cu")
	)
	(gr_arc
		(start 98.454718 -8.024876)
		(mid 98.528124 -8.088717)
		(end 98.625152 -8.081772)
		(stroke
			(width 0.0635)
			(type default)
		)
		(layer "F.Cu")
	)
	(gr_line
		(start 98.466402 -5.141214)
		(end 98.48977 -5.15747)
		(stroke
			(width 0.0635)
			(type default)
		)
		(layer "F.Cu")
	)
	(gr_line
		(start 98.48977 -5.15747)
		(end 98.518218 -5.16255)
		(stroke
			(width 0.0635)
			(type default)
		)
		(layer "F.Cu")
	)
	(gr_line
		(start 98.532188 -6.120638)
		(end 98.576384 -6.128258)
		(stroke
			(width 0.0635)
			(type default)
		)
		(layer "F.Cu")
	)
	(gr_line
		(start 98.576384 -6.128258)
		(end 98.61042 -6.157214)
		(stroke
			(width 0.0635)
			(type default)
		)
		(layer "F.Cu")
	)
	(gr_line
		(start 98.625152 -8.081772)
		(end 98.625406 -8.081772)
		(stroke
			(width 0.0635)
			(type default)
		)
		(layer "F.Cu")
	)
	(gr_line
		(start 98.625406 -8.081772)
		(end 98.62947 -8.07974)
		(stroke
			(width 0.0635)
			(type default)
		)
		(layer "F.Cu")
	)
	(gr_line
		(start 98.704908 -8.524748)
		(end 98.954844 -9.025128)
		(stroke
			(width 0.0635)
			(type default)
		)
		(layer "F.Cu")
	)
	(gr_arc
		(start 98.761804 -8.354314)
		(mid 98.698041 -8.427767)
		(end 98.704908 -8.524748)
		(stroke
			(width 0.0635)
			(type default)
		)
		(layer "F.Cu")
	)
	(gr_line
		(start 98.761804 -8.354314)
		(end 98.762058 -8.354314)
		(stroke
			(width 0.0635)
			(type default)
		)
		(layer "F.Cu")
	)
	(gr_line
		(start 98.861626 -8.304784)
		(end 98.875342 -8.297926)
		(stroke
			(width 0.0635)
			(type default)
		)
		(layer "F.Cu")
	)
	(gr_line
		(start 98.90633 -3.968496)
		(end 98.929698 -3.984752)
		(stroke
			(width 0.0635)
			(type default)
		)
		(layer "F.Cu")
	)
	(gr_line
		(start 98.929698 -3.984752)
		(end 98.957892 -3.989832)
		(stroke
			(width 0.0635)
			(type default)
		)
		(layer "F.Cu")
	)
	(gr_line
		(start 98.954844 -9.025128)
		(end 99.079812 -9.250426)
		(stroke
			(width 0.0635)
			(type default)
		)
		(layer "F.Cu")
	)
	(gr_line
		(start 98.968306 -6.462014)
		(end 98.9711 -6.4643)
		(stroke
			(width 0.0635)
			(type default)
		)
		(layer "F.Cu")
	)
	(gr_line
		(start 98.9711 -6.4643)
		(end 98.973386 -6.467602)
		(stroke
			(width 0.0635)
			(type default)
		)
		(layer "F.Cu")
	)
	(gr_line
		(start 99.240594 -6.871208)
		(end 99.26955 -6.914642)
		(stroke
			(width 0.0635)
			(type default)
		)
		(layer "F.Cu")
	)
	(gr_line
		(start 99.374198 -2.809748)
		(end 99.397566 -2.826004)
		(stroke
			(width 0.0635)
			(type default)
		)
		(layer "F.Cu")
	)
	(gr_line
		(start 99.397566 -2.826004)
		(end 99.42576 -2.831084)
		(stroke
			(width 0.0635)
			(type default)
		)
		(layer "F.Cu")
	)
	(gr_line
		(start 102.036372 -5.473954)
		(end 102.065074 -5.479034)
		(stroke
			(width 0.0635)
			(type default)
		)
		(layer "F.Cu")
	)
	(gr_line
		(start 102.065074 -5.479034)
		(end 102.088442 -5.495544)
		(stroke
			(width 0.0635)
			(type default)
		)
		(layer "F.Cu")
	)
	(gr_line
		(start 102.079552 -7.250176)
		(end 102.22611 -7.568184)
		(stroke
			(width 0.0635)
			(type default)
		)
		(layer "F.Cu")
	)
	(gr_line
		(start 102.22611 -7.568184)
		(end 102.454964 -8.02513)
		(stroke
			(width 0.0635)
			(type default)
		)
		(layer "F.Cu")
	)
	(gr_arc
		(start 102.454964 -8.02513)
		(mid 102.528452 -8.088731)
		(end 102.625398 -8.081772)
		(stroke
			(width 0.0635)
			(type default)
		)
		(layer "F.Cu")
	)
	(gr_line
		(start 102.6795 -5.90931)
		(end 102.6922 -5.9182)
		(stroke
			(width 0.0635)
			(type default)
		)
		(layer "F.Cu")
	)
	(gr_line
		(start 102.6922 -5.9182)
		(end 102.70109 -5.9309)
		(stroke
			(width 0.0635)
			(type default)
		)
		(layer "F.Cu")
	)
	(gr_line
		(start 102.7049 -8.525002)
		(end 102.892606 -8.90016)
		(stroke
			(width 0.0635)
			(type default)
		)
		(layer "F.Cu")
	)
	(gr_arc
		(start 102.761542 -8.354568)
		(mid 102.697923 -8.428054)
		(end 102.7049 -8.525002)
		(stroke
			(width 0.0635)
			(type default)
		)
		(layer "F.Cu")
	)
	(gr_line
		(start 102.860856 -8.305038)
		(end 102.875334 -8.297672)
		(stroke
			(width 0.0635)
			(type default)
		)
		(layer "F.Cu")
	)
	(gr_line
		(start 102.875334 -8.297672)
		(end 102.875588 -8.297418)
		(stroke
			(width 0.0635)
			(type default)
		)
		(layer "F.Cu")
	)
	(gr_line
		(start 102.875334 -8.297418)
		(end 102.875588 -8.297418)
		(stroke
			(width 0.0635)
			(type default)
		)
		(layer "F.Cu")
	)
	(gr_line
		(start 102.892606 -8.90016)
		(end 103.080312 -9.250426)
		(stroke
			(width 0.0635)
			(type default)
		)
		(layer "F.Cu")
	)
	(gr_line
		(start 103.058468 -6.441694)
		(end 103.07447 -6.4643)
		(stroke
			(width 0.0635)
			(type default)
		)
		(layer "F.Cu")
	)
	(gr_line
		(start 103.07447 -6.4643)
		(end 103.07955 -6.492494)
		(stroke
			(width 0.0635)
			(type default)
		)
		(layer "F.Cu")
	)
	(gr_line
		(start 105.539032 -4.840224)
		(end 105.567226 -4.845304)
		(stroke
			(width 0.0635)
			(type default)
		)
		(layer "F.Cu")
	)
	(gr_line
		(start 105.567226 -4.845304)
		(end 105.590594 -4.86156)
		(stroke
			(width 0.0635)
			(type default)
		)
		(layer "F.Cu")
	)
	(gr_line
		(start 106.080052 -7.250176)
		(end 106.26725 -7.649972)
		(stroke
			(width 0.0635)
			(type default)
		)
		(layer "F.Cu")
	)
	(gr_line
		(start 106.26725 -7.649972)
		(end 106.454448 -8.024876)
		(stroke
			(width 0.0635)
			(type default)
		)
		(layer "F.Cu")
	)
	(gr_arc
		(start 106.454448 -8.024876)
		(mid 106.527852 -8.088698)
		(end 106.624882 -8.081772)
		(stroke
			(width 0.0635)
			(type default)
		)
		(layer "F.Cu")
	)
	(gr_line
		(start 106.624882 -8.081772)
		(end 106.625136 -8.081772)
		(stroke
			(width 0.0635)
			(type default)
		)
		(layer "F.Cu")
	)
	(gr_line
		(start 106.625136 -8.081772)
		(end 106.6292 -8.07974)
		(stroke
			(width 0.0635)
			(type default)
		)
		(layer "F.Cu")
	)
	(gr_line
		(start 106.70159 -5.639562)
		(end 106.71429 -5.648452)
		(stroke
			(width 0.0635)
			(type default)
		)
		(layer "F.Cu")
	)
	(gr_line
		(start 106.704638 -8.524748)
		(end 106.954574 -9.025128)
		(stroke
			(width 0.0635)
			(type default)
		)
		(layer "F.Cu")
	)
	(gr_line
		(start 106.71429 -5.648452)
		(end 106.72318 -5.661152)
		(stroke
			(width 0.0635)
			(type default)
		)
		(layer "F.Cu")
	)
	(gr_arc
		(start 106.761534 -8.354314)
		(mid 106.697771 -8.427767)
		(end 106.704638 -8.524748)
		(stroke
			(width 0.0635)
			(type default)
		)
		(layer "F.Cu")
	)
	(gr_line
		(start 106.761534 -8.354314)
		(end 106.761788 -8.354314)
		(stroke
			(width 0.0635)
			(type default)
		)
		(layer "F.Cu")
	)
	(gr_line
		(start 106.861356 -8.304784)
		(end 106.875072 -8.297926)
		(stroke
			(width 0.0635)
			(type default)
		)
		(layer "F.Cu")
	)
	(gr_line
		(start 106.954574 -9.025128)
		(end 107.079542 -9.250426)
		(stroke
			(width 0.0635)
			(type default)
		)
		(layer "F.Cu")
	)
	(gr_line
		(start 107.157774 -6.281674)
		(end 107.17403 -6.305042)
		(stroke
			(width 0.0635)
			(type default)
		)
		(layer "F.Cu")
	)
	(gr_line
		(start 107.17403 -6.305042)
		(end 107.17911 -6.333236)
		(stroke
			(width 0.0635)
			(type default)
		)
		(layer "F.Cu")
	)
	(gr_line
		(start 108.08843 -4.905248)
		(end 108.179616 -5.13207)
		(stroke
			(width 0.0635)
			(type default)
		)
		(layer "F.Cu")
	)
	(gr_line
		(start 108.179616 -5.13207)
		(end 108.530136 -5.281422)
		(stroke
			(width 0.0635)
			(type default)
		)
		(layer "F.Cu")
	)
	(gr_line
		(start 108.243878 -4.637532)
		(end 108.84281 -4.893056)
		(stroke
			(width 0.0635)
			(type default)
		)
		(layer "F.Cu")
	)
	(gr_line
		(start 108.530136 -5.281422)
		(end 108.756704 -5.190236)
		(stroke
			(width 0.0635)
			(type default)
		)
		(layer "F.Cu")
	)
	(gr_line
		(start 109.111796 -5.34162)
		(end 109.202982 -5.568442)
		(stroke
			(width 0.0635)
			(type default)
		)
		(layer "F.Cu")
	)
	(gr_line
		(start 109.202982 -5.568442)
		(end 109.553502 -5.717794)
		(stroke
			(width 0.0635)
			(type default)
		)
		(layer "F.Cu")
	)
	(gr_arc
		(start 109.242606 7.742682)
		(mid 109.496033 7.847654)
		(end 109.601 8.101076)
		(stroke
			(width 0.0635)
			(type default)
		)
		(layer "F.Cu")
	)
	(gr_line
		(start 109.26572 -5.073142)
		(end 109.867446 -5.329936)
		(stroke
			(width 0.0635)
			(type default)
		)
		(layer "F.Cu")
	)
	(gr_line
		(start 109.553502 -5.717794)
		(end 109.780324 -5.626862)
		(stroke
			(width 0.0635)
			(type default)
		)
		(layer "F.Cu")
	)
	(gr_line
		(start 109.7153 8.868918)
		(end 109.72038 8.897366)
		(stroke
			(width 0.0635)
			(type default)
		)
		(layer "F.Cu")
	)
	(gr_line
		(start 109.72038 8.89762)
		(end 109.72038 8.897366)
		(stroke
			(width 0.0635)
			(type default)
		)
		(layer "F.Cu")
	)
	(gr_line
		(start 109.72038 8.89762)
		(end 109.737144 8.92175)
		(stroke
			(width 0.0635)
			(type default)
		)
		(layer "F.Cu")
	)
	(gr_arc
		(start 109.77499 11.082274)
		(mid 109.807075 10.920794)
		(end 109.898434 10.783824)
		(stroke
			(width 0.0635)
			(type default)
		)
		(layer "F.Cu")
	)
	(gr_line
		(start 109.77499 12.234672)
		(end 109.77499 11.082274)
		(stroke
			(width 0.0635)
			(type default)
		)
		(layer "F.Cu")
	)
	(gr_line
		(start 109.898434 10.783824)
		(end 109.898688 10.78357)
		(stroke
			(width 0.0635)
			(type default)
		)
		(layer "F.Cu")
	)
	(gr_arc
		(start 109.9058 8.095488)
		(mid 110.009139 7.846026)
		(end 110.258606 7.742682)
		(stroke
			(width 0.0635)
			(type default)
		)
		(layer "F.Cu")
	)
	(gr_arc
		(start 110.02264 10.484866)
		(mid 109.990332 10.646527)
		(end 109.898688 10.78357)
		(stroke
			(width 0.0635)
			(type default)
		)
		(layer "F.Cu")
	)
	(gr_line
		(start 110.079282 -7.250176)
		(end 110.316264 -7.74827)
		(stroke
			(width 0.0635)
			(type default)
		)
		(layer "F.Cu")
	)
	(gr_line
		(start 110.191296 9.038336)
		(end 110.207552 9.061704)
		(stroke
			(width 0.0635)
			(type default)
		)
		(layer "F.Cu")
	)
	(gr_line
		(start 110.207552 9.061704)
		(end 110.212632 9.090152)
		(stroke
			(width 0.0635)
			(type default)
		)
		(layer "F.Cu")
	)
	(gr_line
		(start 110.316264 -7.74827)
		(end 110.454694 -8.02513)
		(stroke
			(width 0.0635)
			(type default)
		)
		(layer "F.Cu")
	)
	(gr_line
		(start 110.371128 -5.5626)
		(end 110.378748 -5.567426)
		(stroke
			(width 0.0635)
			(type default)
		)
		(layer "F.Cu")
	)
	(gr_line
		(start 110.378748 -5.567426)
		(end 110.384844 -5.574284)
		(stroke
			(width 0.0635)
			(type default)
		)
		(layer "F.Cu")
	)
	(gr_arc
		(start 110.451392 10.77468)
		(mid 110.359653 10.637404)
		(end 110.32744 10.475468)
		(stroke
			(width 0.0635)
			(type default)
		)
		(layer "F.Cu")
	)
	(gr_arc
		(start 110.451392 10.77468)
		(mid 110.542964 10.911727)
		(end 110.57509 11.073384)
		(stroke
			(width 0.0635)
			(type default)
		)
		(layer "F.Cu")
	)
	(gr_arc
		(start 110.454694 -8.02513)
		(mid 110.52818 -8.088712)
		(end 110.625128 -8.081772)
		(stroke
			(width 0.0635)
			(type default)
		)
		(layer "F.Cu")
	)
	(gr_line
		(start 110.57509 12.234672)
		(end 110.57509 11.073384)
		(stroke
			(width 0.0635)
			(type default)
		)
		(layer "F.Cu")
	)
	(gr_line
		(start 110.70463 -8.525002)
		(end 110.933992 -8.983726)
		(stroke
			(width 0.0635)
			(type default)
		)
		(layer "F.Cu")
	)
	(gr_arc
		(start 110.761272 -8.354568)
		(mid 110.697653 -8.428054)
		(end 110.70463 -8.525002)
		(stroke
			(width 0.0635)
			(type default)
		)
		(layer "F.Cu")
	)
	(gr_line
		(start 110.849664 -6.747764)
		(end 110.850426 -6.749542)
		(stroke
			(width 0.0635)
			(type default)
		)
		(layer "F.Cu")
	)
	(gr_line
		(start 110.850426 -6.749542)
		(end 110.853982 -6.757924)
		(stroke
			(width 0.0635)
			(type default)
		)
		(layer "F.Cu")
	)
	(gr_line
		(start 110.853982 -6.757924)
		(end 110.852204 -6.762496)
		(stroke
			(width 0.0635)
			(type default)
		)
		(layer "F.Cu")
	)
	(gr_line
		(start 110.861094 -8.304784)
		(end 110.875064 -8.297672)
		(stroke
			(width 0.0635)
			(type default)
		)
		(layer "F.Cu")
	)
	(gr_line
		(start 110.933992 -8.983726)
		(end 111.080042 -9.250426)
		(stroke
			(width 0.0635)
			(type default)
		)
		(layer "F.Cu")
	)
	(gr_line
		(start 110.961424 -6.23189)
		(end 110.970314 -6.24205)
		(stroke
			(width 0.0635)
			(type default)
		)
		(layer "F.Cu")
	)
	(gr_line
		(start 110.970314 -6.24205)
		(end 110.975648 -6.25475)
		(stroke
			(width 0.0635)
			(type default)
		)
		(layer "F.Cu")
	)
	(gr_line
		(start 111.138716 -6.642354)
		(end 111.140748 -6.643116)
		(stroke
			(width 0.0635)
			(type default)
		)
		(layer "F.Cu")
	)
	(gr_line
		(start 111.140748 -6.643116)
		(end 111.142018 -6.650482)
		(stroke
			(width 0.0635)
			(type default)
		)
		(layer "F.Cu")
	)
	(gr_line
		(start 111.145066 -6.6675)
		(end 111.158528 -6.743192)
		(stroke
			(width 0.0635)
			(type default)
		)
		(layer "F.Cu")
	)
	(gr_line
		(start 111.833406 7.742682)
		(end 111.902494 7.742682)
		(stroke
			(width 0.0635)
			(type default)
		)
		(layer "F.Cu")
	)
	(gr_arc
		(start 111.902494 7.742682)
		(mid 112.113879 7.830245)
		(end 112.201452 8.04164)
		(stroke
			(width 0.0635)
			(type default)
		)
		(layer "F.Cu")
	)
	(gr_arc
		(start 112.175036 11.082274)
		(mid 112.207121 10.920794)
		(end 112.29848 10.783824)
		(stroke
			(width 0.0635)
			(type default)
		)
		(layer "F.Cu")
	)
	(gr_line
		(start 112.175036 12.234672)
		(end 112.175036 11.082274)
		(stroke
			(width 0.0635)
			(type default)
		)
		(layer "F.Cu")
	)
	(gr_line
		(start 112.29848 10.783824)
		(end 112.298734 10.78357)
		(stroke
			(width 0.0635)
			(type default)
		)
		(layer "F.Cu")
	)
	(gr_arc
		(start 112.422686 10.484866)
		(mid 112.390375 10.646524)
		(end 112.298734 10.78357)
		(stroke
			(width 0.0635)
			(type default)
		)
		(layer "F.Cu")
	)
	(gr_arc
		(start 112.506252 8.04164)
		(mid 112.593815 7.830245)
		(end 112.80521 7.742682)
		(stroke
			(width 0.0635)
			(type default)
		)
		(layer "F.Cu")
	)
	(gr_line
		(start 112.80521 7.742682)
		(end 112.849406 7.742682)
		(stroke
			(width 0.0635)
			(type default)
		)
		(layer "F.Cu")
	)
	(gr_arc
		(start 112.851438 10.77468)
		(mid 112.759711 10.6374)
		(end 112.727486 10.475468)
		(stroke
			(width 0.0635)
			(type default)
		)
		(layer "F.Cu")
	)
	(gr_arc
		(start 112.851438 10.77468)
		(mid 112.942965 10.911739)
		(end 112.975136 11.073384)
		(stroke
			(width 0.0635)
			(type default)
		)
		(layer "F.Cu")
	)
	(gr_line
		(start 112.975136 12.234672)
		(end 112.975136 11.073384)
		(stroke
			(width 0.0635)
			(type default)
		)
		(layer "F.Cu")
	)
	(gr_line
		(start 114.424206 7.742682)
		(end 114.493294 7.742682)
		(stroke
			(width 0.0635)
			(type default)
		)
		(layer "F.Cu")
	)
	(gr_arc
		(start 114.493294 7.742682)
		(mid 114.704689 7.830245)
		(end 114.792252 8.04164)
		(stroke
			(width 0.0635)
			(type default)
		)
		(layer "F.Cu")
	)
	(gr_arc
		(start 114.575082 11.082274)
		(mid 114.607153 10.920788)
		(end 114.698526 10.783824)
		(stroke
			(width 0.0635)
			(type default)
		)
		(layer "F.Cu")
	)
	(gr_line
		(start 114.575082 12.234672)
		(end 114.575082 11.082274)
		(stroke
			(width 0.0635)
			(type default)
		)
		(layer "F.Cu")
	)
	(gr_line
		(start 114.698526 10.783824)
		(end 114.69878 10.78357)
		(stroke
			(width 0.0635)
			(type default)
		)
		(layer "F.Cu")
	)
	(gr_line
		(start 114.822478 9.893554)
		(end 114.822478 9.786874)
		(stroke
			(width 0.0635)
			(type default)
		)
		(layer "F.Cu")
	)
	(gr_line
		(start 114.822478 10.484866)
		(end 114.822732 10.484866)
		(stroke
			(width 0.0635)
			(type default)
		)
		(layer "F.Cu")
	)
	(gr_arc
		(start 114.822732 10.484866)
		(mid 114.790476 10.646556)
		(end 114.69878 10.78357)
		(stroke
			(width 0.0635)
			(type default)
		)
		(layer "F.Cu")
	)
	(gr_arc
		(start 115.097052 8.04164)
		(mid 115.184601 7.830222)
		(end 115.39601 7.742682)
		(stroke
			(width 0.0635)
			(type default)
		)
		(layer "F.Cu")
	)
	(gr_line
		(start 115.097052 9.588754)
		(end 115.097052 9.482074)
		(stroke
			(width 0.0635)
			(type default)
		)
		(layer "F.Cu")
	)
	(gr_line
		(start 115.127278 10.475468)
		(end 115.127278 10.180066)
		(stroke
			(width 0.0635)
			(type default)
		)
		(layer "F.Cu")
	)
	(gr_arc
		(start 115.25123 10.77468)
		(mid 115.159483 10.637406)
		(end 115.127278 10.475468)
		(stroke
			(width 0.0635)
			(type default)
		)
		(layer "F.Cu")
	)
	(gr_arc
		(start 115.25123 10.77468)
		(mid 115.342802 10.911727)
		(end 115.374928 11.073384)
		(stroke
			(width 0.0635)
			(type default)
		)
		(layer "F.Cu")
	)
	(gr_line
		(start 115.374928 11.073384)
		(end 115.375182 12.234672)
		(stroke
			(width 0.0635)
			(type default)
		)
		(layer "F.Cu")
	)
	(gr_line
		(start 115.39601 7.742682)
		(end 115.440206 7.742682)
		(stroke
			(width 0.0635)
			(type default)
		)
		(layer "F.Cu")
	)
	(gr_line
		(start 115.798346 -33.446974)
		(end 115.831874 -33.446974)
		(stroke
			(width 0.05715)
			(type default)
		)
		(layer "F.Cu")
	)
	(gr_line
		(start 115.831874 -33.446974)
		(end 116.027962 -33.643062)
		(stroke
			(width 0.05715)
			(type default)
		)
		(layer "F.Cu")
	)
	(gr_line
		(start 116.444522 -33.643062)
		(end 116.661692 -33.425892)
		(stroke
			(width 0.05715)
			(type default)
		)
		(layer "F.Cu")
	)
	(gr_arc
		(start 116.975128 11.082274)
		(mid 117.007213 10.920794)
		(end 117.098572 10.783824)
		(stroke
			(width 0.0635)
			(type default)
		)
		(layer "F.Cu")
	)
	(gr_line
		(start 116.975128 12.234672)
		(end 116.975128 11.082274)
		(stroke
			(width 0.0635)
			(type default)
		)
		(layer "F.Cu")
	)
	(gr_line
		(start 117.015006 7.742682)
		(end 117.084094 7.742682)
		(stroke
			(width 0.0635)
			(type default)
		)
		(layer "F.Cu")
	)
	(gr_arc
		(start 117.084094 7.742682)
		(mid 117.295479 7.830245)
		(end 117.383052 8.04164)
		(stroke
			(width 0.0635)
			(type default)
		)
		(layer "F.Cu")
	)
	(gr_line
		(start 117.098572 10.783824)
		(end 117.098826 10.78357)
		(stroke
			(width 0.0635)
			(type default)
		)
		(layer "F.Cu")
	)
	(gr_line
		(start 117.222524 9.576054)
		(end 117.222778 9.577578)
		(stroke
			(width 0.0635)
			(type default)
		)
		(layer "F.Cu")
	)
	(gr_arc
		(start 117.222778 10.484866)
		(mid 117.190466 10.646523)
		(end 117.098826 10.78357)
		(stroke
			(width 0.0635)
			(type default)
		)
		(layer "F.Cu")
	)
	(gr_line
		(start 117.222778 10.484866)
		(end 117.222778 9.577578)
		(stroke
			(width 0.0635)
			(type default)
		)
		(layer "F.Cu")
	)
	(gr_line
		(start 117.527324 9.576562)
		(end 117.527578 9.575292)
		(stroke
			(width 0.0635)
			(type default)
		)
		(layer "F.Cu")
	)
	(gr_line
		(start 117.527324 10.475468)
		(end 117.527324 9.576562)
		(stroke
			(width 0.0635)
			(type default)
		)
		(layer "F.Cu")
	)
	(gr_arc
		(start 117.651276 10.77468)
		(mid 117.559549 10.6374)
		(end 117.527324 10.475468)
		(stroke
			(width 0.0635)
			(type default)
		)
		(layer "F.Cu")
	)
	(gr_arc
		(start 117.651276 10.77468)
		(mid 117.742816 10.911735)
		(end 117.774974 11.073384)
		(stroke
			(width 0.0635)
			(type default)
		)
		(layer "F.Cu")
	)
	(gr_arc
		(start 117.687852 8.04164)
		(mid 117.775415 7.830245)
		(end 117.98681 7.742682)
		(stroke
			(width 0.0635)
			(type default)
		)
		(layer "F.Cu")
	)
	(gr_line
		(start 117.774974 12.234672)
		(end 117.774974 11.073384)
		(stroke
			(width 0.0635)
			(type default)
		)
		(layer "F.Cu")
	)
	(gr_line
		(start 117.98681 7.742682)
		(end 118.031006 7.742682)
		(stroke
			(width 0.0635)
			(type default)
		)
		(layer "F.Cu")
	)
	(gr_line
		(start 119.2403 -33.4264)
		(end 119.61622 -33.05048)
		(stroke
			(width 0.05715)
			(type default)
		)
		(layer "F.Cu")
	)
	(gr_line
		(start 119.2403 -32.3596)
		(end 119.3419 -32.3596)
		(stroke
			(width 0.05715)
			(type default)
		)
		(layer "F.Cu")
	)
	(gr_line
		(start 119.3419 -32.3596)
		(end 119.61622 -32.63392)
		(stroke
			(width 0.05715)
			(type default)
		)
		(layer "F.Cu")
	)
	(gr_line
		(start 119.37492 11.082274)
		(end 119.375174 12.234672)
		(stroke
			(width 0.0635)
			(type default)
		)
		(layer "F.Cu")
	)
	(gr_arc
		(start 119.37492 11.082274)
		(mid 119.406988 10.920785)
		(end 119.498364 10.783824)
		(stroke
			(width 0.0635)
			(type default)
		)
		(layer "F.Cu")
	)
	(gr_line
		(start 119.498364 10.783824)
		(end 119.498618 10.78357)
		(stroke
			(width 0.0635)
			(type default)
		)
		(layer "F.Cu")
	)
	(gr_line
		(start 119.605806 7.742682)
		(end 119.674894 7.742682)
		(stroke
			(width 0.0635)
			(type default)
		)
		(layer "F.Cu")
	)
	(gr_line
		(start 119.62257 10.483342)
		(end 119.627142 10.423144)
		(stroke
			(width 0.0635)
			(type default)
		)
		(layer "F.Cu")
	)
	(gr_arc
		(start 119.62257 10.484866)
		(mid 119.590314 10.646556)
		(end 119.498618 10.78357)
		(stroke
			(width 0.0635)
			(type default)
		)
		(layer "F.Cu")
	)
	(gr_arc
		(start 119.674894 7.742682)
		(mid 119.886289 7.830245)
		(end 119.973852 8.04164)
		(stroke
			(width 0.0635)
			(type default)
		)
		(layer "F.Cu")
	)
	(gr_line
		(start 119.92737 10.475468)
		(end 119.92991 10.460736)
		(stroke
			(width 0.0635)
			(type default)
		)
		(layer "F.Cu")
	)
	(gr_line
		(start 119.969534 8.479536)
		(end 119.973852 8.47344)
		(stroke
			(width 0.0635)
			(type default)
		)
		(layer "F.Cu")
	)
	(gr_line
		(start 119.973852 8.47344)
		(end 119.973852 8.454898)
		(stroke
			(width 0.0635)
			(type default)
		)
		(layer "F.Cu")
	)
	(gr_arc
		(start 120.051322 10.77468)
		(mid 119.959577 10.637406)
		(end 119.92737 10.475468)
		(stroke
			(width 0.0635)
			(type default)
		)
		(layer "F.Cu")
	)
	(gr_arc
		(start 120.051322 10.77468)
		(mid 120.142894 10.911727)
		(end 120.17502 11.073384)
		(stroke
			(width 0.0635)
			(type default)
		)
		(layer "F.Cu")
	)
	(gr_line
		(start 120.17502 12.234672)
		(end 120.17502 11.073384)
		(stroke
			(width 0.0635)
			(type default)
		)
		(layer "F.Cu")
	)
	(gr_line
		(start 120.263158 8.569198)
		(end 120.263158 8.569706)
		(stroke
			(width 0.0635)
			(type default)
		)
		(layer "F.Cu")
	)
	(gr_line
		(start 120.263158 8.569198)
		(end 120.278398 8.48233)
		(stroke
			(width 0.0635)
			(type default)
		)
		(layer "F.Cu")
	)
	(gr_line
		(start 120.278398 8.48233)
		(end 120.278652 8.481568)
		(stroke
			(width 0.0635)
			(type default)
		)
		(layer "F.Cu")
	)
	(gr_arc
		(start 120.278652 8.04164)
		(mid 120.366201 7.830222)
		(end 120.57761 7.742682)
		(stroke
			(width 0.0635)
			(type default)
		)
		(layer "F.Cu")
	)
	(gr_line
		(start 120.57761 7.742682)
		(end 120.621806 7.742682)
		(stroke
			(width 0.0635)
			(type default)
		)
		(layer "F.Cu")
	)
	(gr_arc
		(start 121.774966 11.082274)
		(mid 121.807037 10.920787)
		(end 121.89841 10.783824)
		(stroke
			(width 0.0635)
			(type default)
		)
		(layer "F.Cu")
	)
	(gr_line
		(start 121.774966 12.234672)
		(end 121.774966 11.082274)
		(stroke
			(width 0.0635)
			(type default)
		)
		(layer "F.Cu")
	)
	(gr_line
		(start 121.89841 10.783824)
		(end 121.898664 10.78357)
		(stroke
			(width 0.0635)
			(type default)
		)
		(layer "F.Cu")
	)
	(gr_line
		(start 122.022616 10.483342)
		(end 122.027188 10.423144)
		(stroke
			(width 0.0635)
			(type default)
		)
		(layer "F.Cu")
	)
	(gr_arc
		(start 122.022616 10.484866)
		(mid 121.99036 10.646556)
		(end 121.898664 10.78357)
		(stroke
			(width 0.0635)
			(type default)
		)
		(layer "F.Cu")
	)
	(gr_line
		(start 122.056144 10.25906)
		(end 122.09526 10.037318)
		(stroke
			(width 0.0635)
			(type default)
		)
		(layer "F.Cu")
	)
	(gr_line
		(start 122.09526 10.037318)
		(end 122.107198 9.969754)
		(stroke
			(width 0.0635)
			(type default)
		)
		(layer "F.Cu")
	)
	(gr_line
		(start 122.112786 9.937496)
		(end 122.11558 9.922256)
		(stroke
			(width 0.0635)
			(type default)
		)
		(layer "F.Cu")
	)
	(gr_line
		(start 122.120914 9.891776)
		(end 122.12574 9.864598)
		(stroke
			(width 0.0635)
			(type default)
		)
		(layer "F.Cu")
	)
	(gr_line
		(start 122.12574 9.864598)
		(end 122.141742 9.841992)
		(stroke
			(width 0.0635)
			(type default)
		)
		(layer "F.Cu")
	)
	(gr_line
		(start 122.196606 7.742682)
		(end 122.265694 7.742682)
		(stroke
			(width 0.0635)
			(type default)
		)
		(layer "F.Cu")
	)
	(gr_arc
		(start 122.265694 7.742682)
		(mid 122.477089 7.830245)
		(end 122.564652 8.04164)
		(stroke
			(width 0.0635)
			(type default)
		)
		(layer "F.Cu")
	)
	(gr_line
		(start 122.327416 10.475468)
		(end 122.329956 10.460736)
		(stroke
			(width 0.0635)
			(type default)
		)
		(layer "F.Cu")
	)
	(gr_line
		(start 122.394472 10.095992)
		(end 122.41403 9.984486)
		(stroke
			(width 0.0635)
			(type default)
		)
		(layer "F.Cu")
	)
	(gr_arc
		(start 122.451368 10.77468)
		(mid 122.359641 10.6374)
		(end 122.327416 10.475468)
		(stroke
			(width 0.0635)
			(type default)
		)
		(layer "F.Cu")
	)
	(gr_arc
		(start 122.451368 10.77468)
		(mid 122.54291 10.911735)
		(end 122.575066 11.073384)
		(stroke
			(width 0.0635)
			(type default)
		)
		(layer "F.Cu")
	)
	(gr_line
		(start 122.575066 12.234672)
		(end 122.575066 11.073384)
		(stroke
			(width 0.0635)
			(type default)
		)
		(layer "F.Cu")
	)
	(gr_line
		(start 122.649996 9.647936)
		(end 122.66676 9.623806)
		(stroke
			(width 0.0635)
			(type default)
		)
		(layer "F.Cu")
	)
	(gr_line
		(start 122.66676 9.623806)
		(end 122.67184 9.595104)
		(stroke
			(width 0.0635)
			(type default)
		)
		(layer "F.Cu")
	)
	(gr_arc
		(start 122.869452 8.04164)
		(mid 122.957015 7.830245)
		(end 123.16841 7.742682)
		(stroke
			(width 0.0635)
			(type default)
		)
		(layer "F.Cu")
	)
	(gr_line
		(start 123.16841 7.742682)
		(end 123.212606 7.742682)
		(stroke
			(width 0.0635)
			(type default)
		)
		(layer "F.Cu")
	)
	(gr_line
		(start 123.274582 -31.78302)
		(end 123.316238 -31.824676)
		(stroke
			(width 0.05715)
			(type default)
		)
		(layer "F.Cu")
	)
	(gr_line
		(start 123.274582 -30.96133)
		(end 123.274582 -31.78302)
		(stroke
			(width 0.05715)
			(type default)
		)
		(layer "F.Cu")
	)
	(gr_line
		(start 123.732798 -31.824676)
		(end 123.774454 -31.78302)
		(stroke
			(width 0.05715)
			(type default)
		)
		(layer "F.Cu")
	)
	(gr_line
		(start 123.774454 -30.96133)
		(end 123.774454 -31.78302)
		(stroke
			(width 0.05715)
			(type default)
		)
		(layer "F.Cu")
	)
	(gr_arc
		(start 124.175012 11.082274)
		(mid 124.207097 10.920794)
		(end 124.298456 10.783824)
		(stroke
			(width 0.0635)
			(type default)
		)
		(layer "F.Cu")
	)
	(gr_line
		(start 124.175012 12.234672)
		(end 124.175012 11.082274)
		(stroke
			(width 0.0635)
			(type default)
		)
		(layer "F.Cu")
	)
	(gr_line
		(start 124.298456 10.783824)
		(end 124.29871 10.78357)
		(stroke
			(width 0.0635)
			(type default)
		)
		(layer "F.Cu")
	)
	(gr_line
		(start 124.422662 10.483342)
		(end 124.427234 10.423144)
		(stroke
			(width 0.0635)
			(type default)
		)
		(layer "F.Cu")
	)
	(gr_arc
		(start 124.422662 10.484866)
		(mid 124.390349 10.646523)
		(end 124.29871 10.78357)
		(stroke
			(width 0.0635)
			(type default)
		)
		(layer "F.Cu")
	)
	(gr_line
		(start 124.521976 9.88314)
		(end 124.527056 9.854946)
		(stroke
			(width 0.0635)
			(type default)
		)
		(layer "F.Cu")
	)
	(gr_line
		(start 124.527056 9.854946)
		(end 124.543312 9.831578)
		(stroke
			(width 0.0635)
			(type default)
		)
		(layer "F.Cu")
	)
	(gr_line
		(start 124.727462 10.475468)
		(end 124.730002 10.460736)
		(stroke
			(width 0.0635)
			(type default)
		)
		(layer "F.Cu")
	)
	(gr_line
		(start 124.774706 -31.78302)
		(end 124.816362 -31.824676)
		(stroke
			(width 0.05715)
			(type default)
		)
		(layer "F.Cu")
	)
	(gr_line
		(start 124.774706 -30.96133)
		(end 124.774706 -31.78302)
		(stroke
			(width 0.05715)
			(type default)
		)
		(layer "F.Cu")
	)
	(gr_line
		(start 124.787406 7.742682)
		(end 124.856494 7.742682)
		(stroke
			(width 0.0635)
			(type default)
		)
		(layer "F.Cu")
	)
	(gr_arc
		(start 124.851414 10.77468)
		(mid 124.75967 10.637406)
		(end 124.727462 10.475468)
		(stroke
			(width 0.0635)
			(type default)
		)
		(layer "F.Cu")
	)
	(gr_arc
		(start 124.851414 10.77468)
		(mid 124.942986 10.911727)
		(end 124.975112 11.073384)
		(stroke
			(width 0.0635)
			(type default)
		)
		(layer "F.Cu")
	)
	(gr_arc
		(start 124.856494 7.742682)
		(mid 125.067879 7.830245)
		(end 125.155452 8.04164)
		(stroke
			(width 0.0635)
			(type default)
		)
		(layer "F.Cu")
	)
	(gr_line
		(start 124.975112 12.234672)
		(end 124.975112 11.073384)
		(stroke
			(width 0.0635)
			(type default)
		)
		(layer "F.Cu")
	)
	(gr_line
		(start 125.115828 8.672068)
		(end 125.164342 8.396478)
		(stroke
			(width 0.0635)
			(type default)
		)
		(layer "F.Cu")
	)
	(gr_line
		(start 125.155452 8.34644)
		(end 125.164342 8.396478)
		(stroke
			(width 0.0635)
			(type default)
		)
		(layer "F.Cu")
	)
	(gr_line
		(start 125.232922 -31.824676)
		(end 125.274578 -31.78302)
		(stroke
			(width 0.05715)
			(type default)
		)
		(layer "F.Cu")
	)
	(gr_line
		(start 125.274578 -30.96133)
		(end 125.274578 -31.78302)
		(stroke
			(width 0.05715)
			(type default)
		)
		(layer "F.Cu")
	)
	(gr_line
		(start 125.307344 9.272524)
		(end 125.3236 9.249156)
		(stroke
			(width 0.0635)
			(type default)
		)
		(layer "F.Cu")
	)
	(gr_line
		(start 125.3236 9.249156)
		(end 125.32868 9.220962)
		(stroke
			(width 0.0635)
			(type default)
		)
		(layer "F.Cu")
	)
	(gr_line
		(start 125.433582 8.625078)
		(end 125.460252 8.47344)
		(stroke
			(width 0.0635)
			(type default)
		)
		(layer "F.Cu")
	)
	(gr_arc
		(start 125.460252 8.04164)
		(mid 125.547801 7.830222)
		(end 125.75921 7.742682)
		(stroke
			(width 0.0635)
			(type default)
		)
		(layer "F.Cu")
	)
	(gr_line
		(start 125.460252 8.47344)
		(end 125.460252 8.319516)
		(stroke
			(width 0.0635)
			(type default)
		)
		(layer "F.Cu")
	)
	(gr_line
		(start 125.639576 -33.865566)
		(end 125.86716 -33.637982)
		(stroke
			(width 0.05715)
			(type default)
		)
		(layer "F.Cu")
	)
	(gr_line
		(start 125.75921 7.742682)
		(end 125.803406 7.742682)
		(stroke
			(width 0.0635)
			(type default)
		)
		(layer "F.Cu")
	)
	(gr_line
		(start 125.774704 -31.629604)
		(end 125.863858 -31.718758)
		(stroke
			(width 0.05715)
			(type default)
		)
		(layer "F.Cu")
	)
	(gr_line
		(start 125.774704 -30.96133)
		(end 125.774704 -31.629604)
		(stroke
			(width 0.05715)
			(type default)
		)
		(layer "F.Cu")
	)
	(gr_line
		(start 126.274576 -31.03753)
		(end 126.274576 -31.7246)
		(stroke
			(width 0.05715)
			(type default)
		)
		(layer "F.Cu")
	)
	(gr_line
		(start 126.28372 -33.637982)
		(end 126.511304 -33.865566)
		(stroke
			(width 0.05715)
			(type default)
		)
		(layer "F.Cu")
	)
	(gr_arc
		(start 126.575058 11.082274)
		(mid 126.607143 10.920794)
		(end 126.698502 10.783824)
		(stroke
			(width 0.0635)
			(type default)
		)
		(layer "F.Cu")
	)
	(gr_line
		(start 126.575058 12.234672)
		(end 126.575058 11.082274)
		(stroke
			(width 0.0635)
			(type default)
		)
		(layer "F.Cu")
	)
	(gr_line
		(start 126.698502 10.783824)
		(end 126.698756 10.78357)
		(stroke
			(width 0.0635)
			(type default)
		)
		(layer "F.Cu")
	)
	(gr_arc
		(start 126.822708 10.484866)
		(mid 126.790398 10.646525)
		(end 126.698756 10.78357)
		(stroke
			(width 0.0635)
			(type default)
		)
		(layer "F.Cu")
	)
	(gr_line
		(start 126.822708 10.484866)
		(end 126.827026 10.423144)
		(stroke
			(width 0.0635)
			(type default)
		)
		(layer "F.Cu")
	)
	(gr_line
		(start 127.11938 -27.616404)
		(end 127.94107 -27.616404)
		(stroke
			(width 0.05715)
			(type default)
		)
		(layer "F.Cu")
	)
	(gr_line
		(start 127.11938 -27.116532)
		(end 127.94107 -27.116532)
		(stroke
			(width 0.05715)
			(type default)
		)
		(layer "F.Cu")
	)
	(gr_line
		(start 127.127254 10.475468)
		(end 127.130048 10.460228)
		(stroke
			(width 0.0635)
			(type default)
		)
		(layer "F.Cu")
	)
	(gr_arc
		(start 127.251206 10.77468)
		(mid 127.159464 10.637405)
		(end 127.127254 10.475468)
		(stroke
			(width 0.0635)
			(type default)
		)
		(layer "F.Cu")
	)
	(gr_arc
		(start 127.251206 10.77468)
		(mid 127.342778 10.911727)
		(end 127.374904 11.073384)
		(stroke
			(width 0.0635)
			(type default)
		)
		(layer "F.Cu")
	)
	(gr_line
		(start 127.374904 11.073384)
		(end 127.375158 12.234672)
		(stroke
			(width 0.0635)
			(type default)
		)
		(layer "F.Cu")
	)
	(gr_line
		(start 127.378206 7.742682)
		(end 127.490982 7.742682)
		(stroke
			(width 0.0635)
			(type default)
		)
		(layer "F.Cu")
	)
	(gr_arc
		(start 127.490982 7.742682)
		(mid 127.658556 7.807952)
		(end 127.738124 7.96925)
		(stroke
			(width 0.0635)
			(type default)
		)
		(layer "F.Cu")
	)
	(gr_line
		(start 127.94107 -27.616404)
		(end 127.982726 -27.574748)
		(stroke
			(width 0.05715)
			(type default)
		)
		(layer "F.Cu")
	)
	(gr_line
		(start 127.94107 -27.116532)
		(end 127.982726 -27.158188)
		(stroke
			(width 0.05715)
			(type default)
		)
		(layer "F.Cu")
	)
	(gr_arc
		(start 128.04394 7.99084)
		(mid 128.11661 7.815339)
		(end 128.292098 7.742682)
		(stroke
			(width 0.0635)
			(type default)
		)
		(layer "F.Cu")
	)
	(gr_line
		(start 128.292098 7.742682)
		(end 128.394206 7.742682)
		(stroke
			(width 0.0635)
			(type default)
		)
		(layer "F.Cu")
	)
	(gr_line
		(start 131.37515 10.788396)
		(end 131.56692 10.596626)
		(stroke
			(width 0.05715)
			(type default)
		)
		(layer "F.Cu")
	)
	(gr_line
		(start 131.37515 12.234672)
		(end 131.37515 10.788396)
		(stroke
			(width 0.05715)
			(type default)
		)
		(layer "F.Cu")
	)
	(gr_line
		(start 131.45389 7.600696)
		(end 131.62661 7.427976)
		(stroke
			(width 0.05715)
			(type default)
		)
		(layer "F.Cu")
	)
	(gr_line
		(start 131.45389 7.943596)
		(end 131.45389 7.600696)
		(stroke
			(width 0.05715)
			(type default)
		)
		(layer "F.Cu")
	)
	(gr_line
		(start 131.45389 7.943596)
		(end 131.62661 8.116316)
		(stroke
			(width 0.05715)
			(type default)
		)
		(layer "F.Cu")
	)
	(gr_line
		(start 131.45389 8.637016)
		(end 131.62661 8.464296)
		(stroke
			(width 0.05715)
			(type default)
		)
		(layer "F.Cu")
	)
	(gr_line
		(start 131.45389 8.979916)
		(end 131.45389 8.637016)
		(stroke
			(width 0.05715)
			(type default)
		)
		(layer "F.Cu")
	)
	(gr_line
		(start 131.45389 8.979916)
		(end 131.62661 9.152636)
		(stroke
			(width 0.05715)
			(type default)
		)
		(layer "F.Cu")
	)
	(gr_line
		(start 131.45389 9.673336)
		(end 131.62661 9.500616)
		(stroke
			(width 0.05715)
			(type default)
		)
		(layer "F.Cu")
	)
	(gr_line
		(start 131.45389 10.016236)
		(end 131.45389 9.673336)
		(stroke
			(width 0.05715)
			(type default)
		)
		(layer "F.Cu")
	)
	(gr_line
		(start 131.45389 10.016236)
		(end 131.62661 10.188956)
		(stroke
			(width 0.05715)
			(type default)
		)
		(layer "F.Cu")
	)
	(gr_line
		(start 131.92125 7.824216)
		(end 131.92125 7.720076)
		(stroke
			(width 0.05715)
			(type default)
		)
		(layer "F.Cu")
	)
	(gr_line
		(start 131.92125 8.860536)
		(end 131.92125 8.756396)
		(stroke
			(width 0.05715)
			(type default)
		)
		(layer "F.Cu")
	)
	(gr_line
		(start 131.92125 9.896856)
		(end 131.92125 9.792716)
		(stroke
			(width 0.05715)
			(type default)
		)
		(layer "F.Cu")
	)
	(gr_line
		(start 131.98348 10.596626)
		(end 132.174996 10.788142)
		(stroke
			(width 0.05715)
			(type default)
		)
		(layer "F.Cu")
	)
	(gr_line
		(start 132.174996 12.234672)
		(end 132.174996 10.788142)
		(stroke
			(width 0.05715)
			(type default)
		)
		(layer "F.Cu")
	)
	(gr_line
		(start 14.0208 -26.028396)
		(end 14.227302 -26.234898)
		(stroke
			(width 0.1016)
			(type default)
		)
		(layer "B.Cu")
	)
	(gr_line
		(start 14.0208 -25.797764)
		(end 14.0208 -26.028396)
		(stroke
			(width 0.1016)
			(type default)
		)
		(layer "B.Cu")
	)
	(gr_line
		(start 14.227302 -26.234898)
		(end 14.449298 -26.234898)
		(stroke
			(width 0.1016)
			(type default)
		)
		(layer "B.Cu")
	)
	(gr_line
		(start 14.35354 -25.467564)
		(end 14.492478 -25.606502)
		(stroke
			(width 0.1016)
			(type default)
		)
		(layer "B.Cu")
	)
	(gr_line
		(start 14.449298 -26.234898)
		(end 14.811502 -26.597102)
		(stroke
			(width 0.1016)
			(type default)
		)
		(layer "B.Cu")
	)
	(gr_line
		(start 14.492478 -25.606502)
		(end 14.855698 -25.606502)
		(stroke
			(width 0.1016)
			(type default)
		)
		(layer "B.Cu")
	)
	(gr_line
		(start 14.811502 -26.597102)
		(end 14.811502 -27.003502)
		(stroke
			(width 0.1016)
			(type default)
		)
		(layer "B.Cu")
	)
	(gr_line
		(start 14.855698 -25.955498)
		(end 15.167102 -26.266902)
		(stroke
			(width 0.1016)
			(type default)
		)
		(layer "B.Cu")
	)
	(gr_line
		(start 14.855698 -25.606502)
		(end 14.855698 -25.955498)
		(stroke
			(width 0.1016)
			(type default)
		)
		(layer "B.Cu")
	)
	(gr_line
		(start 15.167102 -26.266902)
		(end 15.548102 -26.266902)
		(stroke
			(width 0.1016)
			(type default)
		)
		(layer "B.Cu")
	)
	(gr_line
		(start 19.811746 -25.120346)
		(end 19.8374 -25.146)
		(stroke
			(width 0.1016)
			(type default)
		)
		(layer "B.Cu")
	)
	(gr_line
		(start 19.813524 -24.651462)
		(end 20.699476 -24.651462)
		(stroke
			(width 0.1016)
			(type default)
		)
		(layer "B.Cu")
	)
	(gr_line
		(start 19.8374 -25.146)
		(end 20.701 -25.146)
		(stroke
			(width 0.1016)
			(type default)
		)
		(layer "B.Cu")
	)
	(gr_line
		(start 20.701 -25.146)
		(end 21.007324 -25.452324)
		(stroke
			(width 0.1016)
			(type default)
		)
		(layer "B.Cu")
	)
	(gr_line
		(start 21.007324 -25.452324)
		(end 21.500338 -25.452324)
		(stroke
			(width 0.1016)
			(type default)
		)
		(layer "B.Cu")
	)
	(gr_arc
		(start 29.179774 10.924032)
		(mid 29.211927 10.762386)
		(end 29.303472 10.625328)
		(stroke
			(width 0.0635)
			(type default)
		)
		(layer "B.Cu")
	)
	(gr_line
		(start 29.179774 12.514072)
		(end 29.179774 10.924032)
		(stroke
			(width 0.0635)
			(type default)
		)
		(layer "B.Cu")
	)
	(gr_line
		(start 29.427424 10.13587)
		(end 29.442156 10.106406)
		(stroke
			(width 0.0635)
			(type default)
		)
		(layer "B.Cu")
	)
	(gr_line
		(start 29.666184 9.658858)
		(end 29.670756 9.649206)
		(stroke
			(width 0.0635)
			(type default)
		)
		(layer "B.Cu")
	)
	(gr_line
		(start 29.670756 9.649206)
		(end 29.678884 9.641078)
		(stroke
			(width 0.0635)
			(type default)
		)
		(layer "B.Cu")
	)
	(gr_arc
		(start 29.855668 10.805922)
		(mid 29.764282 10.668964)
		(end 29.732224 10.507472)
		(stroke
			(width 0.0635)
			(type default)
		)
		(layer "B.Cu")
	)
	(gr_line
		(start 29.855668 10.805922)
		(end 29.855922 10.806176)
		(stroke
			(width 0.0635)
			(type default)
		)
		(layer "B.Cu")
	)
	(gr_arc
		(start 29.855922 10.806176)
		(mid 29.947625 10.943194)
		(end 29.979874 11.10488)
		(stroke
			(width 0.0635)
			(type default)
		)
		(layer "B.Cu")
	)
	(gr_line
		(start 29.979874 12.514072)
		(end 29.979874 11.10488)
		(stroke
			(width 0.0635)
			(type default)
		)
		(layer "B.Cu")
	)
	(gr_line
		(start 30.671262 8.648192)
		(end 30.718506 8.600948)
		(stroke
			(width 0.0635)
			(type default)
		)
		(layer "B.Cu")
	)
	(gr_line
		(start 30.718506 8.600948)
		(end 30.784546 8.592312)
		(stroke
			(width 0.0635)
			(type default)
		)
		(layer "B.Cu")
	)
	(gr_line
		(start 31.098236 8.549132)
		(end 31.247334 8.355076)
		(stroke
			(width 0.0635)
			(type default)
		)
		(layer "B.Cu")
	)
	(gr_line
		(start 31.173674 8.849106)
		(end 31.82493 8.764016)
		(stroke
			(width 0.0635)
			(type default)
		)
		(layer "B.Cu")
	)
	(gr_line
		(start 31.247334 8.355076)
		(end 31.625032 8.3058)
		(stroke
			(width 0.0635)
			(type default)
		)
		(layer "B.Cu")
	)
	(gr_line
		(start 31.625032 8.3058)
		(end 31.819088 8.454898)
		(stroke
			(width 0.0635)
			(type default)
		)
		(layer "B.Cu")
	)
	(gr_line
		(start 32.201358 8.40486)
		(end 32.350456 8.211058)
		(stroke
			(width 0.0635)
			(type default)
		)
		(layer "B.Cu")
	)
	(gr_line
		(start 32.276034 8.705088)
		(end 32.926528 8.619998)
		(stroke
			(width 0.0635)
			(type default)
		)
		(layer "B.Cu")
	)
	(gr_line
		(start 32.350456 8.211058)
		(end 32.728408 8.161528)
		(stroke
			(width 0.0635)
			(type default)
		)
		(layer "B.Cu")
	)
	(gr_line
		(start 32.728408 8.161528)
		(end 32.92221 8.310626)
		(stroke
			(width 0.0635)
			(type default)
		)
		(layer "B.Cu")
	)
	(gr_line
		(start 36.133786 8.08228)
		(end 36.1569 8.0772)
		(stroke
			(width 0.0635)
			(type default)
		)
		(layer "B.Cu")
	)
	(gr_line
		(start 36.1569 8.0772)
		(end 36.176458 8.063484)
		(stroke
			(width 0.0635)
			(type default)
		)
		(layer "B.Cu")
	)
	(gr_arc
		(start 36.379912 11.013694)
		(mid 36.412134 10.851882)
		(end 36.503864 10.714736)
		(stroke
			(width 0.0635)
			(type default)
		)
		(layer "B.Cu")
	)
	(gr_line
		(start 36.379912 12.514072)
		(end 36.379912 11.013694)
		(stroke
			(width 0.0635)
			(type default)
		)
		(layer "B.Cu")
	)
	(gr_arc
		(start 36.627562 10.416032)
		(mid 36.595422 10.577685)
		(end 36.503864 10.714736)
		(stroke
			(width 0.0635)
			(type default)
		)
		(layer "B.Cu")
	)
	(gr_line
		(start 36.766246 9.08685)
		(end 36.771326 9.06145)
		(stroke
			(width 0.0635)
			(type default)
		)
		(layer "B.Cu")
	)
	(gr_line
		(start 36.771326 9.06145)
		(end 36.786058 9.03986)
		(stroke
			(width 0.0635)
			(type default)
		)
		(layer "B.Cu")
	)
	(gr_arc
		(start 37.05606 10.716514)
		(mid 36.964518 10.579322)
		(end 36.932362 10.417556)
		(stroke
			(width 0.0635)
			(type default)
		)
		(layer "B.Cu")
	)
	(gr_line
		(start 37.05606 10.716514)
		(end 37.093144 10.753598)
		(stroke
			(width 0.0635)
			(type default)
		)
		(layer "B.Cu")
	)
	(gr_arc
		(start 37.093144 10.753598)
		(mid 37.157446 10.849587)
		(end 37.180012 10.962894)
		(stroke
			(width 0.0635)
			(type default)
		)
		(layer "B.Cu")
	)
	(gr_line
		(start 37.107114 8.572754)
		(end 37.11575 8.560308)
		(stroke
			(width 0.0635)
			(type default)
		)
		(layer "B.Cu")
	)
	(gr_line
		(start 37.11575 8.560308)
		(end 37.127688 8.551672)
		(stroke
			(width 0.0635)
			(type default)
		)
		(layer "B.Cu")
	)
	(gr_line
		(start 37.180012 12.514072)
		(end 37.180012 10.962894)
		(stroke
			(width 0.0635)
			(type default)
		)
		(layer "B.Cu")
	)
	(gr_arc
		(start 38.779958 10.874248)
		(mid 38.812101 10.712476)
		(end 38.903656 10.57529)
		(stroke
			(width 0.0635)
			(type default)
		)
		(layer "B.Cu")
	)
	(gr_line
		(start 38.779958 12.514072)
		(end 38.779958 10.874248)
		(stroke
			(width 0.0635)
			(type default)
		)
		(layer "B.Cu")
	)
	(gr_line
		(start 38.903656 10.57529)
		(end 38.94074 10.538206)
		(stroke
			(width 0.0635)
			(type default)
		)
		(layer "B.Cu")
	)
	(gr_line
		(start 38.984174 9.658858)
		(end 38.986714 9.643872)
		(stroke
			(width 0.0635)
			(type default)
		)
		(layer "B.Cu")
	)
	(gr_line
		(start 38.984174 9.658858)
		(end 38.986714 9.67359)
		(stroke
			(width 0.0635)
			(type default)
		)
		(layer "B.Cu")
	)
	(gr_line
		(start 38.986714 9.673844)
		(end 38.986968 9.674606)
		(stroke
			(width 0.0635)
			(type default)
		)
		(layer "B.Cu")
	)
	(gr_arc
		(start 39.027608 10.32891)
		(mid 39.005007 10.442204)
		(end 38.94074 10.538206)
		(stroke
			(width 0.0635)
			(type default)
		)
		(layer "B.Cu")
	)
	(gr_line
		(start 39.096696 9.019794)
		(end 39.101776 8.9916)
		(stroke
			(width 0.0635)
			(type default)
		)
		(layer "B.Cu")
	)
	(gr_line
		(start 39.101776 8.9916)
		(end 39.118032 8.968232)
		(stroke
			(width 0.0635)
			(type default)
		)
		(layer "B.Cu")
	)
	(gr_arc
		(start 39.456106 10.627106)
		(mid 39.364534 10.490059)
		(end 39.332408 10.328402)
		(stroke
			(width 0.0635)
			(type default)
		)
		(layer "B.Cu")
	)
	(gr_line
		(start 39.456106 10.627106)
		(end 39.49319 10.66419)
		(stroke
			(width 0.0635)
			(type default)
		)
		(layer "B.Cu")
	)
	(gr_arc
		(start 39.49319 10.66419)
		(mid 39.557296 10.760093)
		(end 39.579804 10.873232)
		(stroke
			(width 0.0635)
			(type default)
		)
		(layer "B.Cu")
	)
	(gr_line
		(start 39.579804 12.514072)
		(end 39.579804 10.873232)
		(stroke
			(width 0.0635)
			(type default)
		)
		(layer "B.Cu")
	)
	(gr_line
		(start 39.584122 8.302752)
		(end 39.61892 8.253222)
		(stroke
			(width 0.0635)
			(type default)
		)
		(layer "B.Cu")
	)
	(gr_line
		(start 39.629842 8.237474)
		(end 39.63035 8.236712)
		(stroke
			(width 0.0635)
			(type default)
		)
		(layer "B.Cu")
	)
	(gr_line
		(start 39.63035 8.236712)
		(end 39.630604 8.236458)
		(stroke
			(width 0.0635)
			(type default)
		)
		(layer "B.Cu")
	)
	(gr_line
		(start 39.630604 8.236458)
		(end 39.63416 8.236458)
		(stroke
			(width 0.0635)
			(type default)
		)
		(layer "B.Cu")
	)
	(gr_line
		(start 39.752524 8.11784)
		(end 39.75354 8.117332)
		(stroke
			(width 0.0635)
			(type default)
		)
		(layer "B.Cu")
	)
	(gr_line
		(start 39.849806 8.452104)
		(end 39.855902 8.446008)
		(stroke
			(width 0.0635)
			(type default)
		)
		(layer "B.Cu")
	)
	(gr_line
		(start 39.849806 8.455152)
		(end 39.849806 8.452104)
		(stroke
			(width 0.0635)
			(type default)
		)
		(layer "B.Cu")
	)
	(gr_line
		(start 41.351708 4.400804)
		(end 41.357296 4.397756)
		(stroke
			(width 0.0635)
			(type default)
		)
		(layer "B.Cu")
	)
	(gr_line
		(start 41.357296 4.397756)
		(end 41.362884 4.396486)
		(stroke
			(width 0.0635)
			(type default)
		)
		(layer "B.Cu")
	)
	(gr_line
		(start 41.60647 5.63245)
		(end 41.618154 5.625846)
		(stroke
			(width 0.0635)
			(type default)
		)
		(layer "B.Cu")
	)
	(gr_line
		(start 41.618154 5.625846)
		(end 41.63187 5.62356)
		(stroke
			(width 0.0635)
			(type default)
		)
		(layer "B.Cu")
	)
	(gr_line
		(start 41.813734 6.893306)
		(end 41.835324 6.880352)
		(stroke
			(width 0.0635)
			(type default)
		)
		(layer "B.Cu")
	)
	(gr_line
		(start 41.835324 6.880352)
		(end 41.860978 6.877304)
		(stroke
			(width 0.0635)
			(type default)
		)
		(layer "B.Cu")
	)
	(gr_line
		(start 44.119038 5.526786)
		(end 44.1325 5.5245)
		(stroke
			(width 0.0635)
			(type default)
		)
		(layer "B.Cu")
	)
	(gr_line
		(start 44.1325 5.5245)
		(end 44.14393 5.51815)
		(stroke
			(width 0.0635)
			(type default)
		)
		(layer "B.Cu")
	)
	(gr_line
		(start 44.79671 6.836664)
		(end 44.831 6.8326)
		(stroke
			(width 0.0635)
			(type default)
		)
		(layer "B.Cu")
	)
	(gr_line
		(start 44.831 6.8326)
		(end 44.86021 6.813296)
		(stroke
			(width 0.0635)
			(type default)
		)
		(layer "B.Cu")
	)
	(gr_line
		(start 44.906438 -7.176262)
		(end 44.906692 -7.179818)
		(stroke
			(width 0.0635)
			(type default)
		)
		(layer "B.Cu")
	)
	(gr_line
		(start 44.906438 -7.176262)
		(end 44.9072 -7.172706)
		(stroke
			(width 0.0635)
			(type default)
		)
		(layer "B.Cu")
	)
	(gr_line
		(start 44.918122 -7.344918)
		(end 44.918122 -7.34695)
		(stroke
			(width 0.0635)
			(type default)
		)
		(layer "B.Cu")
	)
	(gr_line
		(start 44.9199 -7.363206)
		(end 44.9199 -7.362952)
		(stroke
			(width 0.0635)
			(type default)
		)
		(layer "B.Cu")
	)
	(gr_line
		(start 44.9199 -7.363206)
		(end 44.934378 -7.42569)
		(stroke
			(width 0.0635)
			(type default)
		)
		(layer "B.Cu")
	)
	(gr_line
		(start 44.934378 -7.425944)
		(end 44.934378 -7.42569)
		(stroke
			(width 0.0635)
			(type default)
		)
		(layer "B.Cu")
	)
	(gr_line
		(start 45.010832 -7.75716)
		(end 45.012356 -7.763256)
		(stroke
			(width 0.0635)
			(type default)
		)
		(layer "B.Cu")
	)
	(gr_line
		(start 45.010832 -6.680454)
		(end 45.023024 -6.621526)
		(stroke
			(width 0.0635)
			(type default)
		)
		(layer "B.Cu")
	)
	(gr_line
		(start 45.012356 -7.763256)
		(end 45.015404 -7.768844)
		(stroke
			(width 0.0635)
			(type default)
		)
		(layer "B.Cu")
	)
	(gr_line
		(start 45.023024 -6.621526)
		(end 45.068236 -6.580886)
		(stroke
			(width 0.0635)
			(type default)
		)
		(layer "B.Cu")
	)
	(gr_line
		(start 45.079412 -32.069786)
		(end 45.454824 -32.819848)
		(stroke
			(width 0.0635)
			(type default)
		)
		(layer "B.Cu")
	)
	(gr_line
		(start 45.142404 3.549142)
		(end 45.1866 3.5306)
		(stroke
			(width 0.0635)
			(type default)
		)
		(layer "B.Cu")
	)
	(gr_line
		(start 45.1866 3.5306)
		(end 45.214794 3.491992)
		(stroke
			(width 0.0635)
			(type default)
		)
		(layer "B.Cu")
	)
	(gr_line
		(start 45.221906 -7.316216)
		(end 45.222414 -7.32409)
		(stroke
			(width 0.0635)
			(type default)
		)
		(layer "B.Cu")
	)
	(gr_line
		(start 45.222414 -7.326122)
		(end 45.224192 -7.325868)
		(stroke
			(width 0.0635)
			(type default)
		)
		(layer "B.Cu")
	)
	(gr_line
		(start 45.222414 -7.32409)
		(end 45.222414 -7.326122)
		(stroke
			(width 0.0635)
			(type default)
		)
		(layer "B.Cu")
	)
	(gr_line
		(start 45.268134 -8.211312)
		(end 45.28947 -8.248142)
		(stroke
			(width 0.0635)
			(type default)
		)
		(layer "B.Cu")
	)
	(gr_line
		(start 45.27169 -26.547318)
		(end 45.276262 -26.542746)
		(stroke
			(width 0.0635)
			(type default)
		)
		(layer "B.Cu")
	)
	(gr_line
		(start 45.276262 -26.542746)
		(end 45.28185 -26.539698)
		(stroke
			(width 0.0635)
			(type default)
		)
		(layer "B.Cu")
	)
	(gr_line
		(start 45.296074 -8.26008)
		(end 45.29709 -8.261096)
		(stroke
			(width 0.0635)
			(type default)
		)
		(layer "B.Cu")
	)
	(gr_line
		(start 45.298106 -8.260334)
		(end 45.299122 -8.26135)
		(stroke
			(width 0.0635)
			(type default)
		)
		(layer "B.Cu")
	)
	(gr_line
		(start 45.299122 -8.26135)
		(end 45.303694 -8.267192)
		(stroke
			(width 0.0635)
			(type default)
		)
		(layer "B.Cu")
	)
	(gr_arc
		(start 45.454824 -32.819848)
		(mid 45.52831 -32.883515)
		(end 45.625258 -32.87649)
		(stroke
			(width 0.0635)
			(type default)
		)
		(layer "B.Cu")
	)
	(gr_arc
		(start 45.478954 -28.728162)
		(mid 45.483549 -28.735307)
		(end 45.488606 -28.742132)
		(stroke
			(width 0.0635)
			(type default)
		)
		(layer "B.Cu")
	)
	(gr_line
		(start 45.541692 -8.076946)
		(end 45.5422 -8.076438)
		(stroke
			(width 0.0635)
			(type default)
		)
		(layer "B.Cu")
	)
	(gr_line
		(start 45.541692 -8.076946)
		(end 45.542708 -8.077962)
		(stroke
			(width 0.0635)
			(type default)
		)
		(layer "B.Cu")
	)
	(gr_line
		(start 45.541692 -8.075168)
		(end 45.542708 -8.076184)
		(stroke
			(width 0.0635)
			(type default)
		)
		(layer "B.Cu")
	)
	(gr_line
		(start 45.542708 -8.077962)
		(end 45.543216 -8.078724)
		(stroke
			(width 0.0635)
			(type default)
		)
		(layer "B.Cu")
	)
	(gr_line
		(start 45.543216 -8.078724)
		(end 45.544486 -8.080248)
		(stroke
			(width 0.0635)
			(type default)
		)
		(layer "B.Cu")
	)
	(gr_line
		(start 45.625258 -32.87649)
		(end 45.625512 -32.87649)
		(stroke
			(width 0.0635)
			(type default)
		)
		(layer "B.Cu")
	)
	(gr_line
		(start 45.625512 -32.87649)
		(end 45.62856 -32.874966)
		(stroke
			(width 0.0635)
			(type default)
		)
		(layer "B.Cu")
	)
	(gr_line
		(start 45.70476 -33.31972)
		(end 46.080172 -34.070036)
		(stroke
			(width 0.0635)
			(type default)
		)
		(layer "B.Cu")
	)
	(gr_arc
		(start 45.761402 -33.149286)
		(mid 45.697783 -33.222772)
		(end 45.70476 -33.31972)
		(stroke
			(width 0.0635)
			(type default)
		)
		(layer "B.Cu")
	)
	(gr_line
		(start 45.761402 -33.149286)
		(end 45.761656 -33.149286)
		(stroke
			(width 0.0635)
			(type default)
		)
		(layer "B.Cu")
	)
	(gr_line
		(start 45.964348 -11.895328)
		(end 45.965364 -11.898376)
		(stroke
			(width 0.0635)
			(type default)
		)
		(layer "B.Cu")
	)
	(gr_line
		(start 45.964348 -11.89228)
		(end 45.964348 -11.895328)
		(stroke
			(width 0.0635)
			(type default)
		)
		(layer "B.Cu")
	)
	(gr_arc
		(start 45.979842 10.964164)
		(mid 46.012145 10.802501)
		(end 46.103794 10.66546)
		(stroke
			(width 0.0635)
			(type default)
		)
		(layer "B.Cu")
	)
	(gr_line
		(start 45.979842 12.514072)
		(end 45.979842 10.964164)
		(stroke
			(width 0.0635)
			(type default)
		)
		(layer "B.Cu")
	)
	(gr_line
		(start 46.098206 -29.02204)
		(end 46.11624 -29.0449)
		(stroke
			(width 0.0635)
			(type default)
		)
		(layer "B.Cu")
	)
	(gr_line
		(start 46.103794 10.66546)
		(end 46.104048 10.665206)
		(stroke
			(width 0.0635)
			(type default)
		)
		(layer "B.Cu")
	)
	(gr_line
		(start 46.113954 -12.403582)
		(end 46.120558 -12.426696)
		(stroke
			(width 0.0635)
			(type default)
		)
		(layer "B.Cu")
	)
	(gr_line
		(start 46.11624 -29.0449)
		(end 46.122844 -29.073348)
		(stroke
			(width 0.0635)
			(type default)
		)
		(layer "B.Cu")
	)
	(gr_line
		(start 46.120558 -12.426696)
		(end 46.136052 -12.445492)
		(stroke
			(width 0.0635)
			(type default)
		)
		(layer "B.Cu")
	)
	(gr_line
		(start 46.140116 -8.871966)
		(end 46.164754 -8.904732)
		(stroke
			(width 0.0635)
			(type default)
		)
		(layer "B.Cu")
	)
	(gr_line
		(start 46.164754 -8.904732)
		(end 46.170088 -8.945372)
		(stroke
			(width 0.0635)
			(type default)
		)
		(layer "B.Cu")
	)
	(gr_line
		(start 46.185074 4.385564)
		(end 46.2153 4.3688)
		(stroke
			(width 0.0635)
			(type default)
		)
		(layer "B.Cu")
	)
	(gr_line
		(start 46.2153 4.3688)
		(end 46.234858 4.340352)
		(stroke
			(width 0.0635)
			(type default)
		)
		(layer "B.Cu")
	)
	(gr_arc
		(start 46.227492 10.366756)
		(mid 46.195407 10.528236)
		(end 46.104048 10.665206)
		(stroke
			(width 0.0635)
			(type default)
		)
		(layer "B.Cu")
	)
	(gr_line
		(start 46.433232 8.381746)
		(end 46.43882 8.356092)
		(stroke
			(width 0.0635)
			(type default)
		)
		(layer "B.Cu")
	)
	(gr_line
		(start 46.43882 8.356092)
		(end 46.45406 8.335264)
		(stroke
			(width 0.0635)
			(type default)
		)
		(layer "B.Cu")
	)
	(gr_line
		(start 46.625764 7.803642)
		(end 46.663356 8.044942)
		(stroke
			(width 0.0635)
			(type default)
		)
		(layer "B.Cu")
	)
	(gr_line
		(start 46.625764 7.803642)
		(end 46.850808 7.496048)
		(stroke
			(width 0.0635)
			(type default)
		)
		(layer "B.Cu")
	)
	(gr_arc
		(start 46.656244 10.664444)
		(mid 46.564487 10.527309)
		(end 46.532292 10.365486)
		(stroke
			(width 0.0635)
			(type default)
		)
		(layer "B.Cu")
	)
	(gr_arc
		(start 46.656244 10.664444)
		(mid 46.747803 10.801495)
		(end 46.779942 10.963148)
		(stroke
			(width 0.0635)
			(type default)
		)
		(layer "B.Cu")
	)
	(gr_line
		(start 46.779942 12.514072)
		(end 46.779942 10.963148)
		(stroke
			(width 0.0635)
			(type default)
		)
		(layer "B.Cu")
	)
	(gr_line
		(start 46.850808 7.496048)
		(end 47.092362 7.45871)
		(stroke
			(width 0.0635)
			(type default)
		)
		(layer "B.Cu")
	)
	(gr_line
		(start 46.93285 8.197342)
		(end 47.319184 7.669276)
		(stroke
			(width 0.0635)
			(type default)
		)
		(layer "B.Cu")
	)
	(gr_line
		(start 47.059596 -14.511274)
		(end 47.064422 -14.537436)
		(stroke
			(width 0.0635)
			(type default)
		)
		(layer "B.Cu")
	)
	(gr_line
		(start 47.064422 -14.537436)
		(end 47.112682 -14.651482)
		(stroke
			(width 0.0635)
			(type default)
		)
		(layer "B.Cu")
	)
	(gr_line
		(start 47.082202 -13.114528)
		(end 47.10684 -13.1445)
		(stroke
			(width 0.0635)
			(type default)
		)
		(layer "B.Cu")
	)
	(gr_line
		(start 47.10684 -13.1445)
		(end 47.114206 -13.1826)
		(stroke
			(width 0.0635)
			(type default)
		)
		(layer "B.Cu")
	)
	(gr_line
		(start 47.112682 -14.651482)
		(end 47.114206 -14.65199)
		(stroke
			(width 0.0635)
			(type default)
		)
		(layer "B.Cu")
	)
	(gr_line
		(start 47.187866 5.269484)
		(end 47.2059 5.2578)
		(stroke
			(width 0.0635)
			(type default)
		)
		(layer "B.Cu")
	)
	(gr_line
		(start 47.2059 5.2578)
		(end 47.218346 5.239512)
		(stroke
			(width 0.0635)
			(type default)
		)
		(layer "B.Cu")
	)
	(gr_line
		(start 47.230792 -14.921484)
		(end 47.238412 -14.939772)
		(stroke
			(width 0.0635)
			(type default)
		)
		(layer "B.Cu")
	)
	(gr_line
		(start 47.282608 6.905752)
		(end 47.3202 7.147052)
		(stroke
			(width 0.0635)
			(type default)
		)
		(layer "B.Cu")
	)
	(gr_line
		(start 47.282608 6.905752)
		(end 47.507652 6.598158)
		(stroke
			(width 0.0635)
			(type default)
		)
		(layer "B.Cu")
	)
	(gr_line
		(start 47.356014 -14.426184)
		(end 47.40021 -14.530324)
		(stroke
			(width 0.0635)
			(type default)
		)
		(layer "B.Cu")
	)
	(gr_line
		(start 47.399702 -14.531594)
		(end 47.40021 -14.530324)
		(stroke
			(width 0.0635)
			(type default)
		)
		(layer "B.Cu")
	)
	(gr_line
		(start 47.507652 6.598158)
		(end 47.749206 6.56082)
		(stroke
			(width 0.0635)
			(type default)
		)
		(layer "B.Cu")
	)
	(gr_line
		(start 47.589186 7.300214)
		(end 47.976282 6.771132)
		(stroke
			(width 0.0635)
			(type default)
		)
		(layer "B.Cu")
	)
	(gr_line
		(start 48.03775 -0.39751)
		(end 48.0441 -0.4064)
		(stroke
			(width 0.0635)
			(type default)
		)
		(layer "B.Cu")
	)
	(gr_line
		(start 48.0441 -0.4064)
		(end 48.047148 -0.416306)
		(stroke
			(width 0.0635)
			(type default)
		)
		(layer "B.Cu")
	)
	(gr_line
		(start 48.080422 -13.750036)
		(end 48.209454 -13.516356)
		(stroke
			(width 0.0635)
			(type default)
		)
		(layer "B.Cu")
	)
	(gr_line
		(start 48.209454 -13.516356)
		(end 48.455072 -13.024866)
		(stroke
			(width 0.0635)
			(type default)
		)
		(layer "B.Cu")
	)
	(gr_arc
		(start 48.379888 11.027918)
		(mid 48.412144 10.866228)
		(end 48.50384 10.729214)
		(stroke
			(width 0.0635)
			(type default)
		)
		(layer "B.Cu")
	)
	(gr_line
		(start 48.379888 12.514072)
		(end 48.379888 11.027918)
		(stroke
			(width 0.0635)
			(type default)
		)
		(layer "B.Cu")
	)
	(gr_line
		(start 48.397922 -12.854432)
		(end 48.398176 -12.854432)
		(stroke
			(width 0.0635)
			(type default)
		)
		(layer "B.Cu")
	)
	(gr_arc
		(start 48.455072 -13.024866)
		(mid 48.46192 -12.927866)
		(end 48.398176 -12.854432)
		(stroke
			(width 0.0635)
			(type default)
		)
		(layer "B.Cu")
	)
	(gr_line
		(start 48.50384 10.729214)
		(end 48.504094 10.72896)
		(stroke
			(width 0.0635)
			(type default)
		)
		(layer "B.Cu")
	)
	(gr_line
		(start 48.53051 -12.579858)
		(end 48.534574 -12.58189)
		(stroke
			(width 0.0635)
			(type default)
		)
		(layer "B.Cu")
	)
	(gr_line
		(start 48.534574 -12.58189)
		(end 48.534828 -12.58189)
		(stroke
			(width 0.0635)
			(type default)
		)
		(layer "B.Cu")
	)
	(gr_arc
		(start 48.534828 -12.58189)
		(mid 48.631884 -12.588831)
		(end 48.705262 -12.524994)
		(stroke
			(width 0.0635)
			(type default)
		)
		(layer "B.Cu")
	)
	(gr_line
		(start 48.579024 9.591548)
		(end 48.579024 9.591294)
		(stroke
			(width 0.0635)
			(type default)
		)
		(layer "B.Cu")
	)
	(gr_line
		(start 48.579024 9.591548)
		(end 48.5902 9.654794)
		(stroke
			(width 0.0635)
			(type default)
		)
		(layer "B.Cu")
	)
	(gr_line
		(start 48.5902 9.655048)
		(end 48.5902 9.654794)
		(stroke
			(width 0.0635)
			(type default)
		)
		(layer "B.Cu")
	)
	(gr_arc
		(start 48.627538 10.43051)
		(mid 48.595473 10.592)
		(end 48.504094 10.72896)
		(stroke
			(width 0.0635)
			(type default)
		)
		(layer "B.Cu")
	)
	(gr_line
		(start 48.627538 10.43051)
		(end 48.628046 10.430002)
		(stroke
			(width 0.0635)
			(type default)
		)
		(layer "B.Cu")
	)
	(gr_line
		(start 48.628046 10.430002)
		(end 48.628808 10.422128)
		(stroke
			(width 0.0635)
			(type default)
		)
		(layer "B.Cu")
	)
	(gr_line
		(start 48.694086 -2.41935)
		(end 48.7045 -2.4511)
		(stroke
			(width 0.0635)
			(type default)
		)
		(layer "B.Cu")
	)
	(gr_line
		(start 48.699674 -2.48412)
		(end 48.7045 -2.4511)
		(stroke
			(width 0.0635)
			(type default)
		)
		(layer "B.Cu")
	)
	(gr_line
		(start 48.705262 -12.524994)
		(end 48.872902 -12.189206)
		(stroke
			(width 0.0635)
			(type default)
		)
		(layer "B.Cu")
	)
	(gr_line
		(start 48.851312 7.863586)
		(end 48.856392 7.835392)
		(stroke
			(width 0.0635)
			(type default)
		)
		(layer "B.Cu")
	)
	(gr_line
		(start 48.856392 7.835392)
		(end 48.872394 7.812786)
		(stroke
			(width 0.0635)
			(type default)
		)
		(layer "B.Cu")
	)
	(gr_line
		(start 48.872902 -12.189206)
		(end 49.079912 -11.749786)
		(stroke
			(width 0.0635)
			(type default)
		)
		(layer "B.Cu")
	)
	(gr_line
		(start 48.883062 9.570466)
		(end 48.883062 9.560814)
		(stroke
			(width 0.0635)
			(type default)
		)
		(layer "B.Cu")
	)
	(gr_line
		(start 48.883062 9.570466)
		(end 48.885094 9.572498)
		(stroke
			(width 0.0635)
			(type default)
		)
		(layer "B.Cu")
	)
	(gr_line
		(start 48.93183 10.453878)
		(end 48.932084 10.453624)
		(stroke
			(width 0.0635)
			(type default)
		)
		(layer "B.Cu")
	)
	(gr_line
		(start 48.932338 10.454132)
		(end 48.932592 10.453878)
		(stroke
			(width 0.0635)
			(type default)
		)
		(layer "B.Cu")
	)
	(gr_line
		(start 49.031906 7.279132)
		(end 49.074324 7.519924)
		(stroke
			(width 0.0635)
			(type default)
		)
		(layer "B.Cu")
	)
	(gr_line
		(start 49.031906 7.279132)
		(end 49.250346 6.96722)
		(stroke
			(width 0.0635)
			(type default)
		)
		(layer "B.Cu")
	)
	(gr_arc
		(start 49.056036 10.752836)
		(mid 48.964464 10.615789)
		(end 48.932338 10.454132)
		(stroke
			(width 0.0635)
			(type default)
		)
		(layer "B.Cu")
	)
	(gr_arc
		(start 49.056036 10.752836)
		(mid 49.147764 10.890114)
		(end 49.179988 11.052048)
		(stroke
			(width 0.0635)
			(type default)
		)
		(layer "B.Cu")
	)
	(gr_line
		(start 49.089818 -6.303772)
		(end 49.185576 -5.656834)
		(stroke
			(width 0.0635)
			(type default)
		)
		(layer "B.Cu")
	)
	(gr_line
		(start 49.179988 12.514072)
		(end 49.179988 11.052048)
		(stroke
			(width 0.0635)
			(type default)
		)
		(layer "B.Cu")
	)
	(gr_line
		(start 49.250346 6.96722)
		(end 49.491138 6.924548)
		(stroke
			(width 0.0635)
			(type default)
		)
		(layer "B.Cu")
	)
	(gr_line
		(start 49.252886 -5.20319)
		(end 49.348644 -4.555998)
		(stroke
			(width 0.0635)
			(type default)
		)
		(layer "B.Cu")
	)
	(gr_line
		(start 49.34712 7.66572)
		(end 49.72177 7.130796)
		(stroke
			(width 0.0635)
			(type default)
		)
		(layer "B.Cu")
	)
	(gr_line
		(start 49.388522 -6.385052)
		(end 49.584864 -6.23951)
		(stroke
			(width 0.0635)
			(type default)
		)
		(layer "B.Cu")
	)
	(gr_line
		(start 49.398682 -0.264414)
		(end 49.404524 -0.27305)
		(stroke
			(width 0.0635)
			(type default)
		)
		(layer "B.Cu")
	)
	(gr_line
		(start 49.404524 -0.27305)
		(end 49.407064 -0.282448)
		(stroke
			(width 0.0635)
			(type default)
		)
		(layer "B.Cu")
	)
	(gr_line
		(start 49.494948 -5.666232)
		(end 49.640744 -5.862574)
		(stroke
			(width 0.0635)
			(type default)
		)
		(layer "B.Cu")
	)
	(gr_line
		(start 49.55159 -5.28447)
		(end 49.747932 -5.138928)
		(stroke
			(width 0.0635)
			(type default)
		)
		(layer "B.Cu")
	)
	(gr_line
		(start 49.584864 -6.23951)
		(end 49.640744 -5.862574)
		(stroke
			(width 0.0635)
			(type default)
		)
		(layer "B.Cu")
	)
	(gr_line
		(start 49.658016 -4.56565)
		(end 49.803812 -4.761992)
		(stroke
			(width 0.0635)
			(type default)
		)
		(layer "B.Cu")
	)
	(gr_line
		(start 49.669954 6.36778)
		(end 49.712626 6.608318)
		(stroke
			(width 0.0635)
			(type default)
		)
		(layer "B.Cu")
	)
	(gr_line
		(start 49.669954 6.36778)
		(end 49.888648 6.055868)
		(stroke
			(width 0.0635)
			(type default)
		)
		(layer "B.Cu")
	)
	(gr_line
		(start 49.747932 -5.138928)
		(end 49.803812 -4.761992)
		(stroke
			(width 0.0635)
			(type default)
		)
		(layer "B.Cu")
	)
	(gr_line
		(start 49.888648 6.055868)
		(end 50.129186 6.013196)
		(stroke
			(width 0.0635)
			(type default)
		)
		(layer "B.Cu")
	)
	(gr_line
		(start 49.985168 6.754876)
		(end 50.359564 6.220206)
		(stroke
			(width 0.0635)
			(type default)
		)
		(layer "B.Cu")
	)
	(gr_line
		(start 50.132742 6.012688)
		(end 50.752502 5.127498)
		(stroke
			(width 0.0635)
			(type default)
		)
		(layer "B.Cu")
	)
	(gr_line
		(start 50.380138 6.190742)
		(end 51.002184 5.30225)
		(stroke
			(width 0.0635)
			(type default)
		)
		(layer "B.Cu")
	)
	(gr_arc
		(start 50.779934 11.015472)
		(mid 50.812156 10.85366)
		(end 50.903886 10.716514)
		(stroke
			(width 0.0635)
			(type default)
		)
		(layer "B.Cu")
	)
	(gr_line
		(start 50.779934 12.514072)
		(end 50.779934 11.015472)
		(stroke
			(width 0.0635)
			(type default)
		)
		(layer "B.Cu")
	)
	(gr_line
		(start 50.93462 9.327134)
		(end 50.93716 9.312148)
		(stroke
			(width 0.0635)
			(type default)
		)
		(layer "B.Cu")
	)
	(gr_line
		(start 50.93462 9.327134)
		(end 50.937414 9.342882)
		(stroke
			(width 0.0635)
			(type default)
		)
		(layer "B.Cu")
	)
	(gr_line
		(start 50.950114 -23.43658)
		(end 50.993294 -23.404068)
		(stroke
			(width 0.0635)
			(type default)
		)
		(layer "B.Cu")
	)
	(gr_line
		(start 50.993294 -23.404068)
		(end 51.011074 -23.353522)
		(stroke
			(width 0.0635)
			(type default)
		)
		(layer "B.Cu")
	)
	(gr_arc
		(start 51.027584 10.41781)
		(mid 50.995453 10.579469)
		(end 50.903886 10.716514)
		(stroke
			(width 0.0635)
			(type default)
		)
		(layer "B.Cu")
	)
	(gr_line
		(start 51.027584 10.41781)
		(end 51.028092 10.417302)
		(stroke
			(width 0.0635)
			(type default)
		)
		(layer "B.Cu")
	)
	(gr_line
		(start 51.028092 10.417302)
		(end 51.0286 10.41019)
		(stroke
			(width 0.0635)
			(type default)
		)
		(layer "B.Cu")
	)
	(gr_line
		(start 51.17719 7.950454)
		(end 51.18227 7.92226)
		(stroke
			(width 0.0635)
			(type default)
		)
		(layer "B.Cu")
	)
	(gr_line
		(start 51.18227 7.92226)
		(end 51.198272 7.899654)
		(stroke
			(width 0.0635)
			(type default)
		)
		(layer "B.Cu")
	)
	(gr_line
		(start 51.303682 -22.528784)
		(end 51.308 -22.516338)
		(stroke
			(width 0.0635)
			(type default)
		)
		(layer "B.Cu")
	)
	(gr_line
		(start 51.331876 10.440924)
		(end 51.33213 10.44067)
		(stroke
			(width 0.0635)
			(type default)
		)
		(layer "B.Cu")
	)
	(gr_line
		(start 51.332384 10.441178)
		(end 51.332638 10.440924)
		(stroke
			(width 0.0635)
			(type default)
		)
		(layer "B.Cu")
	)
	(gr_line
		(start 51.357784 7.366)
		(end 51.400202 7.606792)
		(stroke
			(width 0.0635)
			(type default)
		)
		(layer "B.Cu")
	)
	(gr_line
		(start 51.357784 7.366)
		(end 51.576224 7.054088)
		(stroke
			(width 0.0635)
			(type default)
		)
		(layer "B.Cu")
	)
	(gr_arc
		(start 51.456082 10.739882)
		(mid 51.36451 10.602835)
		(end 51.332384 10.441178)
		(stroke
			(width 0.0635)
			(type default)
		)
		(layer "B.Cu")
	)
	(gr_arc
		(start 51.456082 10.739882)
		(mid 51.547621 10.876938)
		(end 51.57978 11.038586)
		(stroke
			(width 0.0635)
			(type default)
		)
		(layer "B.Cu")
	)
	(gr_line
		(start 51.576224 7.054088)
		(end 51.817016 7.011416)
		(stroke
			(width 0.0635)
			(type default)
		)
		(layer "B.Cu")
	)
	(gr_line
		(start 51.57978 12.514072)
		(end 51.57978 11.038586)
		(stroke
			(width 0.0635)
			(type default)
		)
		(layer "B.Cu")
	)
	(gr_line
		(start 51.67249 7.753604)
		(end 52.047394 7.218172)
		(stroke
			(width 0.0635)
			(type default)
		)
		(layer "B.Cu")
	)
	(gr_line
		(start 51.926998 -1.670812)
		(end 51.933856 -1.680972)
		(stroke
			(width 0.0635)
			(type default)
		)
		(layer "B.Cu")
	)
	(gr_line
		(start 51.933856 -1.680972)
		(end 51.937158 -1.692656)
		(stroke
			(width 0.0635)
			(type default)
		)
		(layer "B.Cu")
	)
	(gr_line
		(start 51.995832 6.454648)
		(end 52.03825 6.69544)
		(stroke
			(width 0.0635)
			(type default)
		)
		(layer "B.Cu")
	)
	(gr_line
		(start 51.995832 6.454648)
		(end 52.214272 6.142736)
		(stroke
			(width 0.0635)
			(type default)
		)
		(layer "B.Cu")
	)
	(gr_line
		(start 52.214272 6.142736)
		(end 52.455064 6.100064)
		(stroke
			(width 0.0635)
			(type default)
		)
		(layer "B.Cu")
	)
	(gr_line
		(start 52.257198 -4.727702)
		(end 52.356258 -5.095494)
		(stroke
			(width 0.0635)
			(type default)
		)
		(layer "B.Cu")
	)
	(gr_line
		(start 52.257198 -4.727702)
		(end 52.379118 -4.515866)
		(stroke
			(width 0.0635)
			(type default)
		)
		(layer "B.Cu")
	)
	(gr_line
		(start 52.310792 6.841998)
		(end 52.685696 6.306312)
		(stroke
			(width 0.0635)
			(type default)
		)
		(layer "B.Cu")
	)
	(gr_line
		(start 52.356258 -5.095494)
		(end 52.568094 -5.217414)
		(stroke
			(width 0.0635)
			(type default)
		)
		(layer "B.Cu")
	)
	(gr_line
		(start 52.546504 -5.801868)
		(end 52.645564 -6.16966)
		(stroke
			(width 0.0635)
			(type default)
		)
		(layer "B.Cu")
	)
	(gr_line
		(start 52.546504 -5.801868)
		(end 52.668424 -5.589778)
		(stroke
			(width 0.0635)
			(type default)
		)
		(layer "B.Cu")
	)
	(gr_line
		(start 52.645564 -6.16966)
		(end 52.857654 -6.29158)
		(stroke
			(width 0.0635)
			(type default)
		)
		(layer "B.Cu")
	)
	(gr_line
		(start 52.685442 -4.471924)
		(end 52.855114 -5.10159)
		(stroke
			(width 0.0635)
			(type default)
		)
		(layer "B.Cu")
	)
	(gr_line
		(start 52.974748 -5.545582)
		(end 53.144674 -6.176518)
		(stroke
			(width 0.0635)
			(type default)
		)
		(layer "B.Cu")
	)
	(gr_line
		(start 53.080412 -11.749786)
		(end 53.239162 -12.093702)
		(stroke
			(width 0.0635)
			(type default)
		)
		(layer "B.Cu")
	)
	(gr_arc
		(start 53.17998 11.079226)
		(mid 53.212236 10.917536)
		(end 53.303932 10.780522)
		(stroke
			(width 0.0635)
			(type default)
		)
		(layer "B.Cu")
	)
	(gr_line
		(start 53.17998 12.514072)
		(end 53.17998 11.079226)
		(stroke
			(width 0.0635)
			(type default)
		)
		(layer "B.Cu")
	)
	(gr_line
		(start 53.239162 -12.093702)
		(end 53.453538 -12.524486)
		(stroke
			(width 0.0635)
			(type default)
		)
		(layer "B.Cu")
	)
	(gr_line
		(start 53.276246 -6.665976)
		(end 53.2765 -6.666484)
		(stroke
			(width 0.0635)
			(type default)
		)
		(layer "B.Cu")
	)
	(gr_line
		(start 53.302408 9.753092)
		(end 53.304948 9.738614)
		(stroke
			(width 0.0635)
			(type default)
		)
		(layer "B.Cu")
	)
	(gr_line
		(start 53.302408 9.753092)
		(end 53.305202 9.769348)
		(stroke
			(width 0.0635)
			(type default)
		)
		(layer "B.Cu")
	)
	(gr_line
		(start 53.303932 10.780522)
		(end 53.304186 10.780268)
		(stroke
			(width 0.0635)
			(type default)
		)
		(layer "B.Cu")
	)
	(gr_line
		(start 53.426868 10.464546)
		(end 53.4289 10.476738)
		(stroke
			(width 0.0635)
			(type default)
		)
		(layer "B.Cu")
	)
	(gr_arc
		(start 53.42763 10.481818)
		(mid 53.395562 10.643306)
		(end 53.304186 10.780268)
		(stroke
			(width 0.0635)
			(type default)
		)
		(layer "B.Cu")
	)
	(gr_line
		(start 53.42763 10.481818)
		(end 53.429408 10.479024)
		(stroke
			(width 0.0635)
			(type default)
		)
		(layer "B.Cu")
	)
	(gr_line
		(start 53.4289 10.476738)
		(end 53.429408 10.479024)
		(stroke
			(width 0.0635)
			(type default)
		)
		(layer "B.Cu")
	)
	(gr_line
		(start 53.452776 8.900668)
		(end 53.457856 8.87222)
		(stroke
			(width 0.0635)
			(type default)
		)
		(layer "B.Cu")
	)
	(gr_arc
		(start 53.453538 -12.524486)
		(mid 53.526936 -12.58836)
		(end 53.623972 -12.581382)
		(stroke
			(width 0.0635)
			(type default)
		)
		(layer "B.Cu")
	)
	(gr_line
		(start 53.457856 8.87222)
		(end 53.473858 8.849614)
		(stroke
			(width 0.0635)
			(type default)
		)
		(layer "B.Cu")
	)
	(gr_line
		(start 53.623972 -12.581382)
		(end 53.624226 -12.581382)
		(stroke
			(width 0.0635)
			(type default)
		)
		(layer "B.Cu")
	)
	(gr_line
		(start 53.624226 -12.581382)
		(end 53.628798 -12.579096)
		(stroke
			(width 0.0635)
			(type default)
		)
		(layer "B.Cu")
	)
	(gr_line
		(start 53.63337 8.31596)
		(end 53.675788 8.556752)
		(stroke
			(width 0.0635)
			(type default)
		)
		(layer "B.Cu")
	)
	(gr_line
		(start 53.63337 8.31596)
		(end 53.85181 8.004048)
		(stroke
			(width 0.0635)
			(type default)
		)
		(layer "B.Cu")
	)
	(gr_line
		(start 53.703728 -13.024358)
		(end 53.964078 -13.543788)
		(stroke
			(width 0.0635)
			(type default)
		)
		(layer "B.Cu")
	)
	(gr_line
		(start 53.727096 10.412222)
		(end 53.729128 10.42416)
		(stroke
			(width 0.0635)
			(type default)
		)
		(layer "B.Cu")
	)
	(gr_line
		(start 53.729128 10.42416)
		(end 53.729636 10.426446)
		(stroke
			(width 0.0635)
			(type default)
		)
		(layer "B.Cu")
	)
	(gr_line
		(start 53.729636 10.426446)
		(end 53.73243 10.428224)
		(stroke
			(width 0.0635)
			(type default)
		)
		(layer "B.Cu")
	)
	(gr_arc
		(start 53.760624 -12.853924)
		(mid 53.696861 -12.927377)
		(end 53.703728 -13.024358)
		(stroke
			(width 0.0635)
			(type default)
		)
		(layer "B.Cu")
	)
	(gr_line
		(start 53.760624 -12.853924)
		(end 53.760878 -12.853924)
		(stroke
			(width 0.0635)
			(type default)
		)
		(layer "B.Cu")
	)
	(gr_line
		(start 53.85181 8.004048)
		(end 54.092602 7.961376)
		(stroke
			(width 0.0635)
			(type default)
		)
		(layer "B.Cu")
	)
	(gr_arc
		(start 53.856128 10.726928)
		(mid 53.764556 10.589881)
		(end 53.73243 10.428224)
		(stroke
			(width 0.0635)
			(type default)
		)
		(layer "B.Cu")
	)
	(gr_arc
		(start 53.856128 10.726928)
		(mid 53.947674 10.863983)
		(end 53.979826 11.025632)
		(stroke
			(width 0.0635)
			(type default)
		)
		(layer "B.Cu")
	)
	(gr_line
		(start 53.94833 8.70331)
		(end 54.32298 8.167878)
		(stroke
			(width 0.0635)
			(type default)
		)
		(layer "B.Cu")
	)
	(gr_line
		(start 53.964078 -13.543788)
		(end 54.079902 -13.750036)
		(stroke
			(width 0.0635)
			(type default)
		)
		(layer "B.Cu")
	)
	(gr_line
		(start 53.979826 12.514072)
		(end 53.979826 11.025632)
		(stroke
			(width 0.0635)
			(type default)
		)
		(layer "B.Cu")
	)
	(gr_line
		(start 54.271418 7.404608)
		(end 54.31409 7.645146)
		(stroke
			(width 0.0635)
			(type default)
		)
		(layer "B.Cu")
	)
	(gr_line
		(start 54.271418 7.404608)
		(end 54.489858 7.092696)
		(stroke
			(width 0.0635)
			(type default)
		)
		(layer "B.Cu")
	)
	(gr_line
		(start 54.489858 7.092696)
		(end 54.73065 7.050024)
		(stroke
			(width 0.0635)
			(type default)
		)
		(layer "B.Cu")
	)
	(gr_line
		(start 54.586886 7.79145)
		(end 54.962044 7.25551)
		(stroke
			(width 0.0635)
			(type default)
		)
		(layer "B.Cu")
	)
	(gr_arc
		(start 55.580026 11.01598)
		(mid 55.612179 10.854334)
		(end 55.703724 10.717276)
		(stroke
			(width 0.0635)
			(type default)
		)
		(layer "B.Cu")
	)
	(gr_line
		(start 55.580026 12.514072)
		(end 55.580026 11.01598)
		(stroke
			(width 0.0635)
			(type default)
		)
		(layer "B.Cu")
	)
	(gr_line
		(start 55.799736 1.32461)
		(end 55.808626 1.31191)
		(stroke
			(width 0.0635)
			(type default)
		)
		(layer "B.Cu")
	)
	(gr_line
		(start 55.808626 1.31191)
		(end 55.821326 1.30302)
		(stroke
			(width 0.0635)
			(type default)
		)
		(layer "B.Cu")
	)
	(gr_arc
		(start 55.827676 10.418064)
		(mid 55.79545 10.579995)
		(end 55.703724 10.717276)
		(stroke
			(width 0.0635)
			(type default)
		)
		(layer "B.Cu")
	)
	(gr_line
		(start 55.997094 -2.362708)
		(end 56.005984 -2.375408)
		(stroke
			(width 0.0635)
			(type default)
		)
		(layer "B.Cu")
	)
	(gr_line
		(start 56.005984 -2.375408)
		(end 56.018684 -2.384298)
		(stroke
			(width 0.0635)
			(type default)
		)
		(layer "B.Cu")
	)
	(gr_line
		(start 56.172862 8.09625)
		(end 56.21528 8.337296)
		(stroke
			(width 0.0635)
			(type default)
		)
		(layer "B.Cu")
	)
	(gr_line
		(start 56.172862 8.09625)
		(end 56.391302 7.784338)
		(stroke
			(width 0.0635)
			(type default)
		)
		(layer "B.Cu")
	)
	(gr_arc
		(start 56.256174 10.739374)
		(mid 56.164602 10.602327)
		(end 56.132476 10.44067)
		(stroke
			(width 0.0635)
			(type default)
		)
		(layer "B.Cu")
	)
	(gr_arc
		(start 56.256174 10.739374)
		(mid 56.347717 10.876429)
		(end 56.379872 11.038078)
		(stroke
			(width 0.0635)
			(type default)
		)
		(layer "B.Cu")
	)
	(gr_line
		(start 56.379872 12.514072)
		(end 56.379872 11.038078)
		(stroke
			(width 0.0635)
			(type default)
		)
		(layer "B.Cu")
	)
	(gr_line
		(start 56.391302 7.784338)
		(end 56.632348 7.741666)
		(stroke
			(width 0.0635)
			(type default)
		)
		(layer "B.Cu")
	)
	(gr_line
		(start 56.486298 8.486394)
		(end 56.864758 7.945882)
		(stroke
			(width 0.0635)
			(type default)
		)
		(layer "B.Cu")
	)
	(gr_line
		(start 56.81091 7.184898)
		(end 56.853582 7.425944)
		(stroke
			(width 0.0635)
			(type default)
		)
		(layer "B.Cu")
	)
	(gr_line
		(start 56.81091 7.184898)
		(end 57.02935 6.872986)
		(stroke
			(width 0.0635)
			(type default)
		)
		(layer "B.Cu")
	)
	(gr_line
		(start 56.813958 4.078986)
		(end 56.822848 4.066286)
		(stroke
			(width 0.0635)
			(type default)
		)
		(layer "B.Cu")
	)
	(gr_line
		(start 56.822848 4.066286)
		(end 56.835548 4.057396)
		(stroke
			(width 0.0635)
			(type default)
		)
		(layer "B.Cu")
	)
	(gr_line
		(start 56.899556 -7.306564)
		(end 56.89981 -7.30631)
		(stroke
			(width 0.0635)
			(type default)
		)
		(layer "B.Cu")
	)
	(gr_line
		(start 56.89981 -7.30631)
		(end 56.900064 -7.30631)
		(stroke
			(width 0.0635)
			(type default)
		)
		(layer "B.Cu")
	)
	(gr_line
		(start 56.900064 -7.30631)
		(end 56.900318 -7.306056)
		(stroke
			(width 0.0635)
			(type default)
		)
		(layer "B.Cu")
	)
	(gr_line
		(start 56.900318 -7.306056)
		(end 56.900826 -7.298944)
		(stroke
			(width 0.0635)
			(type default)
		)
		(layer "B.Cu")
	)
	(gr_line
		(start 57.02935 6.872986)
		(end 57.270396 6.830314)
		(stroke
			(width 0.0635)
			(type default)
		)
		(layer "B.Cu")
	)
	(gr_line
		(start 57.079642 -11.749786)
		(end 57.242964 -12.102846)
		(stroke
			(width 0.0635)
			(type default)
		)
		(layer "B.Cu")
	)
	(gr_line
		(start 57.107836 -6.563614)
		(end 57.112408 -6.571996)
		(stroke
			(width 0.0635)
			(type default)
		)
		(layer "B.Cu")
	)
	(gr_line
		(start 57.112408 -6.571996)
		(end 57.114186 -6.581902)
		(stroke
			(width 0.0635)
			(type default)
		)
		(layer "B.Cu")
	)
	(gr_line
		(start 57.125362 7.573518)
		(end 57.502552 7.034784)
		(stroke
			(width 0.0635)
			(type default)
		)
		(layer "B.Cu")
	)
	(gr_line
		(start 57.204102 -7.329678)
		(end 57.204356 -7.329424)
		(stroke
			(width 0.0635)
			(type default)
		)
		(layer "B.Cu")
	)
	(gr_line
		(start 57.204102 -7.329678)
		(end 57.20461 -7.329678)
		(stroke
			(width 0.0635)
			(type default)
		)
		(layer "B.Cu")
	)
	(gr_line
		(start 57.204356 -7.329932)
		(end 57.20461 -7.329678)
		(stroke
			(width 0.0635)
			(type default)
		)
		(layer "B.Cu")
	)
	(gr_line
		(start 57.216802 -7.163308)
		(end 57.217056 -7.163816)
		(stroke
			(width 0.0635)
			(type default)
		)
		(layer "B.Cu")
	)
	(gr_line
		(start 57.217056 -7.163816)
		(end 57.217056 -7.164832)
		(stroke
			(width 0.0635)
			(type default)
		)
		(layer "B.Cu")
	)
	(gr_line
		(start 57.242964 -12.102846)
		(end 57.452768 -12.524486)
		(stroke
			(width 0.0635)
			(type default)
		)
		(layer "B.Cu")
	)
	(gr_arc
		(start 57.452768 -12.524486)
		(mid 57.526182 -12.588215)
		(end 57.623202 -12.581382)
		(stroke
			(width 0.0635)
			(type default)
		)
		(layer "B.Cu")
	)
	(gr_line
		(start 57.623202 -12.581382)
		(end 57.623456 -12.581382)
		(stroke
			(width 0.0635)
			(type default)
		)
		(layer "B.Cu")
	)
	(gr_line
		(start 57.623456 -12.581382)
		(end 57.628028 -12.579096)
		(stroke
			(width 0.0635)
			(type default)
		)
		(layer "B.Cu")
	)
	(gr_line
		(start 57.702958 -13.024358)
		(end 57.907936 -13.432028)
		(stroke
			(width 0.0635)
			(type default)
		)
		(layer "B.Cu")
	)
	(gr_arc
		(start 57.759854 -12.853924)
		(mid 57.696091 -12.927377)
		(end 57.702958 -13.024358)
		(stroke
			(width 0.0635)
			(type default)
		)
		(layer "B.Cu")
	)
	(gr_line
		(start 57.759854 -12.853924)
		(end 57.760108 -12.853924)
		(stroke
			(width 0.0635)
			(type default)
		)
		(layer "B.Cu")
	)
	(gr_line
		(start 57.907936 -13.432028)
		(end 58.080402 -13.750036)
		(stroke
			(width 0.0635)
			(type default)
		)
		(layer "B.Cu")
	)
	(gr_arc
		(start 57.979818 11.054588)
		(mid 58.011961 10.892816)
		(end 58.103516 10.75563)
		(stroke
			(width 0.0635)
			(type default)
		)
		(layer "B.Cu")
	)
	(gr_line
		(start 57.979818 12.514072)
		(end 57.979818 11.054588)
		(stroke
			(width 0.0635)
			(type default)
		)
		(layer "B.Cu")
	)
	(gr_line
		(start 58.103516 10.75563)
		(end 58.1406 10.718546)
		(stroke
			(width 0.0635)
			(type default)
		)
		(layer "B.Cu")
	)
	(gr_line
		(start 58.227468 9.000236)
		(end 58.259472 8.954008)
		(stroke
			(width 0.0635)
			(type default)
		)
		(layer "B.Cu")
	)
	(gr_arc
		(start 58.227468 10.50925)
		(mid 58.204884 10.622554)
		(end 58.1406 10.718546)
		(stroke
			(width 0.0635)
			(type default)
		)
		(layer "B.Cu")
	)
	(gr_line
		(start 58.400442 8.443214)
		(end 58.44413 8.683498)
		(stroke
			(width 0.0635)
			(type default)
		)
		(layer "B.Cu")
	)
	(gr_line
		(start 58.400442 8.443214)
		(end 58.617358 8.130032)
		(stroke
			(width 0.0635)
			(type default)
		)
		(layer "B.Cu")
	)
	(gr_line
		(start 58.617358 8.130032)
		(end 58.857896 8.086344)
		(stroke
			(width 0.0635)
			(type default)
		)
		(layer "B.Cu")
	)
	(gr_arc
		(start 58.65622 10.72642)
		(mid 58.564463 10.589285)
		(end 58.532268 10.427462)
		(stroke
			(width 0.0635)
			(type default)
		)
		(layer "B.Cu")
	)
	(gr_arc
		(start 58.65622 10.72642)
		(mid 58.747771 10.863474)
		(end 58.779918 11.025124)
		(stroke
			(width 0.0635)
			(type default)
		)
		(layer "B.Cu")
	)
	(gr_line
		(start 58.717434 8.828786)
		(end 59.089798 8.291576)
		(stroke
			(width 0.0635)
			(type default)
		)
		(layer "B.Cu")
	)
	(gr_line
		(start 58.779918 12.514072)
		(end 58.779918 11.025124)
		(stroke
			(width 0.0635)
			(type default)
		)
		(layer "B.Cu")
	)
	(gr_line
		(start 59.034172 7.529068)
		(end 59.07786 7.769606)
		(stroke
			(width 0.0635)
			(type default)
		)
		(layer "B.Cu")
	)
	(gr_line
		(start 59.034172 7.529068)
		(end 59.251342 7.215886)
		(stroke
			(width 0.0635)
			(type default)
		)
		(layer "B.Cu")
	)
	(gr_line
		(start 59.251342 7.215886)
		(end 59.49188 7.172198)
		(stroke
			(width 0.0635)
			(type default)
		)
		(layer "B.Cu")
	)
	(gr_line
		(start 59.351418 7.914132)
		(end 59.723274 7.377684)
		(stroke
			(width 0.0635)
			(type default)
		)
		(layer "B.Cu")
	)
	(gr_line
		(start 60.200032 -4.939538)
		(end 60.212732 -4.948428)
		(stroke
			(width 0.0635)
			(type default)
		)
		(layer "B.Cu")
	)
	(gr_line
		(start 60.212732 -4.948428)
		(end 60.221622 -4.961128)
		(stroke
			(width 0.0635)
			(type default)
		)
		(layer "B.Cu")
	)
	(gr_arc
		(start 60.379864 11.016742)
		(mid 60.41212 10.855052)
		(end 60.503816 10.718038)
		(stroke
			(width 0.0635)
			(type default)
		)
		(layer "B.Cu")
	)
	(gr_line
		(start 60.379864 12.514072)
		(end 60.379864 11.016742)
		(stroke
			(width 0.0635)
			(type default)
		)
		(layer "B.Cu")
	)
	(gr_line
		(start 60.503816 10.718038)
		(end 60.50407 10.717784)
		(stroke
			(width 0.0635)
			(type default)
		)
		(layer "B.Cu")
	)
	(gr_arc
		(start 60.627514 10.419334)
		(mid 60.59544 10.580818)
		(end 60.50407 10.717784)
		(stroke
			(width 0.0635)
			(type default)
		)
		(layer "B.Cu")
	)
	(gr_line
		(start 60.879228 8.221726)
		(end 60.884308 8.193532)
		(stroke
			(width 0.0635)
			(type default)
		)
		(layer "B.Cu")
	)
	(gr_line
		(start 60.884308 8.193532)
		(end 60.900564 8.170164)
		(stroke
			(width 0.0635)
			(type default)
		)
		(layer "B.Cu")
	)
	(gr_line
		(start 61.035184 7.97814)
		(end 61.145166 7.820914)
		(stroke
			(width 0.0635)
			(type default)
		)
		(layer "B.Cu")
	)
	(gr_arc
		(start 61.056012 10.764012)
		(mid 60.96444 10.626965)
		(end 60.932314 10.465308)
		(stroke
			(width 0.0635)
			(type default)
		)
		(layer "B.Cu")
	)
	(gr_arc
		(start 61.056012 10.764012)
		(mid 61.147753 10.901287)
		(end 61.179964 11.063224)
		(stroke
			(width 0.0635)
			(type default)
		)
		(layer "B.Cu")
	)
	(gr_line
		(start 61.080142 -11.749786)
		(end 61.453268 -12.524486)
		(stroke
			(width 0.0635)
			(type default)
		)
		(layer "B.Cu")
	)
	(gr_line
		(start 61.121544 -6.246114)
		(end 61.1378 -6.269482)
		(stroke
			(width 0.0635)
			(type default)
		)
		(layer "B.Cu")
	)
	(gr_line
		(start 61.1378 -6.269482)
		(end 61.14288 -6.297676)
		(stroke
			(width 0.0635)
			(type default)
		)
		(layer "B.Cu")
	)
	(gr_line
		(start 61.164216 7.793482)
		(end 61.538612 7.258812)
		(stroke
			(width 0.0635)
			(type default)
		)
		(layer "B.Cu")
	)
	(gr_line
		(start 61.179964 12.514072)
		(end 61.179964 11.063224)
		(stroke
			(width 0.0635)
			(type default)
		)
		(layer "B.Cu")
	)
	(gr_line
		(start 61.254386 8.196326)
		(end 61.391292 8.000746)
		(stroke
			(width 0.0635)
			(type default)
		)
		(layer "B.Cu")
	)
	(gr_line
		(start 61.260228 -6.964172)
		(end 61.262768 -6.977888)
		(stroke
			(width 0.0635)
			(type default)
		)
		(layer "B.Cu")
	)
	(gr_line
		(start 61.260482 -6.99135)
		(end 61.262768 -6.977888)
		(stroke
			(width 0.0635)
			(type default)
		)
		(layer "B.Cu")
	)
	(gr_line
		(start 61.394848 7.999984)
		(end 61.635386 7.95782)
		(stroke
			(width 0.0635)
			(type default)
		)
		(layer "B.Cu")
	)
	(gr_line
		(start 61.452506 -8.478774)
		(end 61.45276 -8.479028)
		(stroke
			(width 0.0635)
			(type default)
		)
		(layer "B.Cu")
	)
	(gr_arc
		(start 61.453268 -12.524486)
		(mid 61.526663 -12.588341)
		(end 61.623702 -12.581382)
		(stroke
			(width 0.0635)
			(type default)
		)
		(layer "B.Cu")
	)
	(gr_line
		(start 61.623702 -12.581382)
		(end 61.623956 -12.581382)
		(stroke
			(width 0.0635)
			(type default)
		)
		(layer "B.Cu")
	)
	(gr_line
		(start 61.623956 -12.581382)
		(end 61.628528 -12.579096)
		(stroke
			(width 0.0635)
			(type default)
		)
		(layer "B.Cu")
	)
	(gr_line
		(start 61.635386 7.95782)
		(end 61.85408 7.645654)
		(stroke
			(width 0.0635)
			(type default)
		)
		(layer "B.Cu")
	)
	(gr_line
		(start 61.703458 -13.024358)
		(end 62.079632 -13.750036)
		(stroke
			(width 0.0635)
			(type default)
		)
		(layer "B.Cu")
	)
	(gr_arc
		(start 61.760354 -12.853924)
		(mid 61.696591 -12.927377)
		(end 61.703458 -13.024358)
		(stroke
			(width 0.0635)
			(type default)
		)
		(layer "B.Cu")
	)
	(gr_line
		(start 61.760354 -12.853924)
		(end 61.760608 -12.853924)
		(stroke
			(width 0.0635)
			(type default)
		)
		(layer "B.Cu")
	)
	(gr_line
		(start 61.801756 6.883146)
		(end 62.177676 6.34619)
		(stroke
			(width 0.0635)
			(type default)
		)
		(layer "B.Cu")
	)
	(gr_line
		(start 61.811408 7.405116)
		(end 61.85408 7.645654)
		(stroke
			(width 0.0635)
			(type default)
		)
		(layer "B.Cu")
	)
	(gr_line
		(start 62.032896 7.088886)
		(end 62.273688 7.046468)
		(stroke
			(width 0.0635)
			(type default)
		)
		(layer "B.Cu")
	)
	(gr_line
		(start 62.054994 3.504946)
		(end 62.063884 3.492246)
		(stroke
			(width 0.0635)
			(type default)
		)
		(layer "B.Cu")
	)
	(gr_line
		(start 62.063884 3.492246)
		(end 62.076584 3.483356)
		(stroke
			(width 0.0635)
			(type default)
		)
		(layer "B.Cu")
	)
	(gr_line
		(start 62.273688 7.046468)
		(end 62.492128 6.734302)
		(stroke
			(width 0.0635)
			(type default)
		)
		(layer "B.Cu")
	)
	(gr_line
		(start 62.44971 6.49351)
		(end 62.492128 6.734302)
		(stroke
			(width 0.0635)
			(type default)
		)
		(layer "B.Cu")
	)
	(gr_arc
		(start 62.77991 11.004296)
		(mid 62.812063 10.84265)
		(end 62.903608 10.705592)
		(stroke
			(width 0.0635)
			(type default)
		)
		(layer "B.Cu")
	)
	(gr_line
		(start 62.77991 12.514072)
		(end 62.77991 11.004296)
		(stroke
			(width 0.0635)
			(type default)
		)
		(layer "B.Cu")
	)
	(gr_arc
		(start 63.02756 10.40638)
		(mid 62.995328 10.568306)
		(end 62.903608 10.705592)
		(stroke
			(width 0.0635)
			(type default)
		)
		(layer "B.Cu")
	)
	(gr_line
		(start 63.240412 8.289036)
		(end 63.245492 8.260842)
		(stroke
			(width 0.0635)
			(type default)
		)
		(layer "B.Cu")
	)
	(gr_line
		(start 63.245492 8.260842)
		(end 63.261748 8.237474)
		(stroke
			(width 0.0635)
			(type default)
		)
		(layer "B.Cu")
	)
	(gr_line
		(start 63.396368 8.04545)
		(end 63.50635 7.88797)
		(stroke
			(width 0.0635)
			(type default)
		)
		(layer "B.Cu")
	)
	(gr_arc
		(start 63.456312 10.725912)
		(mid 63.364555 10.588777)
		(end 63.33236 10.426954)
		(stroke
			(width 0.0635)
			(type default)
		)
		(layer "B.Cu")
	)
	(gr_arc
		(start 63.456312 10.725912)
		(mid 63.547867 10.862965)
		(end 63.58001 11.024616)
		(stroke
			(width 0.0635)
			(type default)
		)
		(layer "B.Cu")
	)
	(gr_line
		(start 63.526416 7.86003)
		(end 63.899796 7.326376)
		(stroke
			(width 0.0635)
			(type default)
		)
		(layer "B.Cu")
	)
	(gr_line
		(start 63.58001 12.514072)
		(end 63.58001 11.024616)
		(stroke
			(width 0.0635)
			(type default)
		)
		(layer "B.Cu")
	)
	(gr_line
		(start 63.635128 8.235696)
		(end 63.752476 8.068056)
		(stroke
			(width 0.0635)
			(type default)
		)
		(layer "B.Cu")
	)
	(gr_line
		(start 63.756032 8.067548)
		(end 63.99657 8.02513)
		(stroke
			(width 0.0635)
			(type default)
		)
		(layer "B.Cu")
	)
	(gr_line
		(start 63.919862 7.297674)
		(end 64.143382 6.978142)
		(stroke
			(width 0.0635)
			(type default)
		)
		(layer "B.Cu")
	)
	(gr_line
		(start 63.99657 8.02513)
		(end 64.215264 7.712964)
		(stroke
			(width 0.0635)
			(type default)
		)
		(layer "B.Cu")
	)
	(gr_line
		(start 64.079882 -34.070036)
		(end 64.463422 -33.302702)
		(stroke
			(width 0.05715)
			(type default)
		)
		(layer "B.Cu")
	)
	(gr_line
		(start 64.079882 -13.750036)
		(end 64.463422 -12.982702)
		(stroke
			(width 0.05715)
			(type default)
		)
		(layer "B.Cu")
	)
	(gr_line
		(start 64.154812 -32.336232)
		(end 64.154812 -32.336486)
		(stroke
			(width 0.05715)
			(type default)
		)
		(layer "B.Cu")
	)
	(gr_line
		(start 64.163956 6.948932)
		(end 64.538098 6.414516)
		(stroke
			(width 0.0635)
			(type default)
		)
		(layer "B.Cu")
	)
	(gr_line
		(start 64.172592 7.472426)
		(end 64.215264 7.712964)
		(stroke
			(width 0.0635)
			(type default)
		)
		(layer "B.Cu")
	)
	(gr_line
		(start 64.207136 3.447796)
		(end 64.21628 3.434588)
		(stroke
			(width 0.0635)
			(type default)
		)
		(layer "B.Cu")
	)
	(gr_line
		(start 64.21628 3.434588)
		(end 64.229996 3.424936)
		(stroke
			(width 0.0635)
			(type default)
		)
		(layer "B.Cu")
	)
	(gr_line
		(start 64.304672 7.279386)
		(end 64.390524 7.156704)
		(stroke
			(width 0.0635)
			(type default)
		)
		(layer "B.Cu")
	)
	(gr_line
		(start 64.39408 7.156196)
		(end 64.634618 7.113778)
		(stroke
			(width 0.0635)
			(type default)
		)
		(layer "B.Cu")
	)
	(gr_arc
		(start 64.463422 -33.302702)
		(mid 64.469486 -33.215595)
		(end 64.412368 -33.14954)
		(stroke
			(width 0.05715)
			(type default)
		)
		(layer "B.Cu")
	)
	(gr_line
		(start 64.463422 -12.982702)
		(end 64.613536 -12.932918)
		(stroke
			(width 0.05715)
			(type default)
		)
		(layer "B.Cu")
	)
	(gr_arc
		(start 64.542416 -32.887666)
		(mid 64.629753 -32.894004)
		(end 64.695832 -32.836612)
		(stroke
			(width 0.05715)
			(type default)
		)
		(layer "B.Cu")
	)
	(gr_line
		(start 64.634618 7.113778)
		(end 64.853312 6.801612)
		(stroke
			(width 0.0635)
			(type default)
		)
		(layer "B.Cu")
	)
	(gr_line
		(start 64.695832 -32.836612)
		(end 65.079372 -32.069786)
		(stroke
			(width 0.05715)
			(type default)
		)
		(layer "B.Cu")
	)
	(gr_line
		(start 64.695832 -12.516866)
		(end 64.746124 -12.667234)
		(stroke
			(width 0.05715)
			(type default)
		)
		(layer "B.Cu")
	)
	(gr_line
		(start 64.695832 -12.516866)
		(end 65.079372 -11.749786)
		(stroke
			(width 0.05715)
			(type default)
		)
		(layer "B.Cu")
	)
	(gr_line
		(start 64.81064 6.561074)
		(end 64.853312 6.801612)
		(stroke
			(width 0.0635)
			(type default)
		)
		(layer "B.Cu")
	)
	(gr_line
		(start 64.841882 -12.717526)
		(end 64.85001 -12.72159)
		(stroke
			(width 0.05715)
			(type default)
		)
		(layer "B.Cu")
	)
	(gr_arc
		(start 65.179956 11.06805)
		(mid 65.212212 10.90636)
		(end 65.303908 10.769346)
		(stroke
			(width 0.0635)
			(type default)
		)
		(layer "B.Cu")
	)
	(gr_line
		(start 65.179956 12.514072)
		(end 65.179956 11.06805)
		(stroke
			(width 0.0635)
			(type default)
		)
		(layer "B.Cu")
	)
	(gr_line
		(start 65.214754 -30.96514)
		(end 65.387474 -31.13786)
		(stroke
			(width 0.05715)
			(type default)
		)
		(layer "B.Cu")
	)
	(gr_line
		(start 65.303908 10.769346)
		(end 65.304162 10.769092)
		(stroke
			(width 0.0635)
			(type default)
		)
		(layer "B.Cu")
	)
	(gr_line
		(start 65.387474 -31.13786)
		(end 65.730374 -31.13786)
		(stroke
			(width 0.05715)
			(type default)
		)
		(layer "B.Cu")
	)
	(gr_arc
		(start 65.427606 10.470642)
		(mid 65.395561 10.632145)
		(end 65.304162 10.769092)
		(stroke
			(width 0.0635)
			(type default)
		)
		(layer "B.Cu")
	)
	(gr_line
		(start 65.506854 -30.6705)
		(end 65.610994 -30.6705)
		(stroke
			(width 0.05715)
			(type default)
		)
		(layer "B.Cu")
	)
	(gr_line
		(start 65.694052 8.08863)
		(end 65.699132 8.060436)
		(stroke
			(width 0.0635)
			(type default)
		)
		(layer "B.Cu")
	)
	(gr_line
		(start 65.699132 8.060436)
		(end 65.715388 8.037068)
		(stroke
			(width 0.0635)
			(type default)
		)
		(layer "B.Cu")
	)
	(gr_line
		(start 65.730374 -31.13786)
		(end 65.903094 -30.96514)
		(stroke
			(width 0.05715)
			(type default)
		)
		(layer "B.Cu")
	)
	(gr_line
		(start 65.817242 7.89178)
		(end 65.95999 7.687818)
		(stroke
			(width 0.0635)
			(type default)
		)
		(layer "B.Cu")
	)
	(gr_arc
		(start 65.856104 10.763504)
		(mid 65.764573 10.626447)
		(end 65.732406 10.4648)
		(stroke
			(width 0.0635)
			(type default)
		)
		(layer "B.Cu")
	)
	(gr_arc
		(start 65.856104 10.763504)
		(mid 65.947676 10.900551)
		(end 65.979802 11.062208)
		(stroke
			(width 0.0635)
			(type default)
		)
		(layer "B.Cu")
	)
	(gr_line
		(start 65.97904 7.66064)
		(end 66.353436 7.126224)
		(stroke
			(width 0.0635)
			(type default)
		)
		(layer "B.Cu")
	)
	(gr_line
		(start 65.979802 12.514072)
		(end 65.979802 11.062208)
		(stroke
			(width 0.0635)
			(type default)
		)
		(layer "B.Cu")
	)
	(gr_line
		(start 66.066924 8.066532)
		(end 66.206116 7.86765)
		(stroke
			(width 0.0635)
			(type default)
		)
		(layer "B.Cu")
	)
	(gr_line
		(start 66.209672 7.866888)
		(end 66.45021 7.824724)
		(stroke
			(width 0.0635)
			(type default)
		)
		(layer "B.Cu")
	)
	(gr_line
		(start 66.251074 -30.96514)
		(end 66.423794 -31.13786)
		(stroke
			(width 0.05715)
			(type default)
		)
		(layer "B.Cu")
	)
	(gr_line
		(start 66.423794 -31.13786)
		(end 66.766694 -31.13786)
		(stroke
			(width 0.05715)
			(type default)
		)
		(layer "B.Cu")
	)
	(gr_line
		(start 66.45021 7.824724)
		(end 66.668904 7.512558)
		(stroke
			(width 0.0635)
			(type default)
		)
		(layer "B.Cu")
	)
	(gr_line
		(start 66.543174 -30.6705)
		(end 66.647314 -30.6705)
		(stroke
			(width 0.05715)
			(type default)
		)
		(layer "B.Cu")
	)
	(gr_line
		(start 66.616072 -5.883402)
		(end 66.628772 -5.892292)
		(stroke
			(width 0.0635)
			(type default)
		)
		(layer "B.Cu")
	)
	(gr_line
		(start 66.617342 6.749288)
		(end 66.990214 6.216904)
		(stroke
			(width 0.0635)
			(type default)
		)
		(layer "B.Cu")
	)
	(gr_line
		(start 66.626232 7.27202)
		(end 66.668904 7.512558)
		(stroke
			(width 0.0635)
			(type default)
		)
		(layer "B.Cu")
	)
	(gr_line
		(start 66.628772 -5.892292)
		(end 66.637662 -5.904992)
		(stroke
			(width 0.0635)
			(type default)
		)
		(layer "B.Cu")
	)
	(gr_line
		(start 66.766694 -31.13786)
		(end 66.939414 -30.96514)
		(stroke
			(width 0.05715)
			(type default)
		)
		(layer "B.Cu")
	)
	(gr_line
		(start 66.802508 3.18008)
		(end 66.811398 3.16738)
		(stroke
			(width 0.0635)
			(type default)
		)
		(layer "B.Cu")
	)
	(gr_line
		(start 66.811398 3.16738)
		(end 66.824098 3.15849)
		(stroke
			(width 0.0635)
			(type default)
		)
		(layer "B.Cu")
	)
	(gr_line
		(start 66.84772 6.95579)
		(end 67.088512 6.913372)
		(stroke
			(width 0.0635)
			(type default)
		)
		(layer "B.Cu")
	)
	(gr_line
		(start 67.009772 6.18871)
		(end 67.015614 6.180074)
		(stroke
			(width 0.0635)
			(type default)
		)
		(layer "B.Cu")
	)
	(gr_line
		(start 67.079622 -11.749786)
		(end 67.138042 -11.89228)
		(stroke
			(width 0.0635)
			(type default)
		)
		(layer "B.Cu")
	)
	(gr_line
		(start 67.087242 -6.54685)
		(end 67.103498 -6.570218)
		(stroke
			(width 0.0635)
			(type default)
		)
		(layer "B.Cu")
	)
	(gr_line
		(start 67.088512 6.913372)
		(end 67.306952 6.601206)
		(stroke
			(width 0.0635)
			(type default)
		)
		(layer "B.Cu")
	)
	(gr_line
		(start 67.103498 -6.570218)
		(end 67.108578 -6.598412)
		(stroke
			(width 0.0635)
			(type default)
		)
		(layer "B.Cu")
	)
	(gr_line
		(start 67.138042 -11.89228)
		(end 67.452748 -12.524486)
		(stroke
			(width 0.0635)
			(type default)
		)
		(layer "B.Cu")
	)
	(gr_line
		(start 67.263772 6.357112)
		(end 67.691254 5.746496)
		(stroke
			(width 0.0635)
			(type default)
		)
		(layer "B.Cu")
	)
	(gr_line
		(start 67.26428 6.360668)
		(end 67.306952 6.601206)
		(stroke
			(width 0.0635)
			(type default)
		)
		(layer "B.Cu")
	)
	(gr_arc
		(start 67.452748 -12.524486)
		(mid 67.526145 -12.588354)
		(end 67.623182 -12.581382)
		(stroke
			(width 0.0635)
			(type default)
		)
		(layer "B.Cu")
	)
	(gr_arc
		(start 67.580002 11.081004)
		(mid 67.612134 10.919347)
		(end 67.7037 10.7823)
		(stroke
			(width 0.0635)
			(type default)
		)
		(layer "B.Cu")
	)
	(gr_line
		(start 67.580002 12.514072)
		(end 67.580002 11.081004)
		(stroke
			(width 0.0635)
			(type default)
		)
		(layer "B.Cu")
	)
	(gr_line
		(start 67.623182 -12.581382)
		(end 67.623436 -12.581382)
		(stroke
			(width 0.0635)
			(type default)
		)
		(layer "B.Cu")
	)
	(gr_line
		(start 67.623436 -12.581382)
		(end 67.628008 -12.579096)
		(stroke
			(width 0.0635)
			(type default)
		)
		(layer "B.Cu")
	)
	(gr_line
		(start 67.702938 -13.024358)
		(end 67.972432 -13.560044)
		(stroke
			(width 0.0635)
			(type default)
		)
		(layer "B.Cu")
	)
	(gr_line
		(start 67.725544 9.573768)
		(end 67.728084 9.558782)
		(stroke
			(width 0.0635)
			(type default)
		)
		(layer "B.Cu")
	)
	(gr_line
		(start 67.725544 9.573768)
		(end 67.728338 9.589516)
		(stroke
			(width 0.0635)
			(type default)
		)
		(layer "B.Cu")
	)
	(gr_arc
		(start 67.759834 -12.853924)
		(mid 67.696071 -12.927377)
		(end 67.702938 -13.024358)
		(stroke
			(width 0.0635)
			(type default)
		)
		(layer "B.Cu")
	)
	(gr_line
		(start 67.759834 -12.853924)
		(end 67.760088 -12.853924)
		(stroke
			(width 0.0635)
			(type default)
		)
		(layer "B.Cu")
	)
	(gr_arc
		(start 67.827652 10.483088)
		(mid 67.795441 10.645026)
		(end 67.7037 10.7823)
		(stroke
			(width 0.0635)
			(type default)
		)
		(layer "B.Cu")
	)
	(gr_line
		(start 67.972432 -13.560044)
		(end 68.080382 -13.750036)
		(stroke
			(width 0.0635)
			(type default)
		)
		(layer "B.Cu")
	)
	(gr_line
		(start 68.130674 7.276084)
		(end 68.135754 7.247636)
		(stroke
			(width 0.0635)
			(type default)
		)
		(layer "B.Cu")
	)
	(gr_line
		(start 68.135754 7.247636)
		(end 68.151756 7.22503)
		(stroke
			(width 0.0635)
			(type default)
		)
		(layer "B.Cu")
	)
	(gr_arc
		(start 68.25615 10.82675)
		(mid 68.164594 10.689698)
		(end 68.132452 10.528046)
		(stroke
			(width 0.0635)
			(type default)
		)
		(layer "B.Cu")
	)
	(gr_arc
		(start 68.25615 10.82675)
		(mid 68.347722 10.963797)
		(end 68.379848 11.125454)
		(stroke
			(width 0.0635)
			(type default)
		)
		(layer "B.Cu")
	)
	(gr_line
		(start 68.379848 12.514072)
		(end 68.379848 11.125454)
		(stroke
			(width 0.0635)
			(type default)
		)
		(layer "B.Cu")
	)
	(gr_line
		(start 68.3895 6.884924)
		(end 68.396612 6.875018)
		(stroke
			(width 0.0635)
			(type default)
		)
		(layer "B.Cu")
	)
	(gr_line
		(start 68.416932 6.846316)
		(end 68.789296 6.31444)
		(stroke
			(width 0.0635)
			(type default)
		)
		(layer "B.Cu")
	)
	(gr_line
		(start 68.50888 7.246366)
		(end 68.642738 7.05485)
		(stroke
			(width 0.0635)
			(type default)
		)
		(layer "B.Cu")
	)
	(gr_line
		(start 68.646294 7.054088)
		(end 68.886832 7.011924)
		(stroke
			(width 0.0635)
			(type default)
		)
		(layer "B.Cu")
	)
	(gr_line
		(start 68.886832 7.011924)
		(end 69.105526 6.699758)
		(stroke
			(width 0.0635)
			(type default)
		)
		(layer "B.Cu")
	)
	(gr_line
		(start 69.054472 5.935726)
		(end 69.42836 5.401818)
		(stroke
			(width 0.0635)
			(type default)
		)
		(layer "B.Cu")
	)
	(gr_line
		(start 69.062854 6.45922)
		(end 69.105526 6.699758)
		(stroke
			(width 0.0635)
			(type default)
		)
		(layer "B.Cu")
	)
	(gr_line
		(start 69.284342 6.14299)
		(end 69.525134 6.100572)
		(stroke
			(width 0.0635)
			(type default)
		)
		(layer "B.Cu")
	)
	(gr_line
		(start 69.313552 2.89814)
		(end 69.322442 2.88544)
		(stroke
			(width 0.0635)
			(type default)
		)
		(layer "B.Cu")
	)
	(gr_line
		(start 69.322442 2.88544)
		(end 69.335142 2.87655)
		(stroke
			(width 0.0635)
			(type default)
		)
		(layer "B.Cu")
	)
	(gr_line
		(start 69.525134 6.100572)
		(end 69.743574 5.788406)
		(stroke
			(width 0.0635)
			(type default)
		)
		(layer "B.Cu")
	)
	(gr_line
		(start 69.701156 5.547614)
		(end 69.743574 5.788406)
		(stroke
			(width 0.0635)
			(type default)
		)
		(layer "B.Cu")
	)
	(gr_arc
		(start 69.979794 11.119104)
		(mid 70.011888 10.957855)
		(end 70.103238 10.821162)
		(stroke
			(width 0.0635)
			(type default)
		)
		(layer "B.Cu")
	)
	(gr_line
		(start 69.979794 12.514072)
		(end 69.979794 11.119104)
		(stroke
			(width 0.0635)
			(type default)
		)
		(layer "B.Cu")
	)
	(gr_line
		(start 70.103238 10.821162)
		(end 70.141084 10.783316)
		(stroke
			(width 0.0635)
			(type default)
		)
		(layer "B.Cu")
	)
	(gr_line
		(start 70.108318 9.365488)
		(end 70.10908 9.373108)
		(stroke
			(width 0.0635)
			(type default)
		)
		(layer "B.Cu")
	)
	(gr_line
		(start 70.108318 9.365488)
		(end 70.109588 9.358122)
		(stroke
			(width 0.0635)
			(type default)
		)
		(layer "B.Cu")
	)
	(gr_line
		(start 70.19544 8.908796)
		(end 70.317868 8.266176)
		(stroke
			(width 0.0635)
			(type default)
		)
		(layer "B.Cu")
	)
	(gr_arc
		(start 70.226682 10.57656)
		(mid 70.204443 10.688453)
		(end 70.141084 10.783316)
		(stroke
			(width 0.0635)
			(type default)
		)
		(layer "B.Cu")
	)
	(gr_line
		(start 70.226682 10.57656)
		(end 70.226682 10.47115)
		(stroke
			(width 0.0635)
			(type default)
		)
		(layer "B.Cu")
	)
	(gr_line
		(start 70.404228 7.814818)
		(end 70.526148 7.175246)
		(stroke
			(width 0.0635)
			(type default)
		)
		(layer "B.Cu")
	)
	(gr_line
		(start 70.490588 9.002014)
		(end 70.692772 8.864346)
		(stroke
			(width 0.0635)
			(type default)
		)
		(layer "B.Cu")
	)
	(gr_line
		(start 70.529704 10.423652)
		(end 70.529958 10.423652)
		(stroke
			(width 0.0635)
			(type default)
		)
		(layer "B.Cu")
	)
	(gr_line
		(start 70.626732 8.287766)
		(end 70.764146 8.48995)
		(stroke
			(width 0.0635)
			(type default)
		)
		(layer "B.Cu")
	)
	(gr_arc
		(start 70.656196 10.737596)
		(mid 70.564459 10.600455)
		(end 70.532244 10.438638)
		(stroke
			(width 0.0635)
			(type default)
		)
		(layer "B.Cu")
	)
	(gr_arc
		(start 70.656196 10.737596)
		(mid 70.747768 10.874643)
		(end 70.779894 11.0363)
		(stroke
			(width 0.0635)
			(type default)
		)
		(layer "B.Cu")
	)
	(gr_line
		(start 70.667626 -5.256022)
		(end 70.680326 -5.264912)
		(stroke
			(width 0.0635)
			(type default)
		)
		(layer "B.Cu")
	)
	(gr_line
		(start 70.680326 -5.264912)
		(end 70.689216 -5.277612)
		(stroke
			(width 0.0635)
			(type default)
		)
		(layer "B.Cu")
	)
	(gr_line
		(start 70.692772 8.864346)
		(end 70.764146 8.48995)
		(stroke
			(width 0.0635)
			(type default)
		)
		(layer "B.Cu")
	)
	(gr_line
		(start 70.698868 7.908798)
		(end 70.901052 7.771384)
		(stroke
			(width 0.0635)
			(type default)
		)
		(layer "B.Cu")
	)
	(gr_line
		(start 70.7136 6.190742)
		(end 70.71995 6.157468)
		(stroke
			(width 0.0635)
			(type default)
		)
		(layer "B.Cu")
	)
	(gr_line
		(start 70.71995 6.157468)
		(end 70.74027 6.131306)
		(stroke
			(width 0.0635)
			(type default)
		)
		(layer "B.Cu")
	)
	(gr_line
		(start 70.779894 12.514072)
		(end 70.779894 11.0363)
		(stroke
			(width 0.0635)
			(type default)
		)
		(layer "B.Cu")
	)
	(gr_line
		(start 70.835012 7.195312)
		(end 70.972426 7.397242)
		(stroke
			(width 0.0635)
			(type default)
		)
		(layer "B.Cu")
	)
	(gr_line
		(start 70.901052 7.771384)
		(end 70.972426 7.397242)
		(stroke
			(width 0.0635)
			(type default)
		)
		(layer "B.Cu")
	)
	(gr_line
		(start 71.080122 -11.749786)
		(end 71.138542 -11.89228)
		(stroke
			(width 0.0635)
			(type default)
		)
		(layer "B.Cu")
	)
	(gr_line
		(start 71.116952 -5.888228)
		(end 71.129652 -5.906516)
		(stroke
			(width 0.0635)
			(type default)
		)
		(layer "B.Cu")
	)
	(gr_line
		(start 71.129652 -5.906516)
		(end 71.134478 -5.928614)
		(stroke
			(width 0.0635)
			(type default)
		)
		(layer "B.Cu")
	)
	(gr_line
		(start 71.138542 -11.89228)
		(end 71.453248 -12.524486)
		(stroke
			(width 0.0635)
			(type default)
		)
		(layer "B.Cu")
	)
	(gr_arc
		(start 71.453248 -12.524486)
		(mid 71.526645 -12.588354)
		(end 71.623682 -12.581382)
		(stroke
			(width 0.0635)
			(type default)
		)
		(layer "B.Cu")
	)
	(gr_line
		(start 71.623682 -12.581382)
		(end 71.623936 -12.581382)
		(stroke
			(width 0.0635)
			(type default)
		)
		(layer "B.Cu")
	)
	(gr_line
		(start 71.623936 -12.581382)
		(end 71.628508 -12.579096)
		(stroke
			(width 0.0635)
			(type default)
		)
		(layer "B.Cu")
	)
	(gr_line
		(start 71.703438 -13.024358)
		(end 72.079612 -13.750036)
		(stroke
			(width 0.0635)
			(type default)
		)
		(layer "B.Cu")
	)
	(gr_arc
		(start 71.760334 -12.853924)
		(mid 71.696571 -12.927377)
		(end 71.703438 -13.024358)
		(stroke
			(width 0.0635)
			(type default)
		)
		(layer "B.Cu")
	)
	(gr_line
		(start 71.760334 -12.853924)
		(end 71.760588 -12.853924)
		(stroke
			(width 0.0635)
			(type default)
		)
		(layer "B.Cu")
	)
	(gr_line
		(start 72.193912 2.32664)
		(end 72.200516 2.320544)
		(stroke
			(width 0.0635)
			(type default)
		)
		(layer "B.Cu")
	)
	(gr_line
		(start 72.200516 2.320544)
		(end 72.260968 2.27838)
		(stroke
			(width 0.0635)
			(type default)
		)
		(layer "B.Cu")
	)
	(gr_line
		(start 72.22109 7.991856)
		(end 72.22363 8.006334)
		(stroke
			(width 0.0635)
			(type default)
		)
		(layer "B.Cu")
	)
	(gr_line
		(start 72.22109 7.991856)
		(end 72.223884 7.976108)
		(stroke
			(width 0.0635)
			(type default)
		)
		(layer "B.Cu")
	)
	(gr_arc
		(start 72.37984 11.005566)
		(mid 72.412142 10.843903)
		(end 72.503792 10.706862)
		(stroke
			(width 0.0635)
			(type default)
		)
		(layer "B.Cu")
	)
	(gr_line
		(start 72.37984 12.514072)
		(end 72.37984 11.005566)
		(stroke
			(width 0.0635)
			(type default)
		)
		(layer "B.Cu")
	)
	(gr_line
		(start 72.389746 2.564384)
		(end 72.438006 2.529586)
		(stroke
			(width 0.0635)
			(type default)
		)
		(layer "B.Cu")
	)
	(gr_line
		(start 72.503792 6.387846)
		(end 72.508872 6.359652)
		(stroke
			(width 0.0635)
			(type default)
		)
		(layer "B.Cu")
	)
	(gr_line
		(start 72.503792 10.706862)
		(end 72.504046 10.706608)
		(stroke
			(width 0.0635)
			(type default)
		)
		(layer "B.Cu")
	)
	(gr_line
		(start 72.508872 6.359652)
		(end 72.524874 6.337046)
		(stroke
			(width 0.0635)
			(type default)
		)
		(layer "B.Cu")
	)
	(gr_arc
		(start 72.626982 10.425176)
		(mid 72.592014 10.577473)
		(end 72.504046 10.706608)
		(stroke
			(width 0.0635)
			(type default)
		)
		(layer "B.Cu")
	)
	(gr_line
		(start 72.661018 6.142482)
		(end 72.768968 5.98805)
		(stroke
			(width 0.0635)
			(type default)
		)
		(layer "B.Cu")
	)
	(gr_line
		(start 72.789034 5.959348)
		(end 73.163176 5.425186)
		(stroke
			(width 0.0635)
			(type default)
		)
		(layer "B.Cu")
	)
	(gr_line
		(start 72.9107 6.317234)
		(end 73.015856 6.166866)
		(stroke
			(width 0.0635)
			(type default)
		)
		(layer "B.Cu")
	)
	(gr_line
		(start 73.010268 3.207512)
		(end 73.014586 3.202178)
		(stroke
			(width 0.0635)
			(type default)
		)
		(layer "B.Cu")
	)
	(gr_line
		(start 73.014586 3.202178)
		(end 73.020174 3.198114)
		(stroke
			(width 0.0635)
			(type default)
		)
		(layer "B.Cu")
	)
	(gr_line
		(start 73.019412 6.166358)
		(end 73.25995 6.12394)
		(stroke
			(width 0.0635)
			(type default)
		)
		(layer "B.Cu")
	)
	(gr_arc
		(start 73.055988 10.698988)
		(mid 72.964433 10.561935)
		(end 72.93229 10.400284)
		(stroke
			(width 0.0635)
			(type default)
		)
		(layer "B.Cu")
	)
	(gr_arc
		(start 73.055988 10.698988)
		(mid 73.147715 10.836268)
		(end 73.17994 10.9982)
		(stroke
			(width 0.0635)
			(type default)
		)
		(layer "B.Cu")
	)
	(gr_line
		(start 73.17994 12.514072)
		(end 73.17994 10.9982)
		(stroke
			(width 0.0635)
			(type default)
		)
		(layer "B.Cu")
	)
	(gr_line
		(start 73.25995 6.12394)
		(end 73.478644 5.811774)
		(stroke
			(width 0.0635)
			(type default)
		)
		(layer "B.Cu")
	)
	(gr_line
		(start 73.426828 5.04825)
		(end 73.801224 4.513834)
		(stroke
			(width 0.0635)
			(type default)
		)
		(layer "B.Cu")
	)
	(gr_line
		(start 73.435972 5.571236)
		(end 73.478644 5.811774)
		(stroke
			(width 0.0635)
			(type default)
		)
		(layer "B.Cu")
	)
	(gr_line
		(start 73.63841 5.277612)
		(end 73.653904 5.255514)
		(stroke
			(width 0.0635)
			(type default)
		)
		(layer "B.Cu")
	)
	(gr_line
		(start 73.65746 5.255006)
		(end 73.897998 5.212588)
		(stroke
			(width 0.0635)
			(type default)
		)
		(layer "B.Cu")
	)
	(gr_line
		(start 73.897998 5.212588)
		(end 74.116692 4.900422)
		(stroke
			(width 0.0635)
			(type default)
		)
		(layer "B.Cu")
	)
	(gr_line
		(start 74.07402 4.659884)
		(end 74.116692 4.900422)
		(stroke
			(width 0.0635)
			(type default)
		)
		(layer "B.Cu")
	)
	(gr_line
		(start 74.33564 3.750564)
		(end 74.345292 3.736594)
		(stroke
			(width 0.0635)
			(type default)
		)
		(layer "B.Cu")
	)
	(gr_line
		(start 74.345292 3.736594)
		(end 74.359516 3.726942)
		(stroke
			(width 0.0635)
			(type default)
		)
		(layer "B.Cu")
	)
	(gr_line
		(start 74.379074 -5.027168)
		(end 74.402696 -5.043678)
		(stroke
			(width 0.0635)
			(type default)
		)
		(layer "B.Cu")
	)
	(gr_line
		(start 74.402696 -5.043678)
		(end 74.431144 -5.048758)
		(stroke
			(width 0.0635)
			(type default)
		)
		(layer "B.Cu")
	)
	(gr_line
		(start 74.45375 7.185152)
		(end 74.45629 7.170166)
		(stroke
			(width 0.0635)
			(type default)
		)
		(layer "B.Cu")
	)
	(gr_line
		(start 74.45375 7.185152)
		(end 74.456544 7.2009)
		(stroke
			(width 0.0635)
			(type default)
		)
		(layer "B.Cu")
	)
	(gr_line
		(start 74.535792 7.651242)
		(end 74.64933 8.294878)
		(stroke
			(width 0.0635)
			(type default)
		)
		(layer "B.Cu")
	)
	(gr_line
		(start 74.728832 8.745982)
		(end 74.842624 9.39165)
		(stroke
			(width 0.0635)
			(type default)
		)
		(layer "B.Cu")
	)
	(gr_line
		(start 74.731118 5.611622)
		(end 74.736198 5.583428)
		(stroke
			(width 0.0635)
			(type default)
		)
		(layer "B.Cu")
	)
	(gr_line
		(start 74.736198 5.583428)
		(end 74.752454 5.56006)
		(stroke
			(width 0.0635)
			(type default)
		)
		(layer "B.Cu")
	)
	(gr_arc
		(start 74.779886 11.018774)
		(mid 74.812097 10.856836)
		(end 74.903838 10.719562)
		(stroke
			(width 0.0635)
			(type default)
		)
		(layer "B.Cu")
	)
	(gr_line
		(start 74.779886 12.514072)
		(end 74.779886 11.018774)
		(stroke
			(width 0.0635)
			(type default)
		)
		(layer "B.Cu")
	)
	(gr_line
		(start 74.83221 7.562342)
		(end 75.032616 7.70255)
		(stroke
			(width 0.0635)
			(type default)
		)
		(layer "B.Cu")
	)
	(gr_line
		(start 74.837036 -3.90144)
		(end 74.86396 -3.919982)
		(stroke
			(width 0.0635)
			(type default)
		)
		(layer "B.Cu")
	)
	(gr_line
		(start 74.86396 -3.919982)
		(end 74.896472 -3.925824)
		(stroke
			(width 0.0635)
			(type default)
		)
		(layer "B.Cu")
	)
	(gr_line
		(start 74.958448 8.27786)
		(end 75.098656 8.077708)
		(stroke
			(width 0.0635)
			(type default)
		)
		(layer "B.Cu")
	)
	(gr_line
		(start 75.025504 8.657844)
		(end 75.225656 8.798052)
		(stroke
			(width 0.0635)
			(type default)
		)
		(layer "B.Cu")
	)
	(gr_arc
		(start 75.027028 10.437622)
		(mid 74.991983 10.590191)
		(end 74.903838 10.719562)
		(stroke
			(width 0.0635)
			(type default)
		)
		(layer "B.Cu")
	)
	(gr_line
		(start 75.032616 7.70255)
		(end 75.098656 8.077708)
		(stroke
			(width 0.0635)
			(type default)
		)
		(layer "B.Cu")
	)
	(gr_line
		(start 75.079352 -11.749786)
		(end 75.137772 -11.89228)
		(stroke
			(width 0.0635)
			(type default)
		)
		(layer "B.Cu")
	)
	(gr_line
		(start 75.137772 -11.89228)
		(end 75.452478 -12.524486)
		(stroke
			(width 0.0635)
			(type default)
		)
		(layer "B.Cu")
	)
	(gr_line
		(start 75.151488 9.373616)
		(end 75.29195 9.173464)
		(stroke
			(width 0.0635)
			(type default)
		)
		(layer "B.Cu")
	)
	(gr_line
		(start 75.225656 8.798052)
		(end 75.29195 9.173464)
		(stroke
			(width 0.0635)
			(type default)
		)
		(layer "B.Cu")
	)
	(gr_line
		(start 75.299824 -2.776728)
		(end 75.325224 -2.794508)
		(stroke
			(width 0.0635)
			(type default)
		)
		(layer "B.Cu")
	)
	(gr_line
		(start 75.325224 -2.794508)
		(end 75.354942 -2.799334)
		(stroke
			(width 0.0635)
			(type default)
		)
		(layer "B.Cu")
	)
	(gr_arc
		(start 75.452478 -12.524486)
		(mid 75.525873 -12.588335)
		(end 75.622912 -12.581382)
		(stroke
			(width 0.0635)
			(type default)
		)
		(layer "B.Cu")
	)
	(gr_arc
		(start 75.456288 10.711688)
		(mid 75.364561 10.574408)
		(end 75.332336 10.412476)
		(stroke
			(width 0.0635)
			(type default)
		)
		(layer "B.Cu")
	)
	(gr_arc
		(start 75.456288 10.711688)
		(mid 75.547823 10.848744)
		(end 75.579986 11.010392)
		(stroke
			(width 0.0635)
			(type default)
		)
		(layer "B.Cu")
	)
	(gr_line
		(start 75.579986 12.514072)
		(end 75.579986 11.010392)
		(stroke
			(width 0.0635)
			(type default)
		)
		(layer "B.Cu")
	)
	(gr_line
		(start 75.622912 -12.581382)
		(end 75.623166 -12.581382)
		(stroke
			(width 0.0635)
			(type default)
		)
		(layer "B.Cu")
	)
	(gr_line
		(start 75.623166 -12.581382)
		(end 75.627738 -12.579096)
		(stroke
			(width 0.0635)
			(type default)
		)
		(layer "B.Cu")
	)
	(gr_line
		(start 75.629008 4.308348)
		(end 75.63866 4.294378)
		(stroke
			(width 0.0635)
			(type default)
		)
		(layer "B.Cu")
	)
	(gr_line
		(start 75.63866 4.294378)
		(end 75.652884 4.284726)
		(stroke
			(width 0.0635)
			(type default)
		)
		(layer "B.Cu")
	)
	(gr_line
		(start 75.702668 -13.024358)
		(end 75.972162 -13.560044)
		(stroke
			(width 0.0635)
			(type default)
		)
		(layer "B.Cu")
	)
	(gr_line
		(start 75.728576 -1.594104)
		(end 75.752198 -1.610614)
		(stroke
			(width 0.0635)
			(type default)
		)
		(layer "B.Cu")
	)
	(gr_line
		(start 75.752198 -1.610614)
		(end 75.780392 -1.615694)
		(stroke
			(width 0.0635)
			(type default)
		)
		(layer "B.Cu")
	)
	(gr_arc
		(start 75.759564 -12.853924)
		(mid 75.695801 -12.927377)
		(end 75.702668 -13.024358)
		(stroke
			(width 0.0635)
			(type default)
		)
		(layer "B.Cu")
	)
	(gr_line
		(start 75.759564 -12.853924)
		(end 75.759818 -12.853924)
		(stroke
			(width 0.0635)
			(type default)
		)
		(layer "B.Cu")
	)
	(gr_line
		(start 75.972162 -13.560044)
		(end 76.080112 -13.750036)
		(stroke
			(width 0.0635)
			(type default)
		)
		(layer "B.Cu")
	)
	(gr_line
		(start 76.014326 6.65226)
		(end 76.016866 6.637274)
		(stroke
			(width 0.0635)
			(type default)
		)
		(layer "B.Cu")
	)
	(gr_line
		(start 76.014326 6.65226)
		(end 76.01712 6.668008)
		(stroke
			(width 0.0635)
			(type default)
		)
		(layer "B.Cu")
	)
	(gr_line
		(start 76.12507 6.023864)
		(end 76.13015 5.99567)
		(stroke
			(width 0.0635)
			(type default)
		)
		(layer "B.Cu")
	)
	(gr_line
		(start 76.13015 5.99567)
		(end 76.146406 5.972302)
		(stroke
			(width 0.0635)
			(type default)
		)
		(layer "B.Cu")
	)
	(gr_line
		(start 76.193142 -0.471424)
		(end 76.216764 -0.487934)
		(stroke
			(width 0.0635)
			(type default)
		)
		(layer "B.Cu")
	)
	(gr_line
		(start 76.216764 -0.487934)
		(end 76.243942 -0.492506)
		(stroke
			(width 0.0635)
			(type default)
		)
		(layer "B.Cu")
	)
	(gr_line
		(start 76.251308 7.99719)
		(end 76.256388 8.025384)
		(stroke
			(width 0.0635)
			(type default)
		)
		(layer "B.Cu")
	)
	(gr_line
		(start 76.256388 8.025384)
		(end 76.272644 8.048752)
		(stroke
			(width 0.0635)
			(type default)
		)
		(layer "B.Cu")
	)
	(gr_line
		(start 76.659232 0.650748)
		(end 76.682092 0.634746)
		(stroke
			(width 0.0635)
			(type default)
		)
		(layer "B.Cu")
	)
	(gr_line
		(start 76.682092 0.634746)
		(end 76.71054 0.629666)
		(stroke
			(width 0.0635)
			(type default)
		)
		(layer "B.Cu")
	)
	(gr_line
		(start 76.873354 4.93395)
		(end 76.882244 4.92125)
		(stroke
			(width 0.0635)
			(type default)
		)
		(layer "B.Cu")
	)
	(gr_line
		(start 76.882244 4.92125)
		(end 76.894944 4.91236)
		(stroke
			(width 0.0635)
			(type default)
		)
		(layer "B.Cu")
	)
	(gr_arc
		(start 77.179932 10.92835)
		(mid 77.202494 10.814919)
		(end 77.2668 10.7188)
		(stroke
			(width 0.0635)
			(type default)
		)
		(layer "B.Cu")
	)
	(gr_line
		(start 77.179932 12.514072)
		(end 77.179932 10.92835)
		(stroke
			(width 0.0635)
			(type default)
		)
		(layer "B.Cu")
	)
	(gr_line
		(start 77.211682 1.79832)
		(end 77.224128 1.789938)
		(stroke
			(width 0.0635)
			(type default)
		)
		(layer "B.Cu")
	)
	(gr_line
		(start 77.224128 1.789938)
		(end 77.237844 1.786636)
		(stroke
			(width 0.0635)
			(type default)
		)
		(layer "B.Cu")
	)
	(gr_line
		(start 77.2668 10.7188)
		(end 77.303884 10.681716)
		(stroke
			(width 0.0635)
			(type default)
		)
		(layer "B.Cu")
	)
	(gr_arc
		(start 77.427582 10.383012)
		(mid 77.395429 10.544658)
		(end 77.303884 10.681716)
		(stroke
			(width 0.0635)
			(type default)
		)
		(layer "B.Cu")
	)
	(gr_line
		(start 77.63383 9.460992)
		(end 77.650086 9.48436)
		(stroke
			(width 0.0635)
			(type default)
		)
		(layer "B.Cu")
	)
	(gr_line
		(start 77.650086 9.48436)
		(end 77.655166 9.512554)
		(stroke
			(width 0.0635)
			(type default)
		)
		(layer "B.Cu")
	)
	(gr_line
		(start 77.694028 2.904236)
		(end 77.71511 2.890012)
		(stroke
			(width 0.0635)
			(type default)
		)
		(layer "B.Cu")
	)
	(gr_line
		(start 77.71511 2.890012)
		(end 77.739494 2.885694)
		(stroke
			(width 0.0635)
			(type default)
		)
		(layer "B.Cu")
	)
	(gr_line
		(start 77.768958 2.880614)
		(end 77.943202 2.84988)
		(stroke
			(width 0.0635)
			(type default)
		)
		(layer "B.Cu")
	)
	(gr_line
		(start 77.806042 -5.334)
		(end 77.815948 -5.335524)
		(stroke
			(width 0.0635)
			(type default)
		)
		(layer "B.Cu")
	)
	(gr_line
		(start 77.815948 -5.335524)
		(end 77.825092 -5.340604)
		(stroke
			(width 0.0635)
			(type default)
		)
		(layer "B.Cu")
	)
	(gr_arc
		(start 77.818996 10.610596)
		(mid 77.754911 10.514687)
		(end 77.732382 10.401554)
		(stroke
			(width 0.0635)
			(type default)
		)
		(layer "B.Cu")
	)
	(gr_line
		(start 77.818996 10.610596)
		(end 77.85608 10.64768)
		(stroke
			(width 0.0635)
			(type default)
		)
		(layer "B.Cu")
	)
	(gr_line
		(start 77.832204 3.17881)
		(end 77.996034 3.149854)
		(stroke
			(width 0.0635)
			(type default)
		)
		(layer "B.Cu")
	)
	(gr_arc
		(start 77.85608 10.64768)
		(mid 77.94762 10.784735)
		(end 77.979778 10.946384)
		(stroke
			(width 0.0635)
			(type default)
		)
		(layer "B.Cu")
	)
	(gr_line
		(start 77.979778 12.514072)
		(end 77.979778 10.946384)
		(stroke
			(width 0.0635)
			(type default)
		)
		(layer "B.Cu")
	)
	(gr_line
		(start 78.156562 4.028948)
		(end 78.17993 4.012692)
		(stroke
			(width 0.0635)
			(type default)
		)
		(layer "B.Cu")
	)
	(gr_line
		(start 78.17993 4.012692)
		(end 78.208124 4.007612)
		(stroke
			(width 0.0635)
			(type default)
		)
		(layer "B.Cu")
	)
	(gr_line
		(start 78.194916 -5.884926)
		(end 78.244446 -5.911342)
		(stroke
			(width 0.0635)
			(type default)
		)
		(layer "B.Cu")
	)
	(gr_arc
		(start 78.631288 5.165852)
		(mid 78.891482 5.422589)
		(end 78.986888 5.775452)
		(stroke
			(width 0.0635)
			(type default)
		)
		(layer "B.Cu")
	)
	(gr_line
		(start 79.079852 -11.749786)
		(end 79.138272 -11.89228)
		(stroke
			(width 0.0635)
			(type default)
		)
		(layer "B.Cu")
	)
	(gr_line
		(start 79.138272 -11.89228)
		(end 79.452978 -12.524486)
		(stroke
			(width 0.0635)
			(type default)
		)
		(layer "B.Cu")
	)
	(gr_line
		(start 79.239618 -4.691126)
		(end 79.287116 -4.699508)
		(stroke
			(width 0.0635)
			(type default)
		)
		(layer "B.Cu")
	)
	(gr_line
		(start 79.258668 -4.382516)
		(end 79.294228 -4.368292)
		(stroke
			(width 0.0635)
			(type default)
		)
		(layer "B.Cu")
	)
	(gr_line
		(start 79.287116 -4.699508)
		(end 79.288894 -4.698746)
		(stroke
			(width 0.0635)
			(type default)
		)
		(layer "B.Cu")
	)
	(gr_arc
		(start 79.291688 5.6896)
		(mid 79.388978 5.373049)
		(end 79.647288 5.165852)
		(stroke
			(width 0.0635)
			(type default)
		)
		(layer "B.Cu")
	)
	(gr_line
		(start 79.294228 -4.368292)
		(end 79.372968 -4.400804)
		(stroke
			(width 0.0635)
			(type default)
		)
		(layer "B.Cu")
	)
	(gr_arc
		(start 79.452978 -12.524486)
		(mid 79.526373 -12.588335)
		(end 79.623412 -12.581382)
		(stroke
			(width 0.0635)
			(type default)
		)
		(layer "B.Cu")
	)
	(gr_arc
		(start 79.579978 10.841228)
		(mid 79.612131 10.679582)
		(end 79.703676 10.542524)
		(stroke
			(width 0.0635)
			(type default)
		)
		(layer "B.Cu")
	)
	(gr_line
		(start 79.579978 12.514072)
		(end 79.579978 10.841228)
		(stroke
			(width 0.0635)
			(type default)
		)
		(layer "B.Cu")
	)
	(gr_line
		(start 79.623412 -12.581382)
		(end 79.623666 -12.581382)
		(stroke
			(width 0.0635)
			(type default)
		)
		(layer "B.Cu")
	)
	(gr_line
		(start 79.623666 -12.581382)
		(end 79.628238 -12.579096)
		(stroke
			(width 0.0635)
			(type default)
		)
		(layer "B.Cu")
	)
	(gr_line
		(start 79.703168 -13.024358)
		(end 80.079342 -13.750036)
		(stroke
			(width 0.0635)
			(type default)
		)
		(layer "B.Cu")
	)
	(gr_arc
		(start 79.760064 -12.853924)
		(mid 79.696301 -12.927377)
		(end 79.703168 -13.024358)
		(stroke
			(width 0.0635)
			(type default)
		)
		(layer "B.Cu")
	)
	(gr_line
		(start 79.760064 -12.853924)
		(end 79.760318 -12.853924)
		(stroke
			(width 0.0635)
			(type default)
		)
		(layer "B.Cu")
	)
	(gr_arc
		(start 80.222344 10.473944)
		(mid 80.155792 10.374436)
		(end 80.132428 10.257028)
		(stroke
			(width 0.0635)
			(type default)
		)
		(layer "B.Cu")
	)
	(gr_arc
		(start 80.222344 10.473944)
		(mid 80.338894 10.648404)
		(end 80.379824 10.854182)
		(stroke
			(width 0.0635)
			(type default)
		)
		(layer "B.Cu")
	)
	(gr_line
		(start 80.379824 12.514072)
		(end 80.379824 10.854182)
		(stroke
			(width 0.0635)
			(type default)
		)
		(layer "B.Cu")
	)
	(gr_line
		(start 80.414114 3.619246)
		(end 81.060544 3.5052)
		(stroke
			(width 0.0635)
			(type default)
		)
		(layer "B.Cu")
	)
	(gr_line
		(start 80.432656 3.927856)
		(end 80.633062 4.068318)
		(stroke
			(width 0.0635)
			(type default)
		)
		(layer "B.Cu")
	)
	(gr_line
		(start 80.633062 4.068318)
		(end 81.008474 4.002278)
		(stroke
			(width 0.0635)
			(type default)
		)
		(layer "B.Cu")
	)
	(gr_line
		(start 81.008474 4.002278)
		(end 81.148682 3.801872)
		(stroke
			(width 0.0635)
			(type default)
		)
		(layer "B.Cu")
	)
	(gr_arc
		(start 81.222088 5.165852)
		(mid 81.482282 5.422589)
		(end 81.577688 5.775452)
		(stroke
			(width 0.0635)
			(type default)
		)
		(layer "B.Cu")
	)
	(gr_line
		(start 81.490058 7.084822)
		(end 81.490312 7.088378)
		(stroke
			(width 0.0635)
			(type default)
		)
		(layer "B.Cu")
	)
	(gr_line
		(start 81.490058 7.084822)
		(end 81.490566 7.081266)
		(stroke
			(width 0.0635)
			(type default)
		)
		(layer "B.Cu")
	)
	(gr_line
		(start 81.490312 7.08914)
		(end 81.490312 7.088378)
		(stroke
			(width 0.0635)
			(type default)
		)
		(layer "B.Cu")
	)
	(gr_line
		(start 81.510886 3.425952)
		(end 82.157062 3.31216)
		(stroke
			(width 0.0635)
			(type default)
		)
		(layer "B.Cu")
	)
	(gr_line
		(start 81.528666 3.734816)
		(end 81.728818 3.875278)
		(stroke
			(width 0.0635)
			(type default)
		)
		(layer "B.Cu")
	)
	(gr_line
		(start 81.728818 3.875278)
		(end 82.103976 3.809238)
		(stroke
			(width 0.0635)
			(type default)
		)
		(layer "B.Cu")
	)
	(gr_arc
		(start 81.882488 5.775452)
		(mid 81.977875 5.422579)
		(end 82.238088 5.165852)
		(stroke
			(width 0.0635)
			(type default)
		)
		(layer "B.Cu")
	)
	(gr_arc
		(start 81.980024 10.981182)
		(mid 82.012177 10.819536)
		(end 82.103722 10.682478)
		(stroke
			(width 0.0635)
			(type default)
		)
		(layer "B.Cu")
	)
	(gr_line
		(start 81.980024 12.514072)
		(end 81.980024 10.981182)
		(stroke
			(width 0.0635)
			(type default)
		)
		(layer "B.Cu")
	)
	(gr_line
		(start 82.103976 3.809238)
		(end 82.244438 3.608832)
		(stroke
			(width 0.0635)
			(type default)
		)
		(layer "B.Cu")
	)
	(gr_arc
		(start 82.1944 9.0678)
		(mid 82.004095 8.629272)
		(end 81.906618 8.161274)
		(stroke
			(width 0.0635)
			(type default)
		)
		(layer "B.Cu")
	)
	(gr_arc
		(start 82.227674 10.383266)
		(mid 82.195448 10.545196)
		(end 82.103722 10.682478)
		(stroke
			(width 0.0635)
			(type default)
		)
		(layer "B.Cu")
	)
	(gr_arc
		(start 82.656172 10.647172)
		(mid 82.564626 10.510117)
		(end 82.532474 10.348468)
		(stroke
			(width 0.0635)
			(type default)
		)
		(layer "B.Cu")
	)
	(gr_arc
		(start 82.656172 10.647172)
		(mid 82.747744 10.784219)
		(end 82.77987 10.945876)
		(stroke
			(width 0.0635)
			(type default)
		)
		(layer "B.Cu")
	)
	(gr_line
		(start 82.77987 12.514072)
		(end 82.77987 10.945876)
		(stroke
			(width 0.0635)
			(type default)
		)
		(layer "B.Cu")
	)
	(gr_arc
		(start 83.812888 5.165852)
		(mid 84.073082 5.422589)
		(end 84.168488 5.775452)
		(stroke
			(width 0.0635)
			(type default)
		)
		(layer "B.Cu")
	)
	(gr_line
		(start 84.079842 -13.750036)
		(end 84.202778 -13.528802)
		(stroke
			(width 0.0635)
			(type default)
		)
		(layer "B.Cu")
	)
	(gr_line
		(start 84.119466 7.982204)
		(end 84.11972 7.978648)
		(stroke
			(width 0.0635)
			(type default)
		)
		(layer "B.Cu")
	)
	(gr_line
		(start 84.119466 7.982966)
		(end 84.119466 7.982204)
		(stroke
			(width 0.0635)
			(type default)
		)
		(layer "B.Cu")
	)
	(gr_arc
		(start 84.126578 8.012938)
		(mid 84.123016 7.997953)
		(end 84.119466 7.982966)
		(stroke
			(width 0.0635)
			(type default)
		)
		(layer "B.Cu")
	)
	(gr_line
		(start 84.202778 -13.528802)
		(end 84.454492 -13.024866)
		(stroke
			(width 0.0635)
			(type default)
		)
		(layer "B.Cu")
	)
	(gr_line
		(start 84.243926 -12.777978)
		(end 84.25053 -12.78128)
		(stroke
			(width 0.0635)
			(type default)
		)
		(layer "B.Cu")
	)
	(gr_arc
		(start 84.379816 11.04519)
		(mid 84.412072 10.8835)
		(end 84.503768 10.746486)
		(stroke
			(width 0.0635)
			(type default)
		)
		(layer "B.Cu")
	)
	(gr_line
		(start 84.379816 12.514072)
		(end 84.379816 11.04519)
		(stroke
			(width 0.0635)
			(type default)
		)
		(layer "B.Cu")
	)
	(gr_line
		(start 84.397342 -12.854432)
		(end 84.397596 -12.854432)
		(stroke
			(width 0.0635)
			(type default)
		)
		(layer "B.Cu")
	)
	(gr_arc
		(start 84.454492 -13.024866)
		(mid 84.461346 -12.927872)
		(end 84.397596 -12.854432)
		(stroke
			(width 0.0635)
			(type default)
		)
		(layer "B.Cu")
	)
	(gr_arc
		(start 84.473288 5.775452)
		(mid 84.568675 5.422579)
		(end 84.828888 5.165852)
		(stroke
			(width 0.0635)
			(type default)
		)
		(layer "B.Cu")
	)
	(gr_line
		(start 84.503768 10.746486)
		(end 84.504022 10.746232)
		(stroke
			(width 0.0635)
			(type default)
		)
		(layer "B.Cu")
	)
	(gr_line
		(start 84.52993 -12.579858)
		(end 84.533994 -12.58189)
		(stroke
			(width 0.0635)
			(type default)
		)
		(layer "B.Cu")
	)
	(gr_line
		(start 84.533994 -12.58189)
		(end 84.534248 -12.58189)
		(stroke
			(width 0.0635)
			(type default)
		)
		(layer "B.Cu")
	)
	(gr_arc
		(start 84.534248 -12.58189)
		(mid 84.631304 -12.588831)
		(end 84.704682 -12.524994)
		(stroke
			(width 0.0635)
			(type default)
		)
		(layer "B.Cu")
	)
	(gr_arc
		(start 84.627466 10.447782)
		(mid 84.595412 10.60928)
		(end 84.504022 10.746232)
		(stroke
			(width 0.0635)
			(type default)
		)
		(layer "B.Cu")
	)
	(gr_line
		(start 84.704682 -12.524994)
		(end 84.952078 -12.029694)
		(stroke
			(width 0.0635)
			(type default)
		)
		(layer "B.Cu")
	)
	(gr_line
		(start 84.952078 -12.029694)
		(end 85.079332 -11.749786)
		(stroke
			(width 0.0635)
			(type default)
		)
		(layer "B.Cu")
	)
	(gr_arc
		(start 85.055964 10.735564)
		(mid 84.964422 10.598508)
		(end 84.932266 10.43686)
		(stroke
			(width 0.0635)
			(type default)
		)
		(layer "B.Cu")
	)
	(gr_arc
		(start 85.055964 10.735564)
		(mid 85.147691 10.872844)
		(end 85.179916 11.034776)
		(stroke
			(width 0.0635)
			(type default)
		)
		(layer "B.Cu")
	)
	(gr_line
		(start 85.179916 12.514072)
		(end 85.179916 11.034776)
		(stroke
			(width 0.0635)
			(type default)
		)
		(layer "B.Cu")
	)
	(gr_arc
		(start 85.21954 -7.278116)
		(mid 85.218898 -7.23314)
		(end 85.217 -7.1882)
		(stroke
			(width 0.0635)
			(type default)
		)
		(layer "B.Cu")
	)
	(gr_line
		(start 85.379306 -2.99847)
		(end 85.4075 -3.00355)
		(stroke
			(width 0.0635)
			(type default)
		)
		(layer "B.Cu")
	)
	(gr_line
		(start 85.4075 -3.00355)
		(end 85.430868 -3.019806)
		(stroke
			(width 0.0635)
			(type default)
		)
		(layer "B.Cu")
	)
	(gr_arc
		(start 86.403688 5.165852)
		(mid 86.663882 5.422589)
		(end 86.759288 5.775452)
		(stroke
			(width 0.0635)
			(type default)
		)
		(layer "B.Cu")
	)
	(gr_arc
		(start 86.779862 11.090656)
		(mid 86.812015 10.92901)
		(end 86.90356 10.791952)
		(stroke
			(width 0.0635)
			(type default)
		)
		(layer "B.Cu")
	)
	(gr_line
		(start 86.779862 12.514072)
		(end 86.779862 11.090656)
		(stroke
			(width 0.0635)
			(type default)
		)
		(layer "B.Cu")
	)
	(gr_line
		(start 86.866984 -2.05613)
		(end 86.895178 -2.06121)
		(stroke
			(width 0.0635)
			(type default)
		)
		(layer "B.Cu")
	)
	(gr_line
		(start 86.895178 -2.06121)
		(end 86.918546 -2.077466)
		(stroke
			(width 0.0635)
			(type default)
		)
		(layer "B.Cu")
	)
	(gr_arc
		(start 87.027512 10.49274)
		(mid 86.99529 10.654672)
		(end 86.90356 10.791952)
		(stroke
			(width 0.0635)
			(type default)
		)
		(layer "B.Cu")
	)
	(gr_arc
		(start 87.064088 5.775452)
		(mid 87.159475 5.422579)
		(end 87.419688 5.165852)
		(stroke
			(width 0.0635)
			(type default)
		)
		(layer "B.Cu")
	)
	(gr_arc
		(start 87.456264 10.824464)
		(mid 87.364544 10.687319)
		(end 87.332312 10.525506)
		(stroke
			(width 0.0635)
			(type default)
		)
		(layer "B.Cu")
	)
	(gr_arc
		(start 87.456264 10.824464)
		(mid 87.547836 10.961511)
		(end 87.579962 11.123168)
		(stroke
			(width 0.0635)
			(type default)
		)
		(layer "B.Cu")
	)
	(gr_line
		(start 87.579962 12.514072)
		(end 87.579962 11.123168)
		(stroke
			(width 0.0635)
			(type default)
		)
		(layer "B.Cu")
	)
	(gr_line
		(start 88.080342 -13.750036)
		(end 88.203278 -13.528802)
		(stroke
			(width 0.0635)
			(type default)
		)
		(layer "B.Cu")
	)
	(gr_line
		(start 88.203278 -13.528802)
		(end 88.454992 -13.024866)
		(stroke
			(width 0.0635)
			(type default)
		)
		(layer "B.Cu")
	)
	(gr_line
		(start 88.244426 -12.777978)
		(end 88.25103 -12.78128)
		(stroke
			(width 0.0635)
			(type default)
		)
		(layer "B.Cu")
	)
	(gr_line
		(start 88.266016 -5.005324)
		(end 88.278716 -5.014214)
		(stroke
			(width 0.0635)
			(type default)
		)
		(layer "B.Cu")
	)
	(gr_line
		(start 88.278716 -5.014214)
		(end 88.287606 -5.026914)
		(stroke
			(width 0.0635)
			(type default)
		)
		(layer "B.Cu")
	)
	(gr_line
		(start 88.397842 -12.854432)
		(end 88.398096 -12.854432)
		(stroke
			(width 0.0635)
			(type default)
		)
		(layer "B.Cu")
	)
	(gr_arc
		(start 88.454992 -13.024866)
		(mid 88.461846 -12.927872)
		(end 88.398096 -12.854432)
		(stroke
			(width 0.0635)
			(type default)
		)
		(layer "B.Cu")
	)
	(gr_line
		(start 88.53043 -12.579858)
		(end 88.534494 -12.58189)
		(stroke
			(width 0.0635)
			(type default)
		)
		(layer "B.Cu")
	)
	(gr_line
		(start 88.534494 -12.58189)
		(end 88.534748 -12.58189)
		(stroke
			(width 0.0635)
			(type default)
		)
		(layer "B.Cu")
	)
	(gr_arc
		(start 88.534748 -12.58189)
		(mid 88.631804 -12.588831)
		(end 88.705182 -12.524994)
		(stroke
			(width 0.0635)
			(type default)
		)
		(layer "B.Cu")
	)
	(gr_line
		(start 88.705182 -12.524994)
		(end 88.952578 -12.029694)
		(stroke
			(width 0.0635)
			(type default)
		)
		(layer "B.Cu")
	)
	(gr_line
		(start 88.952578 -12.029694)
		(end 89.079832 -11.749786)
		(stroke
			(width 0.0635)
			(type default)
		)
		(layer "B.Cu")
	)
	(gr_arc
		(start 88.994488 5.165852)
		(mid 89.258531 5.385862)
		(end 89.357454 5.715)
		(stroke
			(width 0.0635)
			(type default)
		)
		(layer "B.Cu")
	)
	(gr_line
		(start 89.075768 -6.152388)
		(end 89.092024 -6.175756)
		(stroke
			(width 0.0635)
			(type default)
		)
		(layer "B.Cu")
	)
	(gr_line
		(start 89.092024 -6.175756)
		(end 89.097104 -6.20395)
		(stroke
			(width 0.0635)
			(type default)
		)
		(layer "B.Cu")
	)
	(gr_arc
		(start 89.179908 10.944098)
		(mid 89.212061 10.782452)
		(end 89.303606 10.645394)
		(stroke
			(width 0.0635)
			(type default)
		)
		(layer "B.Cu")
	)
	(gr_line
		(start 89.179908 12.514072)
		(end 89.179908 10.944098)
		(stroke
			(width 0.0635)
			(type default)
		)
		(layer "B.Cu")
	)
	(gr_arc
		(start 89.320878 8.068564)
		(mid 89.321003 8.061579)
		(end 89.321132 8.054594)
		(stroke
			(width 0.0635)
			(type default)
		)
		(layer "B.Cu")
	)
	(gr_line
		(start 89.32672 7.932166)
		(end 89.326974 7.927594)
		(stroke
			(width 0.0635)
			(type default)
		)
		(layer "B.Cu")
	)
	(gr_line
		(start 89.326974 7.926832)
		(end 89.327482 7.926324)
		(stroke
			(width 0.0635)
			(type default)
		)
		(layer "B.Cu")
	)
	(gr_line
		(start 89.326974 7.927594)
		(end 89.326974 7.926832)
		(stroke
			(width 0.0635)
			(type default)
		)
		(layer "B.Cu")
	)
	(gr_line
		(start 89.327482 7.92607)
		(end 89.329006 7.893304)
		(stroke
			(width 0.0635)
			(type default)
		)
		(layer "B.Cu")
	)
	(gr_line
		(start 89.327482 7.926324)
		(end 89.327482 7.92607)
		(stroke
			(width 0.0635)
			(type default)
		)
		(layer "B.Cu")
	)
	(gr_line
		(start 89.32799 7.888986)
		(end 89.32799 7.891526)
		(stroke
			(width 0.0635)
			(type default)
		)
		(layer "B.Cu")
	)
	(gr_line
		(start 89.32799 7.89305)
		(end 89.32799 7.891526)
		(stroke
			(width 0.0635)
			(type default)
		)
		(layer "B.Cu")
	)
	(gr_line
		(start 89.329006 7.893304)
		(end 89.32926 7.893304)
		(stroke
			(width 0.0635)
			(type default)
		)
		(layer "B.Cu")
	)
	(gr_line
		(start 89.32926 7.893304)
		(end 89.32799 7.89305)
		(stroke
			(width 0.0635)
			(type default)
		)
		(layer "B.Cu")
	)
	(gr_arc
		(start 89.427558 10.346182)
		(mid 89.395325 10.508108)
		(end 89.303606 10.645394)
		(stroke
			(width 0.0635)
			(type default)
		)
		(layer "B.Cu")
	)
	(gr_line
		(start 89.630758 7.95655)
		(end 89.630758 7.957058)
		(stroke
			(width 0.0635)
			(type default)
		)
		(layer "B.Cu")
	)
	(gr_line
		(start 89.630758 7.95655)
		(end 89.631774 7.934706)
		(stroke
			(width 0.0635)
			(type default)
		)
		(layer "B.Cu")
	)
	(gr_line
		(start 89.63152 7.926832)
		(end 89.632028 7.914386)
		(stroke
			(width 0.0635)
			(type default)
		)
		(layer "B.Cu")
	)
	(gr_line
		(start 89.631774 7.926832)
		(end 89.63152 7.926832)
		(stroke
			(width 0.0635)
			(type default)
		)
		(layer "B.Cu")
	)
	(gr_line
		(start 89.631774 7.934706)
		(end 89.631774 7.926832)
		(stroke
			(width 0.0635)
			(type default)
		)
		(layer "B.Cu")
	)
	(gr_line
		(start 89.632028 7.913878)
		(end 89.632028 7.914386)
		(stroke
			(width 0.0635)
			(type default)
		)
		(layer "B.Cu")
	)
	(gr_line
		(start 89.632028 7.913878)
		(end 89.63279 7.895082)
		(stroke
			(width 0.0635)
			(type default)
		)
		(layer "B.Cu")
	)
	(gr_line
		(start 89.63279 7.865618)
		(end 89.63279 7.868666)
		(stroke
			(width 0.0635)
			(type default)
		)
		(layer "B.Cu")
	)
	(gr_line
		(start 89.63279 7.865618)
		(end 89.633044 7.457694)
		(stroke
			(width 0.0635)
			(type default)
		)
		(layer "B.Cu")
	)
	(gr_line
		(start 89.63279 7.868666)
		(end 89.63279 7.895082)
		(stroke
			(width 0.0635)
			(type default)
		)
		(layer "B.Cu")
	)
	(gr_arc
		(start 89.662254 5.674106)
		(mid 89.777478 5.37963)
		(end 90.010488 5.165852)
		(stroke
			(width 0.0635)
			(type default)
		)
		(layer "B.Cu")
	)
	(gr_arc
		(start 89.856056 10.658856)
		(mid 89.764484 10.521809)
		(end 89.732358 10.360152)
		(stroke
			(width 0.0635)
			(type default)
		)
		(layer "B.Cu")
	)
	(gr_arc
		(start 89.856056 10.658856)
		(mid 89.947773 10.796137)
		(end 89.980008 10.958068)
		(stroke
			(width 0.0635)
			(type default)
		)
		(layer "B.Cu")
	)
	(gr_line
		(start 89.955624 2.2479)
		(end 90.173302 2.2098)
		(stroke
			(width 0.0635)
			(type default)
		)
		(layer "B.Cu")
	)
	(gr_line
		(start 89.980008 12.514072)
		(end 89.980008 10.958068)
		(stroke
			(width 0.0635)
			(type default)
		)
		(layer "B.Cu")
	)
	(gr_line
		(start 90.075512 1.917446)
		(end 90.080338 1.919478)
		(stroke
			(width 0.0635)
			(type default)
		)
		(layer "B.Cu")
	)
	(gr_line
		(start 90.080338 1.919478)
		(end 90.092276 1.914398)
		(stroke
			(width 0.0635)
			(type default)
		)
		(layer "B.Cu")
	)
	(gr_line
		(start 90.18905 2.207006)
		(end 90.194638 2.20599)
		(stroke
			(width 0.0635)
			(type default)
		)
		(layer "B.Cu")
	)
	(gr_line
		(start 90.194638 2.20599)
		(end 90.1954 2.204466)
		(stroke
			(width 0.0635)
			(type default)
		)
		(layer "B.Cu")
	)
	(gr_arc
		(start 91.579954 11.033252)
		(mid 91.612107 10.871606)
		(end 91.703652 10.734548)
		(stroke
			(width 0.0635)
			(type default)
		)
		(layer "B.Cu")
	)
	(gr_line
		(start 91.579954 12.514072)
		(end 91.579954 11.033252)
		(stroke
			(width 0.0635)
			(type default)
		)
		(layer "B.Cu")
	)
	(gr_arc
		(start 91.585288 5.165852)
		(mid 91.845482 5.422589)
		(end 91.940888 5.775452)
		(stroke
			(width 0.0635)
			(type default)
		)
		(layer "B.Cu")
	)
	(gr_arc
		(start 91.827604 10.435336)
		(mid 91.795383 10.597268)
		(end 91.703652 10.734548)
		(stroke
			(width 0.0635)
			(type default)
		)
		(layer "B.Cu")
	)
	(gr_line
		(start 92.079572 -13.750036)
		(end 92.20073 -13.533374)
		(stroke
			(width 0.0635)
			(type default)
		)
		(layer "B.Cu")
	)
	(gr_line
		(start 92.20073 -13.533374)
		(end 92.455492 -13.024866)
		(stroke
			(width 0.0635)
			(type default)
		)
		(layer "B.Cu")
	)
	(gr_line
		(start 92.244164 8.076692)
		(end 92.245434 8.075422)
		(stroke
			(width 0.0635)
			(type default)
		)
		(layer "B.Cu")
	)
	(gr_line
		(start 92.244926 -12.777978)
		(end 92.25153 -12.78128)
		(stroke
			(width 0.0635)
			(type default)
		)
		(layer "B.Cu")
	)
	(gr_arc
		(start 92.245688 5.775452)
		(mid 92.341089 5.422589)
		(end 92.601288 5.165852)
		(stroke
			(width 0.0635)
			(type default)
		)
		(layer "B.Cu")
	)
	(gr_arc
		(start 92.256102 10.747502)
		(mid 92.16453 10.610455)
		(end 92.132404 10.448798)
		(stroke
			(width 0.0635)
			(type default)
		)
		(layer "B.Cu")
	)
	(gr_arc
		(start 92.256102 10.747502)
		(mid 92.34763 10.88456)
		(end 92.3798 11.046206)
		(stroke
			(width 0.0635)
			(type default)
		)
		(layer "B.Cu")
	)
	(gr_line
		(start 92.3798 12.514072)
		(end 92.3798 11.046206)
		(stroke
			(width 0.0635)
			(type default)
		)
		(layer "B.Cu")
	)
	(gr_line
		(start 92.398342 -12.854432)
		(end 92.398596 -12.854432)
		(stroke
			(width 0.0635)
			(type default)
		)
		(layer "B.Cu")
	)
	(gr_arc
		(start 92.455492 -13.024866)
		(mid 92.462346 -12.927872)
		(end 92.398596 -12.854432)
		(stroke
			(width 0.0635)
			(type default)
		)
		(layer "B.Cu")
	)
	(gr_line
		(start 92.53093 -12.579858)
		(end 92.534994 -12.58189)
		(stroke
			(width 0.0635)
			(type default)
		)
		(layer "B.Cu")
	)
	(gr_line
		(start 92.534994 -12.58189)
		(end 92.535248 -12.58189)
		(stroke
			(width 0.0635)
			(type default)
		)
		(layer "B.Cu")
	)
	(gr_arc
		(start 92.535248 -12.58189)
		(mid 92.632242 -12.588727)
		(end 92.705682 -12.524994)
		(stroke
			(width 0.0635)
			(type default)
		)
		(layer "B.Cu")
	)
	(gr_line
		(start 92.705682 -12.524994)
		(end 93.013784 -11.908028)
		(stroke
			(width 0.0635)
			(type default)
		)
		(layer "B.Cu")
	)
	(gr_line
		(start 92.901516 -6.267196)
		(end 92.914216 -6.276086)
		(stroke
			(width 0.0635)
			(type default)
		)
		(layer "B.Cu")
	)
	(gr_line
		(start 92.914216 -6.276086)
		(end 92.923106 -6.288786)
		(stroke
			(width 0.0635)
			(type default)
		)
		(layer "B.Cu")
	)
	(gr_line
		(start 93.013784 -11.908028)
		(end 93.080332 -11.749786)
		(stroke
			(width 0.0635)
			(type default)
		)
		(layer "B.Cu")
	)
	(gr_line
		(start 93.148912 -6.610858)
		(end 93.169232 -6.640068)
		(stroke
			(width 0.0635)
			(type default)
		)
		(layer "B.Cu")
	)
	(gr_line
		(start 93.204538 -6.956552)
		(end 93.204538 -6.956806)
		(stroke
			(width 0.0635)
			(type default)
		)
		(layer "B.Cu")
	)
	(gr_arc
		(start 93.98 10.995406)
		(mid 94.0122 10.833583)
		(end 94.103952 10.696448)
		(stroke
			(width 0.0635)
			(type default)
		)
		(layer "B.Cu")
	)
	(gr_line
		(start 93.98 12.514072)
		(end 93.98 10.995406)
		(stroke
			(width 0.0635)
			(type default)
		)
		(layer "B.Cu")
	)
	(gr_arc
		(start 94.176088 5.165852)
		(mid 94.436303 5.422579)
		(end 94.531688 5.775452)
		(stroke
			(width 0.0635)
			(type default)
		)
		(layer "B.Cu")
	)
	(gr_arc
		(start 94.22765 10.397744)
		(mid 94.195497 10.55939)
		(end 94.103952 10.696448)
		(stroke
			(width 0.0635)
			(type default)
		)
		(layer "B.Cu")
	)
	(gr_line
		(start 94.511368 7.928102)
		(end 94.51213 7.928864)
		(stroke
			(width 0.0635)
			(type default)
		)
		(layer "B.Cu")
	)
	(gr_line
		(start 94.511876 7.93623)
		(end 94.51213 7.92988)
		(stroke
			(width 0.0635)
			(type default)
		)
		(layer "B.Cu")
	)
	(gr_line
		(start 94.51213 7.92988)
		(end 94.51213 7.928864)
		(stroke
			(width 0.0635)
			(type default)
		)
		(layer "B.Cu")
	)
	(gr_line
		(start 94.530418 6.569202)
		(end 94.531688 6.554216)
		(stroke
			(width 0.0635)
			(type default)
		)
		(layer "B.Cu")
	)
	(gr_line
		(start 94.531688 6.554216)
		(end 94.531688 6.546342)
		(stroke
			(width 0.0635)
			(type default)
		)
		(layer "B.Cu")
	)
	(gr_arc
		(start 94.656148 10.632948)
		(mid 94.564576 10.495901)
		(end 94.53245 10.334244)
		(stroke
			(width 0.0635)
			(type default)
		)
		(layer "B.Cu")
	)
	(gr_arc
		(start 94.656148 10.632948)
		(mid 94.747705 10.77)
		(end 94.779846 10.931652)
		(stroke
			(width 0.0635)
			(type default)
		)
		(layer "B.Cu")
	)
	(gr_line
		(start 94.779846 12.514072)
		(end 94.779846 10.931652)
		(stroke
			(width 0.0635)
			(type default)
		)
		(layer "B.Cu")
	)
	(gr_line
		(start 94.814136 7.887462)
		(end 94.81693 7.931912)
		(stroke
			(width 0.0635)
			(type default)
		)
		(layer "B.Cu")
	)
	(gr_line
		(start 94.816676 7.94512)
		(end 94.817692 7.944104)
		(stroke
			(width 0.0635)
			(type default)
		)
		(layer "B.Cu")
	)
	(gr_line
		(start 94.816676 7.946136)
		(end 94.816676 7.94512)
		(stroke
			(width 0.0635)
			(type default)
		)
		(layer "B.Cu")
	)
	(gr_line
		(start 94.83471 6.588252)
		(end 94.83471 6.589014)
		(stroke
			(width 0.0635)
			(type default)
		)
		(layer "B.Cu")
	)
	(gr_line
		(start 94.83471 6.588252)
		(end 94.836488 6.554216)
		(stroke
			(width 0.0635)
			(type default)
		)
		(layer "B.Cu")
	)
	(gr_arc
		(start 94.836488 5.775452)
		(mid 94.931889 5.422589)
		(end 95.192088 5.165852)
		(stroke
			(width 0.0635)
			(type default)
		)
		(layer "B.Cu")
	)
	(gr_line
		(start 96.080072 -13.750036)
		(end 96.200468 -13.533882)
		(stroke
			(width 0.0635)
			(type default)
		)
		(layer "B.Cu")
	)
	(gr_line
		(start 96.200468 -13.533882)
		(end 96.454722 -13.024866)
		(stroke
			(width 0.0635)
			(type default)
		)
		(layer "B.Cu")
	)
	(gr_line
		(start 96.244156 -12.777978)
		(end 96.25076 -12.78128)
		(stroke
			(width 0.0635)
			(type default)
		)
		(layer "B.Cu")
	)
	(gr_arc
		(start 96.379792 11.008614)
		(mid 96.411945 10.846968)
		(end 96.50349 10.70991)
		(stroke
			(width 0.0635)
			(type default)
		)
		(layer "B.Cu")
	)
	(gr_line
		(start 96.379792 12.514072)
		(end 96.379792 11.008614)
		(stroke
			(width 0.0635)
			(type default)
		)
		(layer "B.Cu")
	)
	(gr_line
		(start 96.397572 -12.854432)
		(end 96.397826 -12.854432)
		(stroke
			(width 0.0635)
			(type default)
		)
		(layer "B.Cu")
	)
	(gr_arc
		(start 96.454722 -13.024866)
		(mid 96.461481 -12.927921)
		(end 96.397826 -12.854432)
		(stroke
			(width 0.0635)
			(type default)
		)
		(layer "B.Cu")
	)
	(gr_line
		(start 96.53016 -12.579858)
		(end 96.534224 -12.58189)
		(stroke
			(width 0.0635)
			(type default)
		)
		(layer "B.Cu")
	)
	(gr_line
		(start 96.534224 -12.58189)
		(end 96.534478 -12.58189)
		(stroke
			(width 0.0635)
			(type default)
		)
		(layer "B.Cu")
	)
	(gr_arc
		(start 96.534478 -12.58189)
		(mid 96.631457 -12.588708)
		(end 96.704912 -12.524994)
		(stroke
			(width 0.0635)
			(type default)
		)
		(layer "B.Cu")
	)
	(gr_arc
		(start 96.627442 10.410698)
		(mid 96.595203 10.57262)
		(end 96.50349 10.70991)
		(stroke
			(width 0.0635)
			(type default)
		)
		(layer "B.Cu")
	)
	(gr_line
		(start 96.704912 -12.524994)
		(end 97.034096 -11.865864)
		(stroke
			(width 0.0635)
			(type default)
		)
		(layer "B.Cu")
	)
	(gr_arc
		(start 96.766888 5.165852)
		(mid 97.027082 5.422589)
		(end 97.122488 5.775452)
		(stroke
			(width 0.0635)
			(type default)
		)
		(layer "B.Cu")
	)
	(gr_line
		(start 96.847406 -6.154166)
		(end 96.860106 -6.163056)
		(stroke
			(width 0.0635)
			(type default)
		)
		(layer "B.Cu")
	)
	(gr_line
		(start 96.860106 -6.163056)
		(end 96.868996 -6.175756)
		(stroke
			(width 0.0635)
			(type default)
		)
		(layer "B.Cu")
	)
	(gr_line
		(start 97.034096 -11.865864)
		(end 97.079562 -11.749786)
		(stroke
			(width 0.0635)
			(type default)
		)
		(layer "B.Cu")
	)
	(gr_line
		(start 97.055178 -6.441694)
		(end 97.071434 -6.465062)
		(stroke
			(width 0.0635)
			(type default)
		)
		(layer "B.Cu")
	)
	(gr_arc
		(start 97.05594 10.67054)
		(mid 96.96439 10.533487)
		(end 96.932242 10.371836)
		(stroke
			(width 0.0635)
			(type default)
		)
		(layer "B.Cu")
	)
	(gr_arc
		(start 97.05594 10.67054)
		(mid 97.147667 10.80782)
		(end 97.179892 10.969752)
		(stroke
			(width 0.0635)
			(type default)
		)
		(layer "B.Cu")
	)
	(gr_line
		(start 97.071434 -6.465062)
		(end 97.076514 -6.493256)
		(stroke
			(width 0.0635)
			(type default)
		)
		(layer "B.Cu")
	)
	(gr_line
		(start 97.115376 7.863078)
		(end 97.115884 7.862824)
		(stroke
			(width 0.0635)
			(type default)
		)
		(layer "B.Cu")
	)
	(gr_line
		(start 97.115376 7.863078)
		(end 97.115884 7.864094)
		(stroke
			(width 0.0635)
			(type default)
		)
		(layer "B.Cu")
	)
	(gr_line
		(start 97.118424 7.86892)
		(end 97.120456 7.87273)
		(stroke
			(width 0.0635)
			(type default)
		)
		(layer "B.Cu")
	)
	(gr_line
		(start 97.118424 7.879842)
		(end 97.120456 7.87273)
		(stroke
			(width 0.0635)
			(type default)
		)
		(layer "B.Cu")
	)
	(gr_line
		(start 97.179892 12.514072)
		(end 97.179892 10.969752)
		(stroke
			(width 0.0635)
			(type default)
		)
		(layer "B.Cu")
	)
	(gr_line
		(start 97.415604 7.958582)
		(end 97.421954 7.955026)
		(stroke
			(width 0.0635)
			(type default)
		)
		(layer "B.Cu")
	)
	(gr_line
		(start 97.421954 7.955026)
		(end 97.422462 7.95401)
		(stroke
			(width 0.0635)
			(type default)
		)
		(layer "B.Cu")
	)
	(gr_line
		(start 97.422462 7.95401)
		(end 97.422716 7.928356)
		(stroke
			(width 0.0635)
			(type default)
		)
		(layer "B.Cu")
	)
	(gr_line
		(start 97.42297 7.91083)
		(end 97.423478 7.839964)
		(stroke
			(width 0.0635)
			(type default)
		)
		(layer "B.Cu")
	)
	(gr_arc
		(start 97.427288 5.775452)
		(mid 97.522675 5.422579)
		(end 97.782888 5.165852)
		(stroke
			(width 0.0635)
			(type default)
		)
		(layer "B.Cu")
	)
	(gr_line
		(start 98.564192 -6.113526)
		(end 98.594418 -6.134862)
		(stroke
			(width 0.0635)
			(type default)
		)
		(layer "B.Cu")
	)
	(gr_line
		(start 98.594418 -6.134862)
		(end 98.631502 -6.13918)
		(stroke
			(width 0.0635)
			(type default)
		)
		(layer "B.Cu")
	)
	(gr_line
		(start 98.961956 -4.784852)
		(end 98.985578 -4.801362)
		(stroke
			(width 0.0635)
			(type default)
		)
		(layer "B.Cu")
	)
	(gr_line
		(start 98.985578 -4.801362)
		(end 99.013772 -4.806442)
		(stroke
			(width 0.0635)
			(type default)
		)
		(layer "B.Cu")
	)
	(gr_line
		(start 99.195636 -3.499866)
		(end 99.218242 -3.515868)
		(stroke
			(width 0.0635)
			(type default)
		)
		(layer "B.Cu")
	)
	(gr_line
		(start 99.218242 -3.515868)
		(end 99.246436 -3.520948)
		(stroke
			(width 0.0635)
			(type default)
		)
		(layer "B.Cu")
	)
	(gr_line
		(start 100.079302 -13.750036)
		(end 100.140008 -13.654024)
		(stroke
			(width 0.0635)
			(type default)
		)
		(layer "B.Cu")
	)
	(gr_line
		(start 100.140008 -13.654024)
		(end 100.455222 -13.024866)
		(stroke
			(width 0.0635)
			(type default)
		)
		(layer "B.Cu")
	)
	(gr_line
		(start 100.244656 -12.777978)
		(end 100.25126 -12.78128)
		(stroke
			(width 0.0635)
			(type default)
		)
		(layer "B.Cu")
	)
	(gr_line
		(start 100.398072 -12.854432)
		(end 100.398326 -12.854432)
		(stroke
			(width 0.0635)
			(type default)
		)
		(layer "B.Cu")
	)
	(gr_arc
		(start 100.455222 -13.024866)
		(mid 100.461981 -12.927921)
		(end 100.398326 -12.854432)
		(stroke
			(width 0.0635)
			(type default)
		)
		(layer "B.Cu")
	)
	(gr_line
		(start 100.53066 -12.579858)
		(end 100.534724 -12.58189)
		(stroke
			(width 0.0635)
			(type default)
		)
		(layer "B.Cu")
	)
	(gr_line
		(start 100.534724 -12.58189)
		(end 100.534978 -12.58189)
		(stroke
			(width 0.0635)
			(type default)
		)
		(layer "B.Cu")
	)
	(gr_arc
		(start 100.534978 -12.58189)
		(mid 100.631957 -12.588708)
		(end 100.705412 -12.524994)
		(stroke
			(width 0.0635)
			(type default)
		)
		(layer "B.Cu")
	)
	(gr_line
		(start 100.705412 -12.524994)
		(end 101.014276 -11.90625)
		(stroke
			(width 0.0635)
			(type default)
		)
		(layer "B.Cu")
	)
	(gr_line
		(start 101.014276 -11.90625)
		(end 101.080062 -11.749786)
		(stroke
			(width 0.0635)
			(type default)
		)
		(layer "B.Cu")
	)
	(gr_line
		(start 101.140006 -4.87172)
		(end 101.1682 -4.8768)
		(stroke
			(width 0.0635)
			(type default)
		)
		(layer "B.Cu")
	)
	(gr_line
		(start 101.1682 -4.8768)
		(end 101.191568 -4.893056)
		(stroke
			(width 0.0635)
			(type default)
		)
		(layer "B.Cu")
	)
	(gr_line
		(start 101.691186 -5.614924)
		(end 101.706172 -5.625592)
		(stroke
			(width 0.0635)
			(type default)
		)
		(layer "B.Cu")
	)
	(gr_line
		(start 101.706172 -5.625592)
		(end 101.724968 -5.630164)
		(stroke
			(width 0.0635)
			(type default)
		)
		(layer "B.Cu")
	)
	(gr_line
		(start 101.749606 -3.65252)
		(end 101.7778 -3.6576)
		(stroke
			(width 0.0635)
			(type default)
		)
		(layer "B.Cu")
	)
	(gr_line
		(start 101.7778 -3.6576)
		(end 101.801168 -3.673856)
		(stroke
			(width 0.0635)
			(type default)
		)
		(layer "B.Cu")
	)
	(gr_line
		(start 102.282752 -4.383532)
		(end 102.291134 -4.389374)
		(stroke
			(width 0.0635)
			(type default)
		)
		(layer "B.Cu")
	)
	(gr_line
		(start 102.291134 -4.389374)
		(end 102.30104 -4.392168)
		(stroke
			(width 0.0635)
			(type default)
		)
		(layer "B.Cu")
	)
	(gr_line
		(start 104.079802 -13.750036)
		(end 104.249728 -13.434568)
		(stroke
			(width 0.0635)
			(type default)
		)
		(layer "B.Cu")
	)
	(gr_line
		(start 104.243886 -12.777978)
		(end 104.25049 -12.78128)
		(stroke
			(width 0.0635)
			(type default)
		)
		(layer "B.Cu")
	)
	(gr_line
		(start 104.249728 -13.434568)
		(end 104.454452 -13.024866)
		(stroke
			(width 0.0635)
			(type default)
		)
		(layer "B.Cu")
	)
	(gr_line
		(start 104.397302 -12.854432)
		(end 104.397556 -12.854432)
		(stroke
			(width 0.0635)
			(type default)
		)
		(layer "B.Cu")
	)
	(gr_arc
		(start 104.454452 -13.024866)
		(mid 104.461211 -12.927921)
		(end 104.397556 -12.854432)
		(stroke
			(width 0.0635)
			(type default)
		)
		(layer "B.Cu")
	)
	(gr_line
		(start 104.52989 -12.579858)
		(end 104.533954 -12.58189)
		(stroke
			(width 0.0635)
			(type default)
		)
		(layer "B.Cu")
	)
	(gr_line
		(start 104.533954 -12.58189)
		(end 104.534208 -12.58189)
		(stroke
			(width 0.0635)
			(type default)
		)
		(layer "B.Cu")
	)
	(gr_arc
		(start 104.534208 -12.58189)
		(mid 104.631222 -12.588753)
		(end 104.704642 -12.524994)
		(stroke
			(width 0.0635)
			(type default)
		)
		(layer "B.Cu")
	)
	(gr_line
		(start 104.704642 -12.524994)
		(end 104.903778 -12.126214)
		(stroke
			(width 0.0635)
			(type default)
		)
		(layer "B.Cu")
	)
	(gr_line
		(start 104.903778 -12.126214)
		(end 105.079292 -11.749786)
		(stroke
			(width 0.0635)
			(type default)
		)
		(layer "B.Cu")
	)
	(gr_line
		(start 108.080302 -13.750036)
		(end 108.209588 -13.516356)
		(stroke
			(width 0.0635)
			(type default)
		)
		(layer "B.Cu")
	)
	(gr_line
		(start 108.209588 -13.516356)
		(end 108.454952 -13.024866)
		(stroke
			(width 0.0635)
			(type default)
		)
		(layer "B.Cu")
	)
	(gr_line
		(start 108.244386 -12.777978)
		(end 108.25099 -12.78128)
		(stroke
			(width 0.0635)
			(type default)
		)
		(layer "B.Cu")
	)
	(gr_line
		(start 108.397802 -12.854432)
		(end 108.398056 -12.854432)
		(stroke
			(width 0.0635)
			(type default)
		)
		(layer "B.Cu")
	)
	(gr_arc
		(start 108.454952 -13.024866)
		(mid 108.461801 -12.927868)
		(end 108.398056 -12.854432)
		(stroke
			(width 0.0635)
			(type default)
		)
		(layer "B.Cu")
	)
	(gr_line
		(start 108.53039 -12.579858)
		(end 108.534454 -12.58189)
		(stroke
			(width 0.0635)
			(type default)
		)
		(layer "B.Cu")
	)
	(gr_line
		(start 108.534454 -12.58189)
		(end 108.534708 -12.58189)
		(stroke
			(width 0.0635)
			(type default)
		)
		(layer "B.Cu")
	)
	(gr_arc
		(start 108.534708 -12.58189)
		(mid 108.631764 -12.588831)
		(end 108.705142 -12.524994)
		(stroke
			(width 0.0635)
			(type default)
		)
		(layer "B.Cu")
	)
	(gr_line
		(start 108.705142 -12.524994)
		(end 108.963714 -12.007342)
		(stroke
			(width 0.0635)
			(type default)
		)
		(layer "B.Cu")
	)
	(gr_line
		(start 108.942378 -6.20014)
		(end 109.000036 -6.228588)
		(stroke
			(width 0.0635)
			(type default)
		)
		(layer "B.Cu")
	)
	(gr_line
		(start 108.963714 -12.007342)
		(end 109.079792 -11.749786)
		(stroke
			(width 0.0635)
			(type default)
		)
		(layer "B.Cu")
	)
	(gr_line
		(start 109.000036 -6.228588)
		(end 109.02823 -6.28523)
		(stroke
			(width 0.0635)
			(type default)
		)
		(layer "B.Cu")
	)
	(gr_arc
		(start 110.56874 5.206492)
		(mid 110.828936 5.463227)
		(end 110.92434 5.816092)
		(stroke
			(width 0.0635)
			(type default)
		)
		(layer "B.Cu")
	)
	(gr_arc
		(start 110.57509 11.215116)
		(mid 110.607243 11.05347)
		(end 110.698788 10.916412)
		(stroke
			(width 0.0635)
			(type default)
		)
		(layer "B.Cu")
	)
	(gr_line
		(start 110.57509 12.615672)
		(end 110.57509 11.215116)
		(stroke
			(width 0.0635)
			(type default)
		)
		(layer "B.Cu")
	)
	(gr_arc
		(start 110.82274 10.6172)
		(mid 110.7905 10.779121)
		(end 110.698788 10.916412)
		(stroke
			(width 0.0635)
			(type default)
		)
		(layer "B.Cu")
	)
	(gr_line
		(start 110.92434 5.821426)
		(end 110.92434 5.816092)
		(stroke
			(width 0.0635)
			(type default)
		)
		(layer "B.Cu")
	)
	(gr_line
		(start 111.2266 5.74421)
		(end 111.227362 5.76453)
		(stroke
			(width 0.0635)
			(type default)
		)
		(layer "B.Cu")
	)
	(gr_arc
		(start 111.2266 5.74421)
		(mid 111.319159 5.417731)
		(end 111.58474 5.206492)
		(stroke
			(width 0.0635)
			(type default)
		)
		(layer "B.Cu")
	)
	(gr_line
		(start 111.228378 5.794502)
		(end 111.22914 5.816092)
		(stroke
			(width 0.0635)
			(type default)
		)
		(layer "B.Cu")
	)
	(gr_arc
		(start 111.251492 11.022838)
		(mid 111.159781 10.885822)
		(end 111.12754 10.724134)
		(stroke
			(width 0.0635)
			(type default)
		)
		(layer "B.Cu")
	)
	(gr_line
		(start 111.251492 11.022838)
		(end 111.251746 11.023092)
		(stroke
			(width 0.0635)
			(type default)
		)
		(layer "B.Cu")
	)
	(gr_arc
		(start 111.251746 11.023092)
		(mid 111.343132 11.16005)
		(end 111.37519 11.321542)
		(stroke
			(width 0.0635)
			(type default)
		)
		(layer "B.Cu")
	)
	(gr_line
		(start 111.37519 12.615672)
		(end 111.37519 11.321542)
		(stroke
			(width 0.0635)
			(type default)
		)
		(layer "B.Cu")
	)
	(gr_line
		(start 112.079532 -13.750036)
		(end 112.213136 -13.508482)
		(stroke
			(width 0.0635)
			(type default)
		)
		(layer "B.Cu")
	)
	(gr_line
		(start 112.213136 -13.508482)
		(end 112.455452 -13.024866)
		(stroke
			(width 0.0635)
			(type default)
		)
		(layer "B.Cu")
	)
	(gr_line
		(start 112.244886 -12.777978)
		(end 112.25149 -12.78128)
		(stroke
			(width 0.0635)
			(type default)
		)
		(layer "B.Cu")
	)
	(gr_line
		(start 112.398302 -12.854432)
		(end 112.398556 -12.854432)
		(stroke
			(width 0.0635)
			(type default)
		)
		(layer "B.Cu")
	)
	(gr_arc
		(start 112.455452 -13.024866)
		(mid 112.462211 -12.927921)
		(end 112.398556 -12.854432)
		(stroke
			(width 0.0635)
			(type default)
		)
		(layer "B.Cu")
	)
	(gr_line
		(start 112.53089 -12.579858)
		(end 112.534954 -12.58189)
		(stroke
			(width 0.0635)
			(type default)
		)
		(layer "B.Cu")
	)
	(gr_line
		(start 112.534954 -12.58189)
		(end 112.535208 -12.58189)
		(stroke
			(width 0.0635)
			(type default)
		)
		(layer "B.Cu")
	)
	(gr_arc
		(start 112.535208 -12.58189)
		(mid 112.545076 -12.586247)
		(end 112.555274 -12.589764)
		(stroke
			(width 0.0635)
			(type default)
		)
		(layer "B.Cu")
	)
	(gr_arc
		(start 112.555274 -12.589764)
		(mid 112.6423 -12.584875)
		(end 112.705642 -12.524994)
		(stroke
			(width 0.0635)
			(type default)
		)
		(layer "B.Cu")
	)
	(gr_line
		(start 112.705642 -12.524994)
		(end 112.956086 -12.02309)
		(stroke
			(width 0.0635)
			(type default)
		)
		(layer "B.Cu")
	)
	(gr_line
		(start 112.956086 -12.02309)
		(end 113.080292 -11.749786)
		(stroke
			(width 0.0635)
			(type default)
		)
		(layer "B.Cu")
	)
	(gr_arc
		(start 112.975136 11.25347)
		(mid 113.007392 11.09178)
		(end 113.099088 10.954766)
		(stroke
			(width 0.0635)
			(type default)
		)
		(layer "B.Cu")
	)
	(gr_line
		(start 112.975136 12.615672)
		(end 112.975136 11.25347)
		(stroke
			(width 0.0635)
			(type default)
		)
		(layer "B.Cu")
	)
	(gr_line
		(start 113.099088 10.954766)
		(end 113.099342 10.954512)
		(stroke
			(width 0.0635)
			(type default)
		)
		(layer "B.Cu")
	)
	(gr_arc
		(start 113.15954 5.206492)
		(mid 113.419736 5.463227)
		(end 113.51514 5.816092)
		(stroke
			(width 0.0635)
			(type default)
		)
		(layer "B.Cu")
	)
	(gr_arc
		(start 113.222786 10.656062)
		(mid 113.190739 10.817565)
		(end 113.099342 10.954512)
		(stroke
			(width 0.0635)
			(type default)
		)
		(layer "B.Cu")
	)
	(gr_line
		(start 113.42751 7.125462)
		(end 113.427764 7.129018)
		(stroke
			(width 0.0635)
			(type default)
		)
		(layer "B.Cu")
	)
	(gr_line
		(start 113.42751 7.125462)
		(end 113.428018 7.121906)
		(stroke
			(width 0.0635)
			(type default)
		)
		(layer "B.Cu")
	)
	(gr_line
		(start 113.427764 7.12978)
		(end 113.427764 7.129018)
		(stroke
			(width 0.0635)
			(type default)
		)
		(layer "B.Cu")
	)
	(gr_line
		(start 113.539016 8.216138)
		(end 113.542572 8.250936)
		(stroke
			(width 0.0635)
			(type default)
		)
		(layer "B.Cu")
	)
	(gr_line
		(start 113.543842 8.264398)
		(end 113.543842 8.263636)
		(stroke
			(width 0.0635)
			(type default)
		)
		(layer "B.Cu")
	)
	(gr_line
		(start 113.544858 8.264906)
		(end 113.544858 8.264144)
		(stroke
			(width 0.0635)
			(type default)
		)
		(layer "B.Cu")
	)
	(gr_arc
		(start 113.651284 10.959084)
		(mid 113.559731 10.82203)
		(end 113.527586 10.66038)
		(stroke
			(width 0.0635)
			(type default)
		)
		(layer "B.Cu")
	)
	(gr_arc
		(start 113.651284 10.959084)
		(mid 113.742856 11.096131)
		(end 113.774982 11.257788)
		(stroke
			(width 0.0635)
			(type default)
		)
		(layer "B.Cu")
	)
	(gr_line
		(start 113.774982 12.615672)
		(end 113.774982 11.257788)
		(stroke
			(width 0.0635)
			(type default)
		)
		(layer "B.Cu")
	)
	(gr_arc
		(start 113.81994 5.816092)
		(mid 113.915308 5.463198)
		(end 114.17554 5.206492)
		(stroke
			(width 0.0635)
			(type default)
		)
		(layer "B.Cu")
	)
	(gr_line
		(start 113.843562 8.202676)
		(end 113.843816 8.202422)
		(stroke
			(width 0.0635)
			(type default)
		)
		(layer "B.Cu")
	)
	(gr_line
		(start 113.843562 8.203438)
		(end 113.843562 8.202676)
		(stroke
			(width 0.0635)
			(type default)
		)
		(layer "B.Cu")
	)
	(gr_line
		(start 113.84407 8.202168)
		(end 113.84407 8.201914)
		(stroke
			(width 0.0635)
			(type default)
		)
		(layer "B.Cu")
	)
	(gr_arc
		(start 115.375182 11.266424)
		(mid 115.407335 11.104778)
		(end 115.49888 10.96772)
		(stroke
			(width 0.0635)
			(type default)
		)
		(layer "B.Cu")
	)
	(gr_line
		(start 115.375182 12.615672)
		(end 115.375182 11.266424)
		(stroke
			(width 0.0635)
			(type default)
		)
		(layer "B.Cu")
	)
	(gr_arc
		(start 115.622832 10.668508)
		(mid 115.590622 10.830448)
		(end 115.49888 10.96772)
		(stroke
			(width 0.0635)
			(type default)
		)
		(layer "B.Cu")
	)
	(gr_arc
		(start 115.75034 5.206492)
		(mid 116.010536 5.463227)
		(end 116.10594 5.816092)
		(stroke
			(width 0.0635)
			(type default)
		)
		(layer "B.Cu")
	)
	(gr_line
		(start 115.798346 -33.446974)
		(end 116.03228 -33.21304)
		(stroke
			(width 0.05715)
			(type default)
		)
		(layer "B.Cu")
	)
	(gr_arc
		(start 116.05133 10.97153)
		(mid 115.959758 10.834483)
		(end 115.927632 10.672826)
		(stroke
			(width 0.0635)
			(type default)
		)
		(layer "B.Cu")
	)
	(gr_arc
		(start 116.05133 10.97153)
		(mid 116.142875 11.108585)
		(end 116.175028 11.270234)
		(stroke
			(width 0.0635)
			(type default)
		)
		(layer "B.Cu")
	)
	(gr_line
		(start 116.056918 8.023098)
		(end 116.057426 8.023606)
		(stroke
			(width 0.0635)
			(type default)
		)
		(layer "B.Cu")
	)
	(gr_line
		(start 116.057172 8.01624)
		(end 116.059204 7.976362)
		(stroke
			(width 0.0635)
			(type default)
		)
		(layer "B.Cu")
	)
	(gr_line
		(start 116.057426 8.02386)
		(end 116.057426 8.023606)
		(stroke
			(width 0.0635)
			(type default)
		)
		(layer "B.Cu")
	)
	(gr_line
		(start 116.059204 7.974584)
		(end 116.059204 7.976362)
		(stroke
			(width 0.0635)
			(type default)
		)
		(layer "B.Cu")
	)
	(gr_line
		(start 116.175028 12.615672)
		(end 116.175028 11.270234)
		(stroke
			(width 0.0635)
			(type default)
		)
		(layer "B.Cu")
	)
	(gr_line
		(start 116.361972 8.010398)
		(end 116.362734 8.009636)
		(stroke
			(width 0.0635)
			(type default)
		)
		(layer "B.Cu")
	)
	(gr_line
		(start 116.361972 8.01116)
		(end 116.361972 8.010398)
		(stroke
			(width 0.0635)
			(type default)
		)
		(layer "B.Cu")
	)
	(gr_line
		(start 116.361972 8.01116)
		(end 116.362226 8.018018)
		(stroke
			(width 0.0635)
			(type default)
		)
		(layer "B.Cu")
	)
	(gr_arc
		(start 116.41074 5.816092)
		(mid 116.506141 5.463229)
		(end 116.76634 5.206492)
		(stroke
			(width 0.0635)
			(type default)
		)
		(layer "B.Cu")
	)
	(gr_line
		(start 116.44884 -33.21304)
		(end 116.661692 -33.425892)
		(stroke
			(width 0.05715)
			(type default)
		)
		(layer "B.Cu")
	)
	(gr_arc
		(start 117.774974 11.203432)
		(mid 117.807127 11.041786)
		(end 117.898672 10.904728)
		(stroke
			(width 0.0635)
			(type default)
		)
		(layer "B.Cu")
	)
	(gr_line
		(start 117.774974 12.615672)
		(end 117.774974 11.203432)
		(stroke
			(width 0.0635)
			(type default)
		)
		(layer "B.Cu")
	)
	(gr_arc
		(start 118.022624 10.605516)
		(mid 117.990411 10.767454)
		(end 117.898672 10.904728)
		(stroke
			(width 0.0635)
			(type default)
		)
		(layer "B.Cu")
	)
	(gr_line
		(start 118.033038 9.392412)
		(end 118.033292 9.392412)
		(stroke
			(width 0.0635)
			(type default)
		)
		(layer "B.Cu")
	)
	(gr_line
		(start 118.327424 9.697212)
		(end 118.327424 9.652)
		(stroke
			(width 0.0635)
			(type default)
		)
		(layer "B.Cu")
	)
	(gr_arc
		(start 118.34114 5.206492)
		(mid 118.601336 5.463227)
		(end 118.69674 5.816092)
		(stroke
			(width 0.0635)
			(type default)
		)
		(layer "B.Cu")
	)
	(gr_arc
		(start 118.451376 10.907522)
		(mid 118.359721 10.77049)
		(end 118.327424 10.608818)
		(stroke
			(width 0.0635)
			(type default)
		)
		(layer "B.Cu")
	)
	(gr_line
		(start 118.451376 10.907522)
		(end 118.45163 10.907776)
		(stroke
			(width 0.0635)
			(type default)
		)
		(layer "B.Cu")
	)
	(gr_arc
		(start 118.45163 10.907776)
		(mid 118.543004 11.04474)
		(end 118.575074 11.206226)
		(stroke
			(width 0.0635)
			(type default)
		)
		(layer "B.Cu")
	)
	(gr_line
		(start 118.575074 12.615672)
		(end 118.575074 11.206226)
		(stroke
			(width 0.0635)
			(type default)
		)
		(layer "B.Cu")
	)
	(gr_arc
		(start 119.00154 5.816092)
		(mid 119.096941 5.463229)
		(end 119.35714 5.206492)
		(stroke
			(width 0.0635)
			(type default)
		)
		(layer "B.Cu")
	)
	(gr_arc
		(start 120.17502 11.1887)
		(mid 120.207231 11.026762)
		(end 120.298972 10.889488)
		(stroke
			(width 0.0635)
			(type default)
		)
		(layer "B.Cu")
	)
	(gr_line
		(start 120.17502 12.615672)
		(end 120.17502 11.1887)
		(stroke
			(width 0.0635)
			(type default)
		)
		(layer "B.Cu")
	)
	(gr_arc
		(start 120.42267 10.590784)
		(mid 120.390547 10.752447)
		(end 120.298972 10.889488)
		(stroke
			(width 0.0635)
			(type default)
		)
		(layer "B.Cu")
	)
	(gr_arc
		(start 120.851168 10.881868)
		(mid 120.759596 10.744821)
		(end 120.72747 10.583164)
		(stroke
			(width 0.0635)
			(type default)
		)
		(layer "B.Cu")
	)
	(gr_arc
		(start 120.851168 10.881868)
		(mid 120.942932 11.019138)
		(end 120.97512 11.18108)
		(stroke
			(width 0.0635)
			(type default)
		)
		(layer "B.Cu")
	)
	(gr_arc
		(start 120.93194 5.206492)
		(mid 121.194047 5.38747)
		(end 121.294906 5.6896)
		(stroke
			(width 0.0635)
			(type default)
		)
		(layer "B.Cu")
	)
	(gr_line
		(start 120.97512 12.615672)
		(end 120.97512 11.18108)
		(stroke
			(width 0.0635)
			(type default)
		)
		(layer "B.Cu")
	)
	(gr_line
		(start 121.26341 7.9883)
		(end 121.264426 7.968234)
		(stroke
			(width 0.0635)
			(type default)
		)
		(layer "B.Cu")
	)
	(gr_line
		(start 121.264426 7.967472)
		(end 121.264934 7.966964)
		(stroke
			(width 0.0635)
			(type default)
		)
		(layer "B.Cu")
	)
	(gr_line
		(start 121.264426 7.968234)
		(end 121.264426 7.967472)
		(stroke
			(width 0.0635)
			(type default)
		)
		(layer "B.Cu")
	)
	(gr_line
		(start 121.264934 7.96671)
		(end 121.265696 7.952486)
		(stroke
			(width 0.0635)
			(type default)
		)
		(layer "B.Cu")
	)
	(gr_line
		(start 121.264934 7.966964)
		(end 121.264934 7.96671)
		(stroke
			(width 0.0635)
			(type default)
		)
		(layer "B.Cu")
	)
	(gr_line
		(start 121.265442 7.92861)
		(end 121.265442 7.932166)
		(stroke
			(width 0.0635)
			(type default)
		)
		(layer "B.Cu")
	)
	(gr_line
		(start 121.265442 7.93369)
		(end 121.265442 7.932166)
		(stroke
			(width 0.0635)
			(type default)
		)
		(layer "B.Cu")
	)
	(gr_line
		(start 121.265442 7.93369)
		(end 121.266712 7.933944)
		(stroke
			(width 0.0635)
			(type default)
		)
		(layer "B.Cu")
	)
	(gr_line
		(start 121.265696 7.949692)
		(end 121.265696 7.952486)
		(stroke
			(width 0.0635)
			(type default)
		)
		(layer "B.Cu")
	)
	(gr_line
		(start 121.265696 7.949692)
		(end 121.266204 7.939278)
		(stroke
			(width 0.0635)
			(type default)
		)
		(layer "B.Cu")
	)
	(gr_line
		(start 121.266204 7.939278)
		(end 121.266458 7.933944)
		(stroke
			(width 0.0635)
			(type default)
		)
		(layer "B.Cu")
	)
	(gr_line
		(start 121.266458 7.933944)
		(end 121.266712 7.933944)
		(stroke
			(width 0.0635)
			(type default)
		)
		(layer "B.Cu")
	)
	(gr_line
		(start 121.56821 7.980426)
		(end 121.570242 7.935722)
		(stroke
			(width 0.0635)
			(type default)
		)
		(layer "B.Cu")
	)
	(gr_line
		(start 121.56821 7.996428)
		(end 121.56821 7.998206)
		(stroke
			(width 0.0635)
			(type default)
		)
		(layer "B.Cu")
	)
	(gr_line
		(start 121.56821 7.996428)
		(end 121.568972 7.98195)
		(stroke
			(width 0.0635)
			(type default)
		)
		(layer "B.Cu")
	)
	(gr_line
		(start 121.568972 7.981188)
		(end 121.56821 7.980426)
		(stroke
			(width 0.0635)
			(type default)
		)
		(layer "B.Cu")
	)
	(gr_line
		(start 121.568972 7.98195)
		(end 121.568972 7.981188)
		(stroke
			(width 0.0635)
			(type default)
		)
		(layer "B.Cu")
	)
	(gr_line
		(start 121.570242 7.906258)
		(end 121.570242 7.909306)
		(stroke
			(width 0.0635)
			(type default)
		)
		(layer "B.Cu")
	)
	(gr_line
		(start 121.570242 7.906258)
		(end 121.570496 7.498334)
		(stroke
			(width 0.0635)
			(type default)
		)
		(layer "B.Cu")
	)
	(gr_line
		(start 121.570242 7.909306)
		(end 121.570242 7.935722)
		(stroke
			(width 0.0635)
			(type default)
		)
		(layer "B.Cu")
	)
	(gr_arc
		(start 121.599706 5.714746)
		(mid 121.629031 5.566849)
		(end 121.712736 5.441442)
		(stroke
			(width 0.0635)
			(type default)
		)
		(layer "B.Cu")
	)
	(gr_line
		(start 121.712736 5.441442)
		(end 121.94794 5.206492)
		(stroke
			(width 0.0635)
			(type default)
		)
		(layer "B.Cu")
	)
	(gr_arc
		(start 122.575066 11.217656)
		(mid 122.607178 11.055986)
		(end 122.698764 10.918952)
		(stroke
			(width 0.0635)
			(type default)
		)
		(layer "B.Cu")
	)
	(gr_line
		(start 122.575066 12.615672)
		(end 122.575066 11.217656)
		(stroke
			(width 0.0635)
			(type default)
		)
		(layer "B.Cu")
	)
	(gr_arc
		(start 122.822716 10.61974)
		(mid 122.790505 10.781678)
		(end 122.698764 10.918952)
		(stroke
			(width 0.0635)
			(type default)
		)
		(layer "B.Cu")
	)
	(gr_arc
		(start 122.822716 10.61974)
		(mid 122.823542 10.273153)
		(end 122.826018 9.926574)
		(stroke
			(width 0.0635)
			(type default)
		)
		(layer "B.Cu")
	)
	(gr_line
		(start 123.127516 10.60831)
		(end 123.127516 9.8806)
		(stroke
			(width 0.0635)
			(type default)
		)
		(layer "B.Cu")
	)
	(gr_arc
		(start 123.251214 10.907014)
		(mid 123.159678 10.769958)
		(end 123.127516 10.60831)
		(stroke
			(width 0.0635)
			(type default)
		)
		(layer "B.Cu")
	)
	(gr_arc
		(start 123.251214 10.907014)
		(mid 123.342941 11.044294)
		(end 123.375166 11.206226)
		(stroke
			(width 0.0635)
			(type default)
		)
		(layer "B.Cu")
	)
	(gr_line
		(start 123.341892 -33.209992)
		(end 123.514612 -33.382712)
		(stroke
			(width 0.05715)
			(type default)
		)
		(layer "B.Cu")
	)
	(gr_line
		(start 123.375166 12.615672)
		(end 123.375166 11.206226)
		(stroke
			(width 0.0635)
			(type default)
		)
		(layer "B.Cu")
	)
	(gr_line
		(start 123.514612 -33.382712)
		(end 123.857512 -33.382712)
		(stroke
			(width 0.05715)
			(type default)
		)
		(layer "B.Cu")
	)
	(gr_arc
		(start 123.52274 5.206492)
		(mid 123.782955 5.463219)
		(end 123.87834 5.816092)
		(stroke
			(width 0.0635)
			(type default)
		)
		(layer "B.Cu")
	)
	(gr_line
		(start 123.633992 -32.915352)
		(end 123.738132 -32.915352)
		(stroke
			(width 0.05715)
			(type default)
		)
		(layer "B.Cu")
	)
	(gr_line
		(start 123.857512 -33.382712)
		(end 124.030232 -33.209992)
		(stroke
			(width 0.05715)
			(type default)
		)
		(layer "B.Cu")
	)
	(gr_line
		(start 124.181616 8.117078)
		(end 124.182886 8.116062)
		(stroke
			(width 0.0635)
			(type default)
		)
		(layer "B.Cu")
	)
	(gr_line
		(start 124.182124 8.107172)
		(end 124.182886 8.116062)
		(stroke
			(width 0.0635)
			(type default)
		)
		(layer "B.Cu")
	)
	(gr_arc
		(start 124.18314 5.816092)
		(mid 124.278508 5.463198)
		(end 124.53874 5.206492)
		(stroke
			(width 0.0635)
			(type default)
		)
		(layer "B.Cu")
	)
	(gr_line
		(start 124.378212 -33.209992)
		(end 124.550932 -33.382712)
		(stroke
			(width 0.05715)
			(type default)
		)
		(layer "B.Cu")
	)
	(gr_line
		(start 124.550932 -33.382712)
		(end 124.893832 -33.382712)
		(stroke
			(width 0.05715)
			(type default)
		)
		(layer "B.Cu")
	)
	(gr_line
		(start 124.670312 -32.915352)
		(end 124.774452 -32.915352)
		(stroke
			(width 0.05715)
			(type default)
		)
		(layer "B.Cu")
	)
	(gr_line
		(start 124.893832 -33.382712)
		(end 125.066552 -33.209992)
		(stroke
			(width 0.05715)
			(type default)
		)
		(layer "B.Cu")
	)
	(gr_arc
		(start 124.975112 11.216894)
		(mid 125.007368 11.055204)
		(end 125.099064 10.91819)
		(stroke
			(width 0.0635)
			(type default)
		)
		(layer "B.Cu")
	)
	(gr_line
		(start 124.975112 12.615672)
		(end 124.975112 11.216894)
		(stroke
			(width 0.0635)
			(type default)
		)
		(layer "B.Cu")
	)
	(gr_line
		(start 125.099064 10.91819)
		(end 125.099318 10.917936)
		(stroke
			(width 0.0635)
			(type default)
		)
		(layer "B.Cu")
	)
	(gr_arc
		(start 125.222762 10.619486)
		(mid 125.190706 10.780983)
		(end 125.099318 10.917936)
		(stroke
			(width 0.0635)
			(type default)
		)
		(layer "B.Cu")
	)
	(gr_line
		(start 125.639576 -33.865566)
		(end 125.916944 -33.588198)
		(stroke
			(width 0.05715)
			(type default)
		)
		(layer "B.Cu")
	)
	(gr_arc
		(start 125.65126 10.91946)
		(mid 125.559688 10.782413)
		(end 125.527562 10.620756)
		(stroke
			(width 0.0635)
			(type default)
		)
		(layer "B.Cu")
	)
	(gr_arc
		(start 125.65126 10.91946)
		(mid 125.74281 11.056513)
		(end 125.774958 11.218164)
		(stroke
			(width 0.0635)
			(type default)
		)
		(layer "B.Cu")
	)
	(gr_line
		(start 125.774958 12.615672)
		(end 125.774958 11.218164)
		(stroke
			(width 0.0635)
			(type default)
		)
		(layer "B.Cu")
	)
	(gr_line
		(start 125.916944 -33.394904)
		(end 125.916944 -33.588198)
		(stroke
			(width 0.05715)
			(type default)
		)
		(layer "B.Cu")
	)
	(gr_arc
		(start 126.11354 5.206492)
		(mid 126.373736 5.463227)
		(end 126.46914 5.816092)
		(stroke
			(width 0.0635)
			(type default)
		)
		(layer "B.Cu")
	)
	(gr_line
		(start 126.238 -33.59277)
		(end 126.510796 -33.865566)
		(stroke
			(width 0.05715)
			(type default)
		)
		(layer "B.Cu")
	)
	(gr_line
		(start 126.238 -33.2994)
		(end 126.238 -33.59277)
		(stroke
			(width 0.05715)
			(type default)
		)
		(layer "B.Cu")
	)
	(gr_line
		(start 126.44882 7.968742)
		(end 126.449582 7.969504)
		(stroke
			(width 0.0635)
			(type default)
		)
		(layer "B.Cu")
	)
	(gr_line
		(start 126.449582 7.97052)
		(end 126.449582 7.969504)
		(stroke
			(width 0.0635)
			(type default)
		)
		(layer "B.Cu")
	)
	(gr_line
		(start 126.46787 6.609842)
		(end 126.46914 6.594856)
		(stroke
			(width 0.0635)
			(type default)
		)
		(layer "B.Cu")
	)
	(gr_line
		(start 126.46914 6.594856)
		(end 126.46914 6.586982)
		(stroke
			(width 0.0635)
			(type default)
		)
		(layer "B.Cu")
	)
	(gr_line
		(start 126.510796 -33.865566)
		(end 126.511304 -33.865566)
		(stroke
			(width 0.05715)
			(type default)
		)
		(layer "B.Cu")
	)
	(gr_line
		(start 126.751588 7.928102)
		(end 126.754382 7.972552)
		(stroke
			(width 0.0635)
			(type default)
		)
		(layer "B.Cu")
	)
	(gr_line
		(start 126.754128 7.98576)
		(end 126.755144 7.984744)
		(stroke
			(width 0.0635)
			(type default)
		)
		(layer "B.Cu")
	)
	(gr_line
		(start 126.754128 7.986776)
		(end 126.754128 7.98576)
		(stroke
			(width 0.0635)
			(type default)
		)
		(layer "B.Cu")
	)
	(gr_line
		(start 126.772162 6.628892)
		(end 126.772162 6.629654)
		(stroke
			(width 0.0635)
			(type default)
		)
		(layer "B.Cu")
	)
	(gr_line
		(start 126.772162 6.628892)
		(end 126.77394 6.594856)
		(stroke
			(width 0.0635)
			(type default)
		)
		(layer "B.Cu")
	)
	(gr_arc
		(start 126.77394 5.816092)
		(mid 126.869341 5.463229)
		(end 127.12954 5.206492)
		(stroke
			(width 0.0635)
			(type default)
		)
		(layer "B.Cu")
	)
	(gr_arc
		(start 127.375158 11.179048)
		(mid 127.407311 11.017402)
		(end 127.498856 10.880344)
		(stroke
			(width 0.0635)
			(type default)
		)
		(layer "B.Cu")
	)
	(gr_line
		(start 127.375158 12.615672)
		(end 127.375158 11.179048)
		(stroke
			(width 0.0635)
			(type default)
		)
		(layer "B.Cu")
	)
	(gr_arc
		(start 127.622808 10.581132)
		(mid 127.590589 10.743066)
		(end 127.498856 10.880344)
		(stroke
			(width 0.0635)
			(type default)
		)
		(layer "B.Cu")
	)
	(gr_arc
		(start 128.051306 10.931906)
		(mid 127.959734 10.794859)
		(end 127.927608 10.633202)
		(stroke
			(width 0.0635)
			(type default)
		)
		(layer "B.Cu")
	)
	(gr_arc
		(start 128.051306 10.931906)
		(mid 128.142832 11.068964)
		(end 128.175004 11.23061)
		(stroke
			(width 0.0635)
			(type default)
		)
		(layer "B.Cu")
	)
	(gr_line
		(start 128.175004 12.615672)
		(end 128.175004 11.23061)
		(stroke
			(width 0.0635)
			(type default)
		)
		(layer "B.Cu")
	)
	(gr_arc
		(start 128.70434 5.206492)
		(mid 128.964536 5.463227)
		(end 129.05994 5.816092)
		(stroke
			(width 0.0635)
			(type default)
		)
		(layer "B.Cu")
	)
	(gr_line
		(start 129.05994 5.822188)
		(end 129.05994 5.816092)
		(stroke
			(width 0.0635)
			(type default)
		)
		(layer "B.Cu")
	)
	(gr_line
		(start 129.361438 5.73405)
		(end 129.362708 5.762498)
		(stroke
			(width 0.0635)
			(type default)
		)
		(layer "B.Cu")
	)
	(gr_arc
		(start 129.361438 5.73405)
		(mid 129.453815 5.411036)
		(end 129.72034 5.206492)
		(stroke
			(width 0.0635)
			(type default)
		)
		(layer "B.Cu")
	)
	(gr_line
		(start 129.363724 5.791708)
		(end 129.36474 5.816092)
		(stroke
			(width 0.0635)
			(type default)
		)
		(layer "B.Cu")
	)
	(gr_line
		(start 0 -31.785814)
		(end 0 -0.999998)
		(stroke
			(width 1.524)
			(type default)
		)
		(layer "In1.Cu")
	)
	(gr_arc
		(start 0 -31.785814)
		(mid 0.076081 -32.168518)
		(end 0.292862 -32.49295)
		(stroke
			(width 1.524)
			(type default)
		)
		(layer "In1.Cu")
	)
	(gr_arc
		(start 0.999998 0)
		(mid 0.292893 -0.292893)
		(end 0 -0.999998)
		(stroke
			(width 1.524)
			(type default)
		)
		(layer "In1.Cu")
	)
	(gr_line
		(start 0.999998 0)
		(end 3.885692 0)
		(stroke
			(width 1.524)
			(type default)
		)
		(layer "In1.Cu")
	)
	(gr_line
		(start 2.707132 -34.90722)
		(end 0.292862 -32.49295)
		(stroke
			(width 1.524)
			(type default)
		)
		(layer "In1.Cu")
	)
	(gr_arc
		(start 2.707132 -34.90722)
		(mid 3.031582 -35.123959)
		(end 3.414268 -35.200082)
		(stroke
			(width 1.524)
			(type default)
		)
		(layer "In1.Cu")
	)
	(gr_arc
		(start 4.592828 -0.292862)
		(mid 4.268379 -0.076123)
		(end 3.885692 0)
		(stroke
			(width 1.524)
			(type default)
		)
		(layer "In1.Cu")
	)
	(gr_line
		(start 4.592828 -0.292862)
		(end 5.007102 -0.707136)
		(stroke
			(width 1.524)
			(type default)
		)
		(layer "In1.Cu")
	)
	(gr_arc
		(start 5.299964 -7.590028)
		(mid 6.999986 -9.29005)
		(end 8.700008 -7.590028)
		(stroke
			(width 1.524)
			(type default)
		)
		(layer "In1.Cu")
	)
	(gr_arc
		(start 5.299964 -1.414272)
		(mid 5.223886 -1.031566)
		(end 5.007102 -0.707136)
		(stroke
			(width 1.524)
			(type default)
		)
		(layer "In1.Cu")
	)
	(gr_line
		(start 5.299964 -1.414272)
		(end 5.299964 -7.590028)
		(stroke
			(width 1.524)
			(type default)
		)
		(layer "In1.Cu")
	)
	(gr_line
		(start 8.700008 -7.590028)
		(end 8.700008 -1.414272)
		(stroke
			(width 1.524)
			(type default)
		)
		(layer "In1.Cu")
	)
	(gr_arc
		(start 8.99287 -0.707136)
		(mid 8.776129 -1.031585)
		(end 8.700008 -1.414272)
		(stroke
			(width 1.524)
			(type default)
		)
		(layer "In1.Cu")
	)
	(gr_line
		(start 8.99287 -0.707136)
		(end 9.407144 -0.292862)
		(stroke
			(width 1.524)
			(type default)
		)
		(layer "In1.Cu")
	)
	(gr_line
		(start 9.1567 -20.8788)
		(end 10.7442 -22.4663)
		(stroke
			(width 0.381)
			(type default)
		)
		(layer "In1.Cu")
	)
	(gr_line
		(start 9.1567 -12.0904)
		(end 9.1567 -20.8788)
		(stroke
			(width 0.381)
			(type default)
		)
		(layer "In1.Cu")
	)
	(gr_arc
		(start 10.11428 0)
		(mid 9.73157 -0.076073)
		(end 9.407144 -0.292862)
		(stroke
			(width 1.524)
			(type default)
		)
		(layer "In1.Cu")
	)
	(gr_line
		(start 10.11428 0)
		(end 14.349984 0)
		(stroke
			(width 1.524)
			(type default)
		)
		(layer "In1.Cu")
	)
	(gr_line
		(start 10.4648 -10.7823)
		(end 9.1567 -12.0904)
		(stroke
			(width 0.381)
			(type default)
		)
		(layer "In1.Cu")
	)
	(gr_line
		(start 10.4648 -4.7371)
		(end 10.4648 -10.7823)
		(stroke
			(width 0.381)
			(type default)
		)
		(layer "In1.Cu")
	)
	(gr_line
		(start 10.7442 -27.3685)
		(end 11.7856 -28.4099)
		(stroke
			(width 0.381)
			(type default)
		)
		(layer "In1.Cu")
	)
	(gr_line
		(start 10.7442 -22.4663)
		(end 10.7442 -27.3685)
		(stroke
			(width 0.381)
			(type default)
		)
		(layer "In1.Cu")
	)
	(gr_line
		(start 11.7856 -28.4099)
		(end 18.2245 -28.4099)
		(stroke
			(width 0.381)
			(type default)
		)
		(layer "In1.Cu")
	)
	(gr_line
		(start 12.3063 -19.4183)
		(end 12.3063 -16.6624)
		(stroke
			(width 0.381)
			(type default)
		)
		(layer "In1.Cu")
	)
	(gr_line
		(start 12.3063 -16.6624)
		(end 12.7889 -16.1798)
		(stroke
			(width 0.381)
			(type default)
		)
		(layer "In1.Cu")
	)
	(gr_line
		(start 12.5603 -0.6223)
		(end 12.7381 -0.8001)
		(stroke
			(width 0.381)
			(type default)
		)
		(layer "In1.Cu")
	)
	(gr_line
		(start 12.7889 -16.1798)
		(end 14.1986 -16.1798)
		(stroke
			(width 0.381)
			(type default)
		)
		(layer "In1.Cu")
	)
	(gr_line
		(start 12.7889 -2.413)
		(end 10.4648 -4.7371)
		(stroke
			(width 0.381)
			(type default)
		)
		(layer "In1.Cu")
	)
	(gr_line
		(start 12.7889 0.0889)
		(end 12.7889 -2.413)
		(stroke
			(width 0.381)
			(type default)
		)
		(layer "In1.Cu")
	)
	(gr_line
		(start 13.00734 -0.620014)
		(end 12.82954 -0.797814)
		(stroke
			(width 0.381)
			(type default)
		)
		(layer "In1.Cu")
	)
	(gr_line
		(start 13.1953 -20.3073)
		(end 12.3063 -19.4183)
		(stroke
			(width 0.381)
			(type default)
		)
		(layer "In1.Cu")
	)
	(gr_line
		(start 13.8176 -25.7175)
		(end 13.8176 -24.1427)
		(stroke
			(width 0.381)
			(type default)
		)
		(layer "In1.Cu")
	)
	(gr_line
		(start 13.8176 -24.1427)
		(end 14.478 -23.4823)
		(stroke
			(width 0.381)
			(type default)
		)
		(layer "In1.Cu")
	)
	(gr_line
		(start 14.1097 -26.0096)
		(end 13.8176 -25.7175)
		(stroke
			(width 0.381)
			(type default)
		)
		(layer "In1.Cu")
	)
	(gr_line
		(start 14.1986 -16.1798)
		(end 15.9131 -17.8943)
		(stroke
			(width 0.381)
			(type default)
		)
		(layer "In1.Cu")
	)
	(gr_arc
		(start 14.349984 0)
		(mid 14.491333 0.058549)
		(end 14.549882 0.199898)
		(stroke
			(width 1.524)
			(type default)
		)
		(layer "In1.Cu")
	)
	(gr_line
		(start 14.478 -23.4823)
		(end 16.9291 -23.4823)
		(stroke
			(width 0.381)
			(type default)
		)
		(layer "In1.Cu")
	)
	(gr_line
		(start 14.549882 0.199898)
		(end 14.549882 14.029944)
		(stroke
			(width 1.524)
			(type default)
		)
		(layer "In1.Cu")
	)
	(gr_line
		(start 14.549882 14.029944)
		(end 15.050008 14.53007)
		(stroke
			(width 1.524)
			(type default)
		)
		(layer "In1.Cu")
	)
	(gr_line
		(start 15.0241 -12.8016)
		(end 15.0241 -5.9055)
		(stroke
			(width 0.381)
			(type default)
		)
		(layer "In1.Cu")
	)
	(gr_line
		(start 15.0241 -5.9055)
		(end 19.3802 -1.5494)
		(stroke
			(width 0.381)
			(type default)
		)
		(layer "In1.Cu")
	)
	(gr_line
		(start 15.050008 14.53007)
		(end 40.679878 14.53007)
		(stroke
			(width 7.5946)
			(type default)
		)
		(layer "In1.Cu")
	)
	(gr_line
		(start 15.34414 9.603486)
		(end 15.16634 9.425686)
		(stroke
			(width 0.381)
			(type default)
		)
		(layer "In1.Cu")
	)
	(gr_line
		(start 15.8115 -20.3073)
		(end 13.1953 -20.3073)
		(stroke
			(width 0.381)
			(type default)
		)
		(layer "In1.Cu")
	)
	(gr_line
		(start 15.9131 -26.0096)
		(end 14.1097 -26.0096)
		(stroke
			(width 0.381)
			(type default)
		)
		(layer "In1.Cu")
	)
	(gr_line
		(start 15.9131 -17.8943)
		(end 16.5608 -17.8943)
		(stroke
			(width 0.381)
			(type default)
		)
		(layer "In1.Cu")
	)
	(gr_line
		(start 16.3068 -25.6159)
		(end 15.9131 -26.0096)
		(stroke
			(width 0.381)
			(type default)
		)
		(layer "In1.Cu")
	)
	(gr_line
		(start 16.3068 -24.7396)
		(end 16.3068 -25.6159)
		(stroke
			(width 0.381)
			(type default)
		)
		(layer "In1.Cu")
	)
	(gr_line
		(start 16.4846 -24.5618)
		(end 16.3068 -24.7396)
		(stroke
			(width 0.381)
			(type default)
		)
		(layer "In1.Cu")
	)
	(gr_line
		(start 16.5608 -17.8943)
		(end 18.034 -16.4211)
		(stroke
			(width 0.381)
			(type default)
		)
		(layer "In1.Cu")
	)
	(gr_line
		(start 16.9291 -23.4823)
		(end 17.1831 -23.2283)
		(stroke
			(width 0.381)
			(type default)
		)
		(layer "In1.Cu")
	)
	(gr_line
		(start 17.1831 -23.2283)
		(end 17.1831 -21.6789)
		(stroke
			(width 0.381)
			(type default)
		)
		(layer "In1.Cu")
	)
	(gr_line
		(start 17.1831 -21.6789)
		(end 15.8115 -20.3073)
		(stroke
			(width 0.381)
			(type default)
		)
		(layer "In1.Cu")
	)
	(gr_line
		(start 18.034 -16.4211)
		(end 18.034 -15.8115)
		(stroke
			(width 0.381)
			(type default)
		)
		(layer "In1.Cu")
	)
	(gr_line
		(start 18.034 -15.8115)
		(end 15.0241 -12.8016)
		(stroke
			(width 0.381)
			(type default)
		)
		(layer "In1.Cu")
	)
	(gr_line
		(start 18.2245 -28.4099)
		(end 19.7866 -26.8478)
		(stroke
			(width 0.381)
			(type default)
		)
		(layer "In1.Cu")
	)
	(gr_line
		(start 18.4404 -24.5618)
		(end 16.4846 -24.5618)
		(stroke
			(width 0.381)
			(type default)
		)
		(layer "In1.Cu")
	)
	(gr_line
		(start 19.0881 9.6012)
		(end 14.9606 9.6012)
		(stroke
			(width 0.381)
			(type default)
		)
		(layer "In1.Cu")
	)
	(gr_line
		(start 19.3802 -1.5494)
		(end 19.3802 9.3091)
		(stroke
			(width 0.381)
			(type default)
		)
		(layer "In1.Cu")
	)
	(gr_line
		(start 19.3802 9.3091)
		(end 19.0881 9.6012)
		(stroke
			(width 0.381)
			(type default)
		)
		(layer "In1.Cu")
	)
	(gr_line
		(start 19.7866 -26.8478)
		(end 19.7866 -25.908)
		(stroke
			(width 0.381)
			(type default)
		)
		(layer "In1.Cu")
	)
	(gr_line
		(start 19.7866 -25.908)
		(end 18.4404 -24.5618)
		(stroke
			(width 0.381)
			(type default)
		)
		(layer "In1.Cu")
	)
	(gr_line
		(start 40.679878 14.53007)
		(end 41.180004 14.029944)
		(stroke
			(width 1.524)
			(type default)
		)
		(layer "In1.Cu")
	)
	(gr_arc
		(start 41.180004 9.329928)
		(mid 42.380154 8.129778)
		(end 43.58005 9.329928)
		(stroke
			(width 1.524)
			(type default)
		)
		(layer "In1.Cu")
	)
	(gr_line
		(start 41.180004 14.029944)
		(end 41.180004 9.329928)
		(stroke
			(width 1.524)
			(type default)
		)
		(layer "In1.Cu")
	)
	(gr_line
		(start 43.58005 9.329928)
		(end 43.58005 14.029944)
		(stroke
			(width 1.524)
			(type default)
		)
		(layer "In1.Cu")
	)
	(gr_line
		(start 43.58005 14.029944)
		(end 44.079922 14.53007)
		(stroke
			(width 1.524)
			(type default)
		)
		(layer "In1.Cu")
	)
	(gr_line
		(start 44.079922 14.53007)
		(end 98.49993 14.53007)
		(stroke
			(width 7.5946)
			(type default)
		)
		(layer "In1.Cu")
	)
	(gr_line
		(start 44.6024 -32.308546)
		(end 45.602906 -34.308542)
		(stroke
			(width 0.2)
			(type default)
		)
		(layer "In1.Cu")
	)
	(gr_line
		(start 44.6024 -11.988546)
		(end 45.602906 -13.988542)
		(stroke
			(width 0.2)
			(type default)
		)
		(layer "In1.Cu")
	)
	(gr_arc
		(start 45.556424 -31.831026)
		(mid 44.840652 -31.592774)
		(end 44.6024 -32.308546)
		(stroke
			(width 0.2)
			(type default)
		)
		(layer "In1.Cu")
	)
	(gr_arc
		(start 45.556424 -11.511026)
		(mid 44.840652 -11.272774)
		(end 44.6024 -11.988546)
		(stroke
			(width 0.2)
			(type default)
		)
		(layer "In1.Cu")
	)
	(gr_line
		(start 45.602906 -34.308542)
		(end 45.60316 -34.308542)
		(stroke
			(width 0.2)
			(type default)
		)
		(layer "In1.Cu")
	)
	(gr_line
		(start 45.602906 -27.808682)
		(end 46.602396 -29.808678)
		(stroke
			(width 0.2)
			(type default)
		)
		(layer "In1.Cu")
	)
	(gr_line
		(start 45.602906 -13.988542)
		(end 45.60316 -13.988542)
		(stroke
			(width 0.2)
			(type default)
		)
		(layer "In1.Cu")
	)
	(gr_line
		(start 45.602906 -7.488682)
		(end 46.602396 -9.488678)
		(stroke
			(width 0.2)
			(type default)
		)
		(layer "In1.Cu")
	)
	(gr_arc
		(start 45.60316 -34.308542)
		(mid 46.31878 -34.546997)
		(end 46.557184 -33.831276)
		(stroke
			(width 0.2)
			(type default)
		)
		(layer "In1.Cu")
	)
	(gr_line
		(start 45.60316 -27.808682)
		(end 45.602906 -27.808682)
		(stroke
			(width 0.2)
			(type default)
		)
		(layer "In1.Cu")
	)
	(gr_arc
		(start 45.60316 -13.988542)
		(mid 46.31878 -14.226997)
		(end 46.557184 -13.511276)
		(stroke
			(width 0.2)
			(type default)
		)
		(layer "In1.Cu")
	)
	(gr_line
		(start 45.60316 -7.488682)
		(end 45.602906 -7.488682)
		(stroke
			(width 0.2)
			(type default)
		)
		(layer "In1.Cu")
	)
	(gr_line
		(start 46.557184 -33.831276)
		(end 45.556424 -31.831026)
		(stroke
			(width 0.2)
			(type default)
		)
		(layer "In1.Cu")
	)
	(gr_arc
		(start 46.557184 -27.33167)
		(mid 45.841666 -27.093164)
		(end 45.60316 -27.808682)
		(stroke
			(width 0.2)
			(type default)
		)
		(layer "In1.Cu")
	)
	(gr_line
		(start 46.557184 -13.511276)
		(end 45.556424 -11.511026)
		(stroke
			(width 0.2)
			(type default)
		)
		(layer "In1.Cu")
	)
	(gr_arc
		(start 46.557184 -7.01167)
		(mid 45.841666 -6.773164)
		(end 45.60316 -7.488682)
		(stroke
			(width 0.2)
			(type default)
		)
		(layer "In1.Cu")
	)
	(gr_line
		(start 46.557438 -27.33167)
		(end 46.557184 -27.33167)
		(stroke
			(width 0.2)
			(type default)
		)
		(layer "In1.Cu")
	)
	(gr_line
		(start 46.557438 -7.01167)
		(end 46.557184 -7.01167)
		(stroke
			(width 0.2)
			(type default)
		)
		(layer "In1.Cu")
	)
	(gr_arc
		(start 46.602396 -29.808678)
		(mid 47.318066 -30.047616)
		(end 47.556674 -29.33192)
		(stroke
			(width 0.2)
			(type default)
		)
		(layer "In1.Cu")
	)
	(gr_arc
		(start 46.602396 -9.488678)
		(mid 47.318066 -9.727616)
		(end 47.556674 -9.01192)
		(stroke
			(width 0.2)
			(type default)
		)
		(layer "In1.Cu")
	)
	(gr_line
		(start 47.556674 -29.33192)
		(end 47.556928 -29.33192)
		(stroke
			(width 0.2)
			(type default)
		)
		(layer "In1.Cu")
	)
	(gr_line
		(start 47.556674 -9.01192)
		(end 47.556928 -9.01192)
		(stroke
			(width 0.2)
			(type default)
		)
		(layer "In1.Cu")
	)
	(gr_line
		(start 47.556928 -29.33192)
		(end 46.557438 -27.33167)
		(stroke
			(width 0.2)
			(type default)
		)
		(layer "In1.Cu")
	)
	(gr_line
		(start 47.556928 -9.01192)
		(end 46.557438 -7.01167)
		(stroke
			(width 0.2)
			(type default)
		)
		(layer "In1.Cu")
	)
	(gr_line
		(start 47.603156 -33.83153)
		(end 47.60341 -33.83153)
		(stroke
			(width 0.2)
			(type default)
		)
		(layer "In1.Cu")
	)
	(gr_line
		(start 47.603156 -13.51153)
		(end 47.60341 -13.51153)
		(stroke
			(width 0.2)
			(type default)
		)
		(layer "In1.Cu")
	)
	(gr_arc
		(start 47.60341 -33.83153)
		(mid 47.841916 -34.547048)
		(end 48.557434 -34.308542)
		(stroke
			(width 0.2)
			(type default)
		)
		(layer "In1.Cu")
	)
	(gr_arc
		(start 47.60341 -13.51153)
		(mid 47.841916 -14.227048)
		(end 48.557434 -13.988542)
		(stroke
			(width 0.2)
			(type default)
		)
		(layer "In1.Cu")
	)
	(gr_line
		(start 48.557434 -34.308542)
		(end 48.557688 -34.308542)
		(stroke
			(width 0.2)
			(type default)
		)
		(layer "In1.Cu")
	)
	(gr_line
		(start 48.557434 -13.988542)
		(end 48.557688 -13.988542)
		(stroke
			(width 0.2)
			(type default)
		)
		(layer "In1.Cu")
	)
	(gr_line
		(start 48.557688 -34.308542)
		(end 49.556924 -32.308546)
		(stroke
			(width 0.2)
			(type default)
		)
		(layer "In1.Cu")
	)
	(gr_line
		(start 48.557688 -13.988542)
		(end 49.556924 -11.988546)
		(stroke
			(width 0.2)
			(type default)
		)
		(layer "In1.Cu")
	)
	(gr_line
		(start 48.602646 -31.83128)
		(end 47.603156 -33.83153)
		(stroke
			(width 0.2)
			(type default)
		)
		(layer "In1.Cu")
	)
	(gr_line
		(start 48.602646 -11.51128)
		(end 47.603156 -13.51153)
		(stroke
			(width 0.2)
			(type default)
		)
		(layer "In1.Cu")
	)
	(gr_line
		(start 48.6029 -31.83128)
		(end 48.602646 -31.83128)
		(stroke
			(width 0.2)
			(type default)
		)
		(layer "In1.Cu")
	)
	(gr_line
		(start 48.6029 -11.51128)
		(end 48.602646 -11.51128)
		(stroke
			(width 0.2)
			(type default)
		)
		(layer "In1.Cu")
	)
	(gr_arc
		(start 49.556924 -32.308546)
		(mid 49.31857 -31.592723)
		(end 48.6029 -31.83128)
		(stroke
			(width 0.2)
			(type default)
		)
		(layer "In1.Cu")
	)
	(gr_arc
		(start 49.556924 -11.988546)
		(mid 49.31857 -11.272723)
		(end 48.6029 -11.51128)
		(stroke
			(width 0.2)
			(type default)
		)
		(layer "In1.Cu")
	)
	(gr_line
		(start 50.602896 -29.33192)
		(end 50.60315 -29.33192)
		(stroke
			(width 0.2)
			(type default)
		)
		(layer "In1.Cu")
	)
	(gr_line
		(start 50.602896 -9.01192)
		(end 50.60315 -9.01192)
		(stroke
			(width 0.2)
			(type default)
		)
		(layer "In1.Cu")
	)
	(gr_arc
		(start 50.60315 -29.33192)
		(mid 50.841656 -30.047438)
		(end 51.557174 -29.808932)
		(stroke
			(width 0.2)
			(type default)
		)
		(layer "In1.Cu")
	)
	(gr_arc
		(start 50.60315 -9.01192)
		(mid 50.841656 -9.727438)
		(end 51.557174 -9.488932)
		(stroke
			(width 0.2)
			(type default)
		)
		(layer "In1.Cu")
	)
	(gr_line
		(start 51.557174 -29.808932)
		(end 51.557428 -29.808932)
		(stroke
			(width 0.2)
			(type default)
		)
		(layer "In1.Cu")
	)
	(gr_line
		(start 51.557174 -9.488932)
		(end 51.557428 -9.488932)
		(stroke
			(width 0.2)
			(type default)
		)
		(layer "In1.Cu")
	)
	(gr_line
		(start 51.557428 -29.808932)
		(end 52.556664 -27.808936)
		(stroke
			(width 0.2)
			(type default)
		)
		(layer "In1.Cu")
	)
	(gr_line
		(start 51.557428 -9.488932)
		(end 52.556664 -7.488936)
		(stroke
			(width 0.2)
			(type default)
		)
		(layer "In1.Cu")
	)
	(gr_line
		(start 51.602386 -27.33167)
		(end 50.602896 -29.33192)
		(stroke
			(width 0.2)
			(type default)
		)
		(layer "In1.Cu")
	)
	(gr_line
		(start 51.602386 -7.01167)
		(end 50.602896 -9.01192)
		(stroke
			(width 0.2)
			(type default)
		)
		(layer "In1.Cu")
	)
	(gr_line
		(start 51.60264 -27.33167)
		(end 51.602386 -27.33167)
		(stroke
			(width 0.2)
			(type default)
		)
		(layer "In1.Cu")
	)
	(gr_line
		(start 51.60264 -7.01167)
		(end 51.602386 -7.01167)
		(stroke
			(width 0.2)
			(type default)
		)
		(layer "In1.Cu")
	)
	(gr_arc
		(start 52.556664 -27.808936)
		(mid 52.31831 -27.093113)
		(end 51.60264 -27.33167)
		(stroke
			(width 0.2)
			(type default)
		)
		(layer "In1.Cu")
	)
	(gr_arc
		(start 52.556664 -7.488936)
		(mid 52.31831 -6.773113)
		(end 51.60264 -7.01167)
		(stroke
			(width 0.2)
			(type default)
		)
		(layer "In1.Cu")
	)
	(gr_line
		(start 52.603146 -32.308292)
		(end 53.602636 -34.308288)
		(stroke
			(width 0.2)
			(type default)
		)
		(layer "In1.Cu")
	)
	(gr_line
		(start 52.603146 -11.988292)
		(end 53.602636 -13.988288)
		(stroke
			(width 0.2)
			(type default)
		)
		(layer "In1.Cu")
	)
	(gr_line
		(start 52.6034 -32.308292)
		(end 52.603146 -32.308292)
		(stroke
			(width 0.2)
			(type default)
		)
		(layer "In1.Cu")
	)
	(gr_line
		(start 52.6034 -11.988292)
		(end 52.603146 -11.988292)
		(stroke
			(width 0.2)
			(type default)
		)
		(layer "In1.Cu")
	)
	(gr_arc
		(start 53.557424 -31.83128)
		(mid 52.841906 -31.592774)
		(end 52.6034 -32.308292)
		(stroke
			(width 0.2)
			(type default)
		)
		(layer "In1.Cu")
	)
	(gr_arc
		(start 53.557424 -11.51128)
		(mid 52.841906 -11.272774)
		(end 52.6034 -11.988292)
		(stroke
			(width 0.2)
			(type default)
		)
		(layer "In1.Cu")
	)
	(gr_line
		(start 53.557678 -31.83128)
		(end 53.557424 -31.83128)
		(stroke
			(width 0.2)
			(type default)
		)
		(layer "In1.Cu")
	)
	(gr_line
		(start 53.557678 -11.51128)
		(end 53.557424 -11.51128)
		(stroke
			(width 0.2)
			(type default)
		)
		(layer "In1.Cu")
	)
	(gr_arc
		(start 53.602636 -34.308288)
		(mid 54.318306 -34.547226)
		(end 54.556914 -33.83153)
		(stroke
			(width 0.2)
			(type default)
		)
		(layer "In1.Cu")
	)
	(gr_arc
		(start 53.602636 -13.988288)
		(mid 54.318306 -14.227226)
		(end 54.556914 -13.51153)
		(stroke
			(width 0.2)
			(type default)
		)
		(layer "In1.Cu")
	)
	(gr_line
		(start 54.556914 -33.83153)
		(end 54.557168 -33.83153)
		(stroke
			(width 0.2)
			(type default)
		)
		(layer "In1.Cu")
	)
	(gr_line
		(start 54.556914 -13.51153)
		(end 54.557168 -13.51153)
		(stroke
			(width 0.2)
			(type default)
		)
		(layer "In1.Cu")
	)
	(gr_line
		(start 54.557168 -33.83153)
		(end 53.557678 -31.83128)
		(stroke
			(width 0.2)
			(type default)
		)
		(layer "In1.Cu")
	)
	(gr_line
		(start 54.557168 -13.51153)
		(end 53.557678 -11.51128)
		(stroke
			(width 0.2)
			(type default)
		)
		(layer "In1.Cu")
	)
	(gr_arc
		(start 54.60238 -29.331666)
		(mid 54.840632 -30.047438)
		(end 55.556404 -29.809186)
		(stroke
			(width 0.2)
			(type default)
		)
		(layer "In1.Cu")
	)
	(gr_arc
		(start 54.60238 -9.011666)
		(mid 54.840632 -9.727438)
		(end 55.556404 -9.489186)
		(stroke
			(width 0.2)
			(type default)
		)
		(layer "In1.Cu")
	)
	(gr_line
		(start 55.556404 -29.809186)
		(end 56.557164 -27.80919)
		(stroke
			(width 0.2)
			(type default)
		)
		(layer "In1.Cu")
	)
	(gr_line
		(start 55.556404 -9.489186)
		(end 56.557164 -7.48919)
		(stroke
			(width 0.2)
			(type default)
		)
		(layer "In1.Cu")
	)
	(gr_line
		(start 55.60314 -27.331416)
		(end 54.60238 -29.331666)
		(stroke
			(width 0.2)
			(type default)
		)
		(layer "In1.Cu")
	)
	(gr_line
		(start 55.60314 -7.011416)
		(end 54.60238 -9.011666)
		(stroke
			(width 0.2)
			(type default)
		)
		(layer "In1.Cu")
	)
	(gr_line
		(start 56.557164 -27.80919)
		(end 56.557164 -27.808936)
		(stroke
			(width 0.2)
			(type default)
		)
		(layer "In1.Cu")
	)
	(gr_arc
		(start 56.557164 -27.808936)
		(mid 56.318912 -27.093164)
		(end 55.60314 -27.331416)
		(stroke
			(width 0.2)
			(type default)
		)
		(layer "In1.Cu")
	)
	(gr_line
		(start 56.557164 -7.48919)
		(end 56.557164 -7.488936)
		(stroke
			(width 0.2)
			(type default)
		)
		(layer "In1.Cu")
	)
	(gr_arc
		(start 56.557164 -7.488936)
		(mid 56.318912 -6.773164)
		(end 55.60314 -7.011416)
		(stroke
			(width 0.2)
			(type default)
		)
		(layer "In1.Cu")
	)
	(gr_line
		(start 56.60263 -32.308546)
		(end 57.603136 -34.308542)
		(stroke
			(width 0.2)
			(type default)
		)
		(layer "In1.Cu")
	)
	(gr_line
		(start 56.60263 -11.988546)
		(end 57.603136 -13.988542)
		(stroke
			(width 0.2)
			(type default)
		)
		(layer "In1.Cu")
	)
	(gr_arc
		(start 57.556654 -31.831026)
		(mid 56.840882 -31.592774)
		(end 56.60263 -32.308546)
		(stroke
			(width 0.2)
			(type default)
		)
		(layer "In1.Cu")
	)
	(gr_arc
		(start 57.556654 -11.511026)
		(mid 56.840882 -11.272774)
		(end 56.60263 -11.988546)
		(stroke
			(width 0.2)
			(type default)
		)
		(layer "In1.Cu")
	)
	(gr_line
		(start 57.603136 -34.308542)
		(end 57.60339 -34.308542)
		(stroke
			(width 0.2)
			(type default)
		)
		(layer "In1.Cu")
	)
	(gr_line
		(start 57.603136 -13.988542)
		(end 57.60339 -13.988542)
		(stroke
			(width 0.2)
			(type default)
		)
		(layer "In1.Cu")
	)
	(gr_arc
		(start 57.60339 -34.308542)
		(mid 58.31901 -34.546997)
		(end 58.557414 -33.831276)
		(stroke
			(width 0.2)
			(type default)
		)
		(layer "In1.Cu")
	)
	(gr_arc
		(start 57.60339 -13.988542)
		(mid 58.31901 -14.226997)
		(end 58.557414 -13.511276)
		(stroke
			(width 0.2)
			(type default)
		)
		(layer "In1.Cu")
	)
	(gr_line
		(start 58.557414 -33.831276)
		(end 57.556654 -31.831026)
		(stroke
			(width 0.2)
			(type default)
		)
		(layer "In1.Cu")
	)
	(gr_line
		(start 58.557414 -13.511276)
		(end 57.556654 -11.511026)
		(stroke
			(width 0.2)
			(type default)
		)
		(layer "In1.Cu")
	)
	(gr_line
		(start 58.602626 -29.33192)
		(end 58.60288 -29.33192)
		(stroke
			(width 0.2)
			(type default)
		)
		(layer "In1.Cu")
	)
	(gr_line
		(start 58.602626 -9.01192)
		(end 58.60288 -9.01192)
		(stroke
			(width 0.2)
			(type default)
		)
		(layer "In1.Cu")
	)
	(gr_arc
		(start 58.60288 -29.33192)
		(mid 58.841386 -30.047438)
		(end 59.556904 -29.808932)
		(stroke
			(width 0.2)
			(type default)
		)
		(layer "In1.Cu")
	)
	(gr_arc
		(start 58.60288 -9.01192)
		(mid 58.841386 -9.727438)
		(end 59.556904 -9.488932)
		(stroke
			(width 0.2)
			(type default)
		)
		(layer "In1.Cu")
	)
	(gr_line
		(start 59.556904 -29.808932)
		(end 59.557158 -29.808932)
		(stroke
			(width 0.2)
			(type default)
		)
		(layer "In1.Cu")
	)
	(gr_line
		(start 59.556904 -9.488932)
		(end 59.557158 -9.488932)
		(stroke
			(width 0.2)
			(type default)
		)
		(layer "In1.Cu")
	)
	(gr_line
		(start 59.557158 -29.808932)
		(end 60.556394 -27.808936)
		(stroke
			(width 0.2)
			(type default)
		)
		(layer "In1.Cu")
	)
	(gr_line
		(start 59.557158 -9.488932)
		(end 60.556394 -7.488936)
		(stroke
			(width 0.2)
			(type default)
		)
		(layer "In1.Cu")
	)
	(gr_line
		(start 59.602116 -27.33167)
		(end 58.602626 -29.33192)
		(stroke
			(width 0.2)
			(type default)
		)
		(layer "In1.Cu")
	)
	(gr_line
		(start 59.602116 -7.01167)
		(end 58.602626 -9.01192)
		(stroke
			(width 0.2)
			(type default)
		)
		(layer "In1.Cu")
	)
	(gr_line
		(start 59.60237 -27.33167)
		(end 59.602116 -27.33167)
		(stroke
			(width 0.2)
			(type default)
		)
		(layer "In1.Cu")
	)
	(gr_line
		(start 59.60237 -7.01167)
		(end 59.602116 -7.01167)
		(stroke
			(width 0.2)
			(type default)
		)
		(layer "In1.Cu")
	)
	(gr_arc
		(start 60.556394 -27.808936)
		(mid 60.31804 -27.093113)
		(end 59.60237 -27.33167)
		(stroke
			(width 0.2)
			(type default)
		)
		(layer "In1.Cu")
	)
	(gr_arc
		(start 60.556394 -7.488936)
		(mid 60.31804 -6.773113)
		(end 59.60237 -7.01167)
		(stroke
			(width 0.2)
			(type default)
		)
		(layer "In1.Cu")
	)
	(gr_line
		(start 60.602876 -32.308292)
		(end 61.602366 -34.308288)
		(stroke
			(width 0.2)
			(type default)
		)
		(layer "In1.Cu")
	)
	(gr_line
		(start 60.602876 -11.988292)
		(end 61.602366 -13.988288)
		(stroke
			(width 0.2)
			(type default)
		)
		(layer "In1.Cu")
	)
	(gr_line
		(start 60.60313 -32.308292)
		(end 60.602876 -32.308292)
		(stroke
			(width 0.2)
			(type default)
		)
		(layer "In1.Cu")
	)
	(gr_line
		(start 60.60313 -11.988292)
		(end 60.602876 -11.988292)
		(stroke
			(width 0.2)
			(type default)
		)
		(layer "In1.Cu")
	)
	(gr_arc
		(start 61.557154 -31.83128)
		(mid 60.841636 -31.592774)
		(end 60.60313 -32.308292)
		(stroke
			(width 0.2)
			(type default)
		)
		(layer "In1.Cu")
	)
	(gr_arc
		(start 61.557154 -11.51128)
		(mid 60.841636 -11.272774)
		(end 60.60313 -11.988292)
		(stroke
			(width 0.2)
			(type default)
		)
		(layer "In1.Cu")
	)
	(gr_line
		(start 61.557408 -31.83128)
		(end 61.557154 -31.83128)
		(stroke
			(width 0.2)
			(type default)
		)
		(layer "In1.Cu")
	)
	(gr_line
		(start 61.557408 -11.51128)
		(end 61.557154 -11.51128)
		(stroke
			(width 0.2)
			(type default)
		)
		(layer "In1.Cu")
	)
	(gr_arc
		(start 61.602366 -34.308288)
		(mid 62.318036 -34.547226)
		(end 62.556644 -33.83153)
		(stroke
			(width 0.2)
			(type default)
		)
		(layer "In1.Cu")
	)
	(gr_arc
		(start 61.602366 -13.988288)
		(mid 62.318036 -14.227226)
		(end 62.556644 -13.51153)
		(stroke
			(width 0.2)
			(type default)
		)
		(layer "In1.Cu")
	)
	(gr_line
		(start 62.556644 -33.83153)
		(end 62.556898 -33.83153)
		(stroke
			(width 0.2)
			(type default)
		)
		(layer "In1.Cu")
	)
	(gr_line
		(start 62.556644 -13.51153)
		(end 62.556898 -13.51153)
		(stroke
			(width 0.2)
			(type default)
		)
		(layer "In1.Cu")
	)
	(gr_line
		(start 62.556898 -33.83153)
		(end 61.557408 -31.83128)
		(stroke
			(width 0.2)
			(type default)
		)
		(layer "In1.Cu")
	)
	(gr_line
		(start 62.556898 -13.51153)
		(end 61.557408 -11.51128)
		(stroke
			(width 0.2)
			(type default)
		)
		(layer "In1.Cu")
	)
	(gr_line
		(start 63.602616 -33.83153)
		(end 63.60287 -33.83153)
		(stroke
			(width 0.2)
			(type default)
		)
		(layer "In1.Cu")
	)
	(gr_line
		(start 63.602616 -13.51153)
		(end 63.60287 -13.51153)
		(stroke
			(width 0.2)
			(type default)
		)
		(layer "In1.Cu")
	)
	(gr_arc
		(start 63.60287 -33.83153)
		(mid 63.841376 -34.547048)
		(end 64.556894 -34.308542)
		(stroke
			(width 0.2)
			(type default)
		)
		(layer "In1.Cu")
	)
	(gr_arc
		(start 63.60287 -13.51153)
		(mid 63.841376 -14.227048)
		(end 64.556894 -13.988542)
		(stroke
			(width 0.2)
			(type default)
		)
		(layer "In1.Cu")
	)
	(gr_line
		(start 64.556894 -34.308542)
		(end 64.557148 -34.308542)
		(stroke
			(width 0.2)
			(type default)
		)
		(layer "In1.Cu")
	)
	(gr_line
		(start 64.556894 -13.988542)
		(end 64.557148 -13.988542)
		(stroke
			(width 0.2)
			(type default)
		)
		(layer "In1.Cu")
	)
	(gr_line
		(start 64.557148 -34.308542)
		(end 65.556384 -32.308546)
		(stroke
			(width 0.2)
			(type default)
		)
		(layer "In1.Cu")
	)
	(gr_line
		(start 64.557148 -13.988542)
		(end 65.556384 -11.988546)
		(stroke
			(width 0.2)
			(type default)
		)
		(layer "In1.Cu")
	)
	(gr_line
		(start 64.602106 -31.83128)
		(end 63.602616 -33.83153)
		(stroke
			(width 0.2)
			(type default)
		)
		(layer "In1.Cu")
	)
	(gr_line
		(start 64.602106 -11.51128)
		(end 63.602616 -13.51153)
		(stroke
			(width 0.2)
			(type default)
		)
		(layer "In1.Cu")
	)
	(gr_line
		(start 64.60236 -31.83128)
		(end 64.602106 -31.83128)
		(stroke
			(width 0.2)
			(type default)
		)
		(layer "In1.Cu")
	)
	(gr_arc
		(start 64.60236 -29.331666)
		(mid 64.840612 -30.047438)
		(end 65.556384 -29.809186)
		(stroke
			(width 0.2)
			(type default)
		)
		(layer "In1.Cu")
	)
	(gr_line
		(start 64.60236 -11.51128)
		(end 64.602106 -11.51128)
		(stroke
			(width 0.2)
			(type default)
		)
		(layer "In1.Cu")
	)
	(gr_arc
		(start 64.60236 -9.011666)
		(mid 64.840612 -9.727438)
		(end 65.556384 -9.489186)
		(stroke
			(width 0.2)
			(type default)
		)
		(layer "In1.Cu")
	)
	(gr_arc
		(start 65.556384 -32.308546)
		(mid 65.31803 -31.592723)
		(end 64.60236 -31.83128)
		(stroke
			(width 0.2)
			(type default)
		)
		(layer "In1.Cu")
	)
	(gr_line
		(start 65.556384 -29.809186)
		(end 66.557144 -27.80919)
		(stroke
			(width 0.2)
			(type default)
		)
		(layer "In1.Cu")
	)
	(gr_arc
		(start 65.556384 -11.988546)
		(mid 65.31803 -11.272723)
		(end 64.60236 -11.51128)
		(stroke
			(width 0.2)
			(type default)
		)
		(layer "In1.Cu")
	)
	(gr_line
		(start 65.556384 -9.489186)
		(end 66.557144 -7.48919)
		(stroke
			(width 0.2)
			(type default)
		)
		(layer "In1.Cu")
	)
	(gr_line
		(start 65.60312 -27.331416)
		(end 64.60236 -29.331666)
		(stroke
			(width 0.2)
			(type default)
		)
		(layer "In1.Cu")
	)
	(gr_line
		(start 65.60312 -7.011416)
		(end 64.60236 -9.011666)
		(stroke
			(width 0.2)
			(type default)
		)
		(layer "In1.Cu")
	)
	(gr_line
		(start 66.557144 -27.80919)
		(end 66.557144 -27.808936)
		(stroke
			(width 0.2)
			(type default)
		)
		(layer "In1.Cu")
	)
	(gr_arc
		(start 66.557144 -27.808936)
		(mid 66.318892 -27.093164)
		(end 65.60312 -27.331416)
		(stroke
			(width 0.2)
			(type default)
		)
		(layer "In1.Cu")
	)
	(gr_line
		(start 66.557144 -7.48919)
		(end 66.557144 -7.488936)
		(stroke
			(width 0.2)
			(type default)
		)
		(layer "In1.Cu")
	)
	(gr_arc
		(start 66.557144 -7.488936)
		(mid 66.318892 -6.773164)
		(end 65.60312 -7.011416)
		(stroke
			(width 0.2)
			(type default)
		)
		(layer "In1.Cu")
	)
	(gr_line
		(start 66.60261 -32.308546)
		(end 67.603116 -34.308542)
		(stroke
			(width 0.2)
			(type default)
		)
		(layer "In1.Cu")
	)
	(gr_line
		(start 66.60261 -11.988546)
		(end 67.603116 -13.988542)
		(stroke
			(width 0.2)
			(type default)
		)
		(layer "In1.Cu")
	)
	(gr_arc
		(start 67.556634 -31.831026)
		(mid 66.840862 -31.592774)
		(end 66.60261 -32.308546)
		(stroke
			(width 0.2)
			(type default)
		)
		(layer "In1.Cu")
	)
	(gr_arc
		(start 67.556634 -11.511026)
		(mid 66.840862 -11.272774)
		(end 66.60261 -11.988546)
		(stroke
			(width 0.2)
			(type default)
		)
		(layer "In1.Cu")
	)
	(gr_line
		(start 67.603116 -34.308542)
		(end 67.60337 -34.308542)
		(stroke
			(width 0.2)
			(type default)
		)
		(layer "In1.Cu")
	)
	(gr_line
		(start 67.603116 -13.988542)
		(end 67.60337 -13.988542)
		(stroke
			(width 0.2)
			(type default)
		)
		(layer "In1.Cu")
	)
	(gr_arc
		(start 67.60337 -34.308542)
		(mid 68.31899 -34.546997)
		(end 68.557394 -33.831276)
		(stroke
			(width 0.2)
			(type default)
		)
		(layer "In1.Cu")
	)
	(gr_arc
		(start 67.60337 -13.988542)
		(mid 68.31899 -14.226997)
		(end 68.557394 -13.511276)
		(stroke
			(width 0.2)
			(type default)
		)
		(layer "In1.Cu")
	)
	(gr_line
		(start 68.557394 -33.831276)
		(end 67.556634 -31.831026)
		(stroke
			(width 0.2)
			(type default)
		)
		(layer "In1.Cu")
	)
	(gr_line
		(start 68.557394 -13.511276)
		(end 67.556634 -11.511026)
		(stroke
			(width 0.2)
			(type default)
		)
		(layer "In1.Cu")
	)
	(gr_line
		(start 68.602606 -29.33192)
		(end 68.60286 -29.33192)
		(stroke
			(width 0.2)
			(type default)
		)
		(layer "In1.Cu")
	)
	(gr_line
		(start 68.602606 -9.01192)
		(end 68.60286 -9.01192)
		(stroke
			(width 0.2)
			(type default)
		)
		(layer "In1.Cu")
	)
	(gr_arc
		(start 68.60286 -29.33192)
		(mid 68.841366 -30.047438)
		(end 69.556884 -29.808932)
		(stroke
			(width 0.2)
			(type default)
		)
		(layer "In1.Cu")
	)
	(gr_arc
		(start 68.60286 -9.01192)
		(mid 68.841366 -9.727438)
		(end 69.556884 -9.488932)
		(stroke
			(width 0.2)
			(type default)
		)
		(layer "In1.Cu")
	)
	(gr_line
		(start 69.556884 -29.808932)
		(end 69.557138 -29.808932)
		(stroke
			(width 0.2)
			(type default)
		)
		(layer "In1.Cu")
	)
	(gr_line
		(start 69.556884 -9.488932)
		(end 69.557138 -9.488932)
		(stroke
			(width 0.2)
			(type default)
		)
		(layer "In1.Cu")
	)
	(gr_line
		(start 69.557138 -29.808932)
		(end 70.556374 -27.808936)
		(stroke
			(width 0.2)
			(type default)
		)
		(layer "In1.Cu")
	)
	(gr_line
		(start 69.557138 -9.488932)
		(end 70.556374 -7.488936)
		(stroke
			(width 0.2)
			(type default)
		)
		(layer "In1.Cu")
	)
	(gr_line
		(start 69.602096 -27.33167)
		(end 68.602606 -29.33192)
		(stroke
			(width 0.2)
			(type default)
		)
		(layer "In1.Cu")
	)
	(gr_line
		(start 69.602096 -7.01167)
		(end 68.602606 -9.01192)
		(stroke
			(width 0.2)
			(type default)
		)
		(layer "In1.Cu")
	)
	(gr_line
		(start 69.60235 -27.33167)
		(end 69.602096 -27.33167)
		(stroke
			(width 0.2)
			(type default)
		)
		(layer "In1.Cu")
	)
	(gr_line
		(start 69.60235 -7.01167)
		(end 69.602096 -7.01167)
		(stroke
			(width 0.2)
			(type default)
		)
		(layer "In1.Cu")
	)
	(gr_arc
		(start 70.556374 -27.808936)
		(mid 70.31802 -27.093113)
		(end 69.60235 -27.33167)
		(stroke
			(width 0.2)
			(type default)
		)
		(layer "In1.Cu")
	)
	(gr_arc
		(start 70.556374 -7.488936)
		(mid 70.31802 -6.773113)
		(end 69.60235 -7.01167)
		(stroke
			(width 0.2)
			(type default)
		)
		(layer "In1.Cu")
	)
	(gr_line
		(start 70.602856 -32.308292)
		(end 71.602346 -34.308288)
		(stroke
			(width 0.2)
			(type default)
		)
		(layer "In1.Cu")
	)
	(gr_line
		(start 70.602856 -11.988292)
		(end 71.602346 -13.988288)
		(stroke
			(width 0.2)
			(type default)
		)
		(layer "In1.Cu")
	)
	(gr_line
		(start 70.60311 -32.308292)
		(end 70.602856 -32.308292)
		(stroke
			(width 0.2)
			(type default)
		)
		(layer "In1.Cu")
	)
	(gr_line
		(start 70.60311 -11.988292)
		(end 70.602856 -11.988292)
		(stroke
			(width 0.2)
			(type default)
		)
		(layer "In1.Cu")
	)
	(gr_arc
		(start 71.557134 -31.83128)
		(mid 70.841616 -31.592774)
		(end 70.60311 -32.308292)
		(stroke
			(width 0.2)
			(type default)
		)
		(layer "In1.Cu")
	)
	(gr_arc
		(start 71.557134 -11.51128)
		(mid 70.841616 -11.272774)
		(end 70.60311 -11.988292)
		(stroke
			(width 0.2)
			(type default)
		)
		(layer "In1.Cu")
	)
	(gr_line
		(start 71.557388 -31.83128)
		(end 71.557134 -31.83128)
		(stroke
			(width 0.2)
			(type default)
		)
		(layer "In1.Cu")
	)
	(gr_line
		(start 71.557388 -11.51128)
		(end 71.557134 -11.51128)
		(stroke
			(width 0.2)
			(type default)
		)
		(layer "In1.Cu")
	)
	(gr_arc
		(start 71.602346 -34.308288)
		(mid 72.318016 -34.547226)
		(end 72.556624 -33.83153)
		(stroke
			(width 0.2)
			(type default)
		)
		(layer "In1.Cu")
	)
	(gr_arc
		(start 71.602346 -13.988288)
		(mid 72.318016 -14.227226)
		(end 72.556624 -13.51153)
		(stroke
			(width 0.2)
			(type default)
		)
		(layer "In1.Cu")
	)
	(gr_line
		(start 72.556624 -33.83153)
		(end 72.556878 -33.83153)
		(stroke
			(width 0.2)
			(type default)
		)
		(layer "In1.Cu")
	)
	(gr_line
		(start 72.556624 -13.51153)
		(end 72.556878 -13.51153)
		(stroke
			(width 0.2)
			(type default)
		)
		(layer "In1.Cu")
	)
	(gr_line
		(start 72.556878 -33.83153)
		(end 71.557388 -31.83128)
		(stroke
			(width 0.2)
			(type default)
		)
		(layer "In1.Cu")
	)
	(gr_line
		(start 72.556878 -13.51153)
		(end 71.557388 -11.51128)
		(stroke
			(width 0.2)
			(type default)
		)
		(layer "In1.Cu")
	)
	(gr_line
		(start 72.603106 -29.33192)
		(end 72.60336 -29.33192)
		(stroke
			(width 0.2)
			(type default)
		)
		(layer "In1.Cu")
	)
	(gr_line
		(start 72.603106 -9.01192)
		(end 72.60336 -9.01192)
		(stroke
			(width 0.2)
			(type default)
		)
		(layer "In1.Cu")
	)
	(gr_arc
		(start 72.60336 -29.33192)
		(mid 72.841866 -30.047438)
		(end 73.557384 -29.808932)
		(stroke
			(width 0.2)
			(type default)
		)
		(layer "In1.Cu")
	)
	(gr_arc
		(start 72.60336 -9.01192)
		(mid 72.841866 -9.727438)
		(end 73.557384 -9.488932)
		(stroke
			(width 0.2)
			(type default)
		)
		(layer "In1.Cu")
	)
	(gr_line
		(start 73.557384 -29.808932)
		(end 73.557638 -29.808932)
		(stroke
			(width 0.2)
			(type default)
		)
		(layer "In1.Cu")
	)
	(gr_line
		(start 73.557384 -9.488932)
		(end 73.557638 -9.488932)
		(stroke
			(width 0.2)
			(type default)
		)
		(layer "In1.Cu")
	)
	(gr_line
		(start 73.557638 -29.808932)
		(end 74.556874 -27.808936)
		(stroke
			(width 0.2)
			(type default)
		)
		(layer "In1.Cu")
	)
	(gr_line
		(start 73.557638 -9.488932)
		(end 74.556874 -7.488936)
		(stroke
			(width 0.2)
			(type default)
		)
		(layer "In1.Cu")
	)
	(gr_line
		(start 73.602596 -27.33167)
		(end 72.603106 -29.33192)
		(stroke
			(width 0.2)
			(type default)
		)
		(layer "In1.Cu")
	)
	(gr_line
		(start 73.602596 -7.01167)
		(end 72.603106 -9.01192)
		(stroke
			(width 0.2)
			(type default)
		)
		(layer "In1.Cu")
	)
	(gr_line
		(start 73.60285 -27.33167)
		(end 73.602596 -27.33167)
		(stroke
			(width 0.2)
			(type default)
		)
		(layer "In1.Cu")
	)
	(gr_line
		(start 73.60285 -7.01167)
		(end 73.602596 -7.01167)
		(stroke
			(width 0.2)
			(type default)
		)
		(layer "In1.Cu")
	)
	(gr_arc
		(start 74.556874 -27.808936)
		(mid 74.31852 -27.093113)
		(end 73.60285 -27.33167)
		(stroke
			(width 0.2)
			(type default)
		)
		(layer "In1.Cu")
	)
	(gr_arc
		(start 74.556874 -7.488936)
		(mid 74.31852 -6.773113)
		(end 73.60285 -7.01167)
		(stroke
			(width 0.2)
			(type default)
		)
		(layer "In1.Cu")
	)
	(gr_line
		(start 74.60234 -32.308546)
		(end 75.602846 -34.308542)
		(stroke
			(width 0.2)
			(type default)
		)
		(layer "In1.Cu")
	)
	(gr_line
		(start 74.60234 -11.988546)
		(end 75.602846 -13.988542)
		(stroke
			(width 0.2)
			(type default)
		)
		(layer "In1.Cu")
	)
	(gr_arc
		(start 75.556364 -31.831026)
		(mid 74.840592 -31.592774)
		(end 74.60234 -32.308546)
		(stroke
			(width 0.2)
			(type default)
		)
		(layer "In1.Cu")
	)
	(gr_arc
		(start 75.556364 -11.511026)
		(mid 74.840592 -11.272774)
		(end 74.60234 -11.988546)
		(stroke
			(width 0.2)
			(type default)
		)
		(layer "In1.Cu")
	)
	(gr_line
		(start 75.602846 -34.308542)
		(end 75.6031 -34.308542)
		(stroke
			(width 0.2)
			(type default)
		)
		(layer "In1.Cu")
	)
	(gr_line
		(start 75.602846 -13.988542)
		(end 75.6031 -13.988542)
		(stroke
			(width 0.2)
			(type default)
		)
		(layer "In1.Cu")
	)
	(gr_arc
		(start 75.6031 -34.308542)
		(mid 76.31872 -34.546997)
		(end 76.557124 -33.831276)
		(stroke
			(width 0.2)
			(type default)
		)
		(layer "In1.Cu")
	)
	(gr_arc
		(start 75.6031 -13.988542)
		(mid 76.31872 -14.226997)
		(end 76.557124 -13.511276)
		(stroke
			(width 0.2)
			(type default)
		)
		(layer "In1.Cu")
	)
	(gr_line
		(start 76.557124 -33.831276)
		(end 75.556364 -31.831026)
		(stroke
			(width 0.2)
			(type default)
		)
		(layer "In1.Cu")
	)
	(gr_line
		(start 76.557124 -13.511276)
		(end 75.556364 -11.511026)
		(stroke
			(width 0.2)
			(type default)
		)
		(layer "In1.Cu")
	)
	(gr_arc
		(start 76.60259 -29.331666)
		(mid 76.840842 -30.047438)
		(end 77.556614 -29.809186)
		(stroke
			(width 0.2)
			(type default)
		)
		(layer "In1.Cu")
	)
	(gr_arc
		(start 76.60259 -9.011666)
		(mid 76.840842 -9.727438)
		(end 77.556614 -9.489186)
		(stroke
			(width 0.2)
			(type default)
		)
		(layer "In1.Cu")
	)
	(gr_line
		(start 77.305154 7.343902)
		(end 78.3209 7.343902)
		(stroke
			(width 0.2)
			(type default)
		)
		(layer "In1.Cu")
	)
	(gr_arc
		(start 77.305154 8.060182)
		(mid 76.947014 7.702042)
		(end 77.305154 7.343902)
		(stroke
			(width 0.2)
			(type default)
		)
		(layer "In1.Cu")
	)
	(gr_line
		(start 77.556614 -29.809186)
		(end 78.557374 -27.80919)
		(stroke
			(width 0.2)
			(type default)
		)
		(layer "In1.Cu")
	)
	(gr_line
		(start 77.556614 -9.489186)
		(end 78.557374 -7.48919)
		(stroke
			(width 0.2)
			(type default)
		)
		(layer "In1.Cu")
	)
	(gr_line
		(start 77.60335 -27.331416)
		(end 76.60259 -29.331666)
		(stroke
			(width 0.2)
			(type default)
		)
		(layer "In1.Cu")
	)
	(gr_line
		(start 77.60335 -7.011416)
		(end 76.60259 -9.011666)
		(stroke
			(width 0.2)
			(type default)
		)
		(layer "In1.Cu")
	)
	(gr_arc
		(start 78.3209 7.343902)
		(mid 78.679294 7.701915)
		(end 78.321154 8.060182)
		(stroke
			(width 0.2)
			(type default)
		)
		(layer "In1.Cu")
	)
	(gr_line
		(start 78.321154 8.060182)
		(end 77.305154 8.060182)
		(stroke
			(width 0.2)
			(type default)
		)
		(layer "In1.Cu")
	)
	(gr_line
		(start 78.557374 -27.80919)
		(end 78.557374 -27.808936)
		(stroke
			(width 0.2)
			(type default)
		)
		(layer "In1.Cu")
	)
	(gr_arc
		(start 78.557374 -27.808936)
		(mid 78.319122 -27.093164)
		(end 77.60335 -27.331416)
		(stroke
			(width 0.2)
			(type default)
		)
		(layer "In1.Cu")
	)
	(gr_line
		(start 78.557374 -7.48919)
		(end 78.557374 -7.488936)
		(stroke
			(width 0.2)
			(type default)
		)
		(layer "In1.Cu")
	)
	(gr_arc
		(start 78.557374 -7.488936)
		(mid 78.319122 -6.773164)
		(end 77.60335 -7.011416)
		(stroke
			(width 0.2)
			(type default)
		)
		(layer "In1.Cu")
	)
	(gr_line
		(start 78.602586 -32.308292)
		(end 79.602076 -34.308288)
		(stroke
			(width 0.2)
			(type default)
		)
		(layer "In1.Cu")
	)
	(gr_line
		(start 78.602586 -11.988292)
		(end 79.602076 -13.988288)
		(stroke
			(width 0.2)
			(type default)
		)
		(layer "In1.Cu")
	)
	(gr_line
		(start 78.60284 -32.308292)
		(end 78.602586 -32.308292)
		(stroke
			(width 0.2)
			(type default)
		)
		(layer "In1.Cu")
	)
	(gr_line
		(start 78.60284 -11.988292)
		(end 78.602586 -11.988292)
		(stroke
			(width 0.2)
			(type default)
		)
		(layer "In1.Cu")
	)
	(gr_line
		(start 78.631288 4.807712)
		(end 79.647034 4.807712)
		(stroke
			(width 0.2)
			(type default)
		)
		(layer "In1.Cu")
	)
	(gr_arc
		(start 78.631288 5.523992)
		(mid 78.273148 5.165852)
		(end 78.631288 4.807712)
		(stroke
			(width 0.2)
			(type default)
		)
		(layer "In1.Cu")
	)
	(gr_arc
		(start 79.556864 -31.83128)
		(mid 78.841346 -31.592774)
		(end 78.60284 -32.308292)
		(stroke
			(width 0.2)
			(type default)
		)
		(layer "In1.Cu")
	)
	(gr_arc
		(start 79.556864 -11.51128)
		(mid 78.841346 -11.272774)
		(end 78.60284 -11.988292)
		(stroke
			(width 0.2)
			(type default)
		)
		(layer "In1.Cu")
	)
	(gr_line
		(start 79.557118 -31.83128)
		(end 79.556864 -31.83128)
		(stroke
			(width 0.2)
			(type default)
		)
		(layer "In1.Cu")
	)
	(gr_line
		(start 79.557118 -11.51128)
		(end 79.556864 -11.51128)
		(stroke
			(width 0.2)
			(type default)
		)
		(layer "In1.Cu")
	)
	(gr_arc
		(start 79.602076 -34.308288)
		(mid 80.317746 -34.547226)
		(end 80.556354 -33.83153)
		(stroke
			(width 0.2)
			(type default)
		)
		(layer "In1.Cu")
	)
	(gr_arc
		(start 79.602076 -13.988288)
		(mid 80.317746 -14.227226)
		(end 80.556354 -13.51153)
		(stroke
			(width 0.2)
			(type default)
		)
		(layer "In1.Cu")
	)
	(gr_arc
		(start 79.647034 4.807712)
		(mid 80.005428 5.165725)
		(end 79.647288 5.523992)
		(stroke
			(width 0.2)
			(type default)
		)
		(layer "In1.Cu")
	)
	(gr_line
		(start 79.647288 5.523992)
		(end 78.631288 5.523992)
		(stroke
			(width 0.2)
			(type default)
		)
		(layer "In1.Cu")
	)
	(gr_line
		(start 79.895954 7.343902)
		(end 80.9117 7.343902)
		(stroke
			(width 0.2)
			(type default)
		)
		(layer "In1.Cu")
	)
	(gr_arc
		(start 79.895954 8.060182)
		(mid 79.537814 7.702042)
		(end 79.895954 7.343902)
		(stroke
			(width 0.2)
			(type default)
		)
		(layer "In1.Cu")
	)
	(gr_line
		(start 80.556354 -33.83153)
		(end 80.556608 -33.83153)
		(stroke
			(width 0.2)
			(type default)
		)
		(layer "In1.Cu")
	)
	(gr_line
		(start 80.556354 -13.51153)
		(end 80.556608 -13.51153)
		(stroke
			(width 0.2)
			(type default)
		)
		(layer "In1.Cu")
	)
	(gr_line
		(start 80.556608 -33.83153)
		(end 79.557118 -31.83128)
		(stroke
			(width 0.2)
			(type default)
		)
		(layer "In1.Cu")
	)
	(gr_line
		(start 80.556608 -13.51153)
		(end 79.557118 -11.51128)
		(stroke
			(width 0.2)
			(type default)
		)
		(layer "In1.Cu")
	)
	(gr_arc
		(start 80.9117 7.343902)
		(mid 81.270094 7.701915)
		(end 80.911954 8.060182)
		(stroke
			(width 0.2)
			(type default)
		)
		(layer "In1.Cu")
	)
	(gr_line
		(start 80.911954 8.060182)
		(end 79.895954 8.060182)
		(stroke
			(width 0.2)
			(type default)
		)
		(layer "In1.Cu")
	)
	(gr_line
		(start 81.222088 4.807712)
		(end 82.237834 4.807712)
		(stroke
			(width 0.2)
			(type default)
		)
		(layer "In1.Cu")
	)
	(gr_arc
		(start 81.222088 5.523992)
		(mid 80.863948 5.165852)
		(end 81.222088 4.807712)
		(stroke
			(width 0.2)
			(type default)
		)
		(layer "In1.Cu")
	)
	(gr_line
		(start 81.60258 -27.808936)
		(end 82.603086 -29.808932)
		(stroke
			(width 0.2)
			(type default)
		)
		(layer "In1.Cu")
	)
	(gr_line
		(start 81.60258 -7.488936)
		(end 82.603086 -9.488932)
		(stroke
			(width 0.2)
			(type default)
		)
		(layer "In1.Cu")
	)
	(gr_arc
		(start 82.237834 4.807712)
		(mid 82.596228 5.165725)
		(end 82.238088 5.523992)
		(stroke
			(width 0.2)
			(type default)
		)
		(layer "In1.Cu")
	)
	(gr_line
		(start 82.238088 5.523992)
		(end 81.222088 5.523992)
		(stroke
			(width 0.2)
			(type default)
		)
		(layer "In1.Cu")
	)
	(gr_line
		(start 82.486754 7.343902)
		(end 83.5025 7.343902)
		(stroke
			(width 0.2)
			(type default)
		)
		(layer "In1.Cu")
	)
	(gr_arc
		(start 82.486754 8.060182)
		(mid 82.128614 7.702042)
		(end 82.486754 7.343902)
		(stroke
			(width 0.2)
			(type default)
		)
		(layer "In1.Cu")
	)
	(gr_arc
		(start 82.556604 -27.331416)
		(mid 81.840832 -27.093164)
		(end 81.60258 -27.808936)
		(stroke
			(width 0.2)
			(type default)
		)
		(layer "In1.Cu")
	)
	(gr_arc
		(start 82.556604 -7.011416)
		(mid 81.840832 -6.773164)
		(end 81.60258 -7.488936)
		(stroke
			(width 0.2)
			(type default)
		)
		(layer "In1.Cu")
	)
	(gr_line
		(start 82.603086 -29.808932)
		(end 82.60334 -29.808932)
		(stroke
			(width 0.2)
			(type default)
		)
		(layer "In1.Cu")
	)
	(gr_line
		(start 82.603086 -9.488932)
		(end 82.60334 -9.488932)
		(stroke
			(width 0.2)
			(type default)
		)
		(layer "In1.Cu")
	)
	(gr_arc
		(start 82.60334 -29.808932)
		(mid 83.31896 -30.047387)
		(end 83.557364 -29.331666)
		(stroke
			(width 0.2)
			(type default)
		)
		(layer "In1.Cu")
	)
	(gr_arc
		(start 82.60334 -9.488932)
		(mid 83.31896 -9.727387)
		(end 83.557364 -9.011666)
		(stroke
			(width 0.2)
			(type default)
		)
		(layer "In1.Cu")
	)
	(gr_arc
		(start 83.5025 7.343902)
		(mid 83.860894 7.701915)
		(end 83.502754 8.060182)
		(stroke
			(width 0.2)
			(type default)
		)
		(layer "In1.Cu")
	)
	(gr_line
		(start 83.502754 8.060182)
		(end 82.486754 8.060182)
		(stroke
			(width 0.2)
			(type default)
		)
		(layer "In1.Cu")
	)
	(gr_line
		(start 83.557364 -29.331666)
		(end 82.556604 -27.331416)
		(stroke
			(width 0.2)
			(type default)
		)
		(layer "In1.Cu")
	)
	(gr_line
		(start 83.557364 -9.011666)
		(end 82.556604 -7.011416)
		(stroke
			(width 0.2)
			(type default)
		)
		(layer "In1.Cu")
	)
	(gr_line
		(start 83.602576 -33.83153)
		(end 83.60283 -33.83153)
		(stroke
			(width 0.2)
			(type default)
		)
		(layer "In1.Cu")
	)
	(gr_line
		(start 83.602576 -13.51153)
		(end 83.60283 -13.51153)
		(stroke
			(width 0.2)
			(type default)
		)
		(layer "In1.Cu")
	)
	(gr_arc
		(start 83.60283 -33.83153)
		(mid 83.841336 -34.547048)
		(end 84.556854 -34.308542)
		(stroke
			(width 0.2)
			(type default)
		)
		(layer "In1.Cu")
	)
	(gr_arc
		(start 83.60283 -13.51153)
		(mid 83.841336 -14.227048)
		(end 84.556854 -13.988542)
		(stroke
			(width 0.2)
			(type default)
		)
		(layer "In1.Cu")
	)
	(gr_line
		(start 83.812888 4.807712)
		(end 84.828634 4.807712)
		(stroke
			(width 0.2)
			(type default)
		)
		(layer "In1.Cu")
	)
	(gr_arc
		(start 83.812888 5.523992)
		(mid 83.454748 5.165852)
		(end 83.812888 4.807712)
		(stroke
			(width 0.2)
			(type default)
		)
		(layer "In1.Cu")
	)
	(gr_line
		(start 84.556854 -34.308542)
		(end 84.557108 -34.308542)
		(stroke
			(width 0.2)
			(type default)
		)
		(layer "In1.Cu")
	)
	(gr_line
		(start 84.556854 -13.988542)
		(end 84.557108 -13.988542)
		(stroke
			(width 0.2)
			(type default)
		)
		(layer "In1.Cu")
	)
	(gr_line
		(start 84.557108 -34.308542)
		(end 85.556344 -32.308546)
		(stroke
			(width 0.2)
			(type default)
		)
		(layer "In1.Cu")
	)
	(gr_line
		(start 84.557108 -13.988542)
		(end 85.556344 -11.988546)
		(stroke
			(width 0.2)
			(type default)
		)
		(layer "In1.Cu")
	)
	(gr_line
		(start 84.602066 -31.83128)
		(end 83.602576 -33.83153)
		(stroke
			(width 0.2)
			(type default)
		)
		(layer "In1.Cu")
	)
	(gr_line
		(start 84.602066 -11.51128)
		(end 83.602576 -13.51153)
		(stroke
			(width 0.2)
			(type default)
		)
		(layer "In1.Cu")
	)
	(gr_line
		(start 84.60232 -31.83128)
		(end 84.602066 -31.83128)
		(stroke
			(width 0.2)
			(type default)
		)
		(layer "In1.Cu")
	)
	(gr_line
		(start 84.60232 -11.51128)
		(end 84.602066 -11.51128)
		(stroke
			(width 0.2)
			(type default)
		)
		(layer "In1.Cu")
	)
	(gr_arc
		(start 84.828634 4.807712)
		(mid 85.187028 5.165725)
		(end 84.828888 5.523992)
		(stroke
			(width 0.2)
			(type default)
		)
		(layer "In1.Cu")
	)
	(gr_line
		(start 84.828888 5.523992)
		(end 83.812888 5.523992)
		(stroke
			(width 0.2)
			(type default)
		)
		(layer "In1.Cu")
	)
	(gr_line
		(start 85.077554 7.343902)
		(end 86.0933 7.343902)
		(stroke
			(width 0.2)
			(type default)
		)
		(layer "In1.Cu")
	)
	(gr_arc
		(start 85.077554 8.060182)
		(mid 84.719414 7.702042)
		(end 85.077554 7.343902)
		(stroke
			(width 0.2)
			(type default)
		)
		(layer "In1.Cu")
	)
	(gr_arc
		(start 85.556344 -32.308546)
		(mid 85.31799 -31.592723)
		(end 84.60232 -31.83128)
		(stroke
			(width 0.2)
			(type default)
		)
		(layer "In1.Cu")
	)
	(gr_arc
		(start 85.556344 -11.988546)
		(mid 85.31799 -11.272723)
		(end 84.60232 -11.51128)
		(stroke
			(width 0.2)
			(type default)
		)
		(layer "In1.Cu")
	)
	(gr_line
		(start 85.602826 -27.808682)
		(end 86.602316 -29.808678)
		(stroke
			(width 0.2)
			(type default)
		)
		(layer "In1.Cu")
	)
	(gr_line
		(start 85.602826 -7.488682)
		(end 86.602316 -9.488678)
		(stroke
			(width 0.2)
			(type default)
		)
		(layer "In1.Cu")
	)
	(gr_line
		(start 85.60308 -27.808682)
		(end 85.602826 -27.808682)
		(stroke
			(width 0.2)
			(type default)
		)
		(layer "In1.Cu")
	)
	(gr_line
		(start 85.60308 -7.488682)
		(end 85.602826 -7.488682)
		(stroke
			(width 0.2)
			(type default)
		)
		(layer "In1.Cu")
	)
	(gr_arc
		(start 86.0933 7.343902)
		(mid 86.451694 7.701915)
		(end 86.093554 8.060182)
		(stroke
			(width 0.2)
			(type default)
		)
		(layer "In1.Cu")
	)
	(gr_line
		(start 86.093554 8.060182)
		(end 85.077554 8.060182)
		(stroke
			(width 0.2)
			(type default)
		)
		(layer "In1.Cu")
	)
	(gr_line
		(start 86.403688 4.807712)
		(end 87.419434 4.807712)
		(stroke
			(width 0.2)
			(type default)
		)
		(layer "In1.Cu")
	)
	(gr_arc
		(start 86.403688 5.523992)
		(mid 86.045548 5.165852)
		(end 86.403688 4.807712)
		(stroke
			(width 0.2)
			(type default)
		)
		(layer "In1.Cu")
	)
	(gr_arc
		(start 86.557104 -27.33167)
		(mid 85.841586 -27.093164)
		(end 85.60308 -27.808682)
		(stroke
			(width 0.2)
			(type default)
		)
		(layer "In1.Cu")
	)
	(gr_arc
		(start 86.557104 -7.01167)
		(mid 85.841586 -6.773164)
		(end 85.60308 -7.488682)
		(stroke
			(width 0.2)
			(type default)
		)
		(layer "In1.Cu")
	)
	(gr_line
		(start 86.557358 -27.33167)
		(end 86.557104 -27.33167)
		(stroke
			(width 0.2)
			(type default)
		)
		(layer "In1.Cu")
	)
	(gr_line
		(start 86.557358 -7.01167)
		(end 86.557104 -7.01167)
		(stroke
			(width 0.2)
			(type default)
		)
		(layer "In1.Cu")
	)
	(gr_arc
		(start 86.602316 -29.808678)
		(mid 87.317986 -30.047616)
		(end 87.556594 -29.33192)
		(stroke
			(width 0.2)
			(type default)
		)
		(layer "In1.Cu")
	)
	(gr_arc
		(start 86.602316 -9.488678)
		(mid 87.317986 -9.727616)
		(end 87.556594 -9.01192)
		(stroke
			(width 0.2)
			(type default)
		)
		(layer "In1.Cu")
	)
	(gr_arc
		(start 87.419434 4.807712)
		(mid 87.777828 5.165725)
		(end 87.419688 5.523992)
		(stroke
			(width 0.2)
			(type default)
		)
		(layer "In1.Cu")
	)
	(gr_line
		(start 87.419688 5.523992)
		(end 86.403688 5.523992)
		(stroke
			(width 0.2)
			(type default)
		)
		(layer "In1.Cu")
	)
	(gr_line
		(start 87.556594 -29.33192)
		(end 87.556848 -29.33192)
		(stroke
			(width 0.2)
			(type default)
		)
		(layer "In1.Cu")
	)
	(gr_line
		(start 87.556594 -9.01192)
		(end 87.556848 -9.01192)
		(stroke
			(width 0.2)
			(type default)
		)
		(layer "In1.Cu")
	)
	(gr_line
		(start 87.556848 -29.33192)
		(end 86.557358 -27.33167)
		(stroke
			(width 0.2)
			(type default)
		)
		(layer "In1.Cu")
	)
	(gr_line
		(start 87.556848 -9.01192)
		(end 86.557358 -7.01167)
		(stroke
			(width 0.2)
			(type default)
		)
		(layer "In1.Cu")
	)
	(gr_line
		(start 87.603076 -33.83153)
		(end 87.60333 -33.83153)
		(stroke
			(width 0.2)
			(type default)
		)
		(layer "In1.Cu")
	)
	(gr_line
		(start 87.603076 -13.51153)
		(end 87.60333 -13.51153)
		(stroke
			(width 0.2)
			(type default)
		)
		(layer "In1.Cu")
	)
	(gr_arc
		(start 87.60333 -33.83153)
		(mid 87.841836 -34.547048)
		(end 88.557354 -34.308542)
		(stroke
			(width 0.2)
			(type default)
		)
		(layer "In1.Cu")
	)
	(gr_arc
		(start 87.60333 -13.51153)
		(mid 87.841836 -14.227048)
		(end 88.557354 -13.988542)
		(stroke
			(width 0.2)
			(type default)
		)
		(layer "In1.Cu")
	)
	(gr_line
		(start 87.668354 7.343902)
		(end 88.6841 7.343902)
		(stroke
			(width 0.2)
			(type default)
		)
		(layer "In1.Cu")
	)
	(gr_arc
		(start 87.668354 8.060182)
		(mid 87.310214 7.702042)
		(end 87.668354 7.343902)
		(stroke
			(width 0.2)
			(type default)
		)
		(layer "In1.Cu")
	)
	(gr_line
		(start 88.557354 -34.308542)
		(end 88.557608 -34.308542)
		(stroke
			(width 0.2)
			(type default)
		)
		(layer "In1.Cu")
	)
	(gr_line
		(start 88.557354 -13.988542)
		(end 88.557608 -13.988542)
		(stroke
			(width 0.2)
			(type default)
		)
		(layer "In1.Cu")
	)
	(gr_line
		(start 88.557608 -34.308542)
		(end 89.556844 -32.308546)
		(stroke
			(width 0.2)
			(type default)
		)
		(layer "In1.Cu")
	)
	(gr_line
		(start 88.557608 -13.988542)
		(end 89.556844 -11.988546)
		(stroke
			(width 0.2)
			(type default)
		)
		(layer "In1.Cu")
	)
	(gr_line
		(start 88.602566 -31.83128)
		(end 87.603076 -33.83153)
		(stroke
			(width 0.2)
			(type default)
		)
		(layer "In1.Cu")
	)
	(gr_line
		(start 88.602566 -11.51128)
		(end 87.603076 -13.51153)
		(stroke
			(width 0.2)
			(type default)
		)
		(layer "In1.Cu")
	)
	(gr_line
		(start 88.60282 -31.83128)
		(end 88.602566 -31.83128)
		(stroke
			(width 0.2)
			(type default)
		)
		(layer "In1.Cu")
	)
	(gr_line
		(start 88.60282 -11.51128)
		(end 88.602566 -11.51128)
		(stroke
			(width 0.2)
			(type default)
		)
		(layer "In1.Cu")
	)
	(gr_arc
		(start 88.6841 7.343902)
		(mid 89.042494 7.701915)
		(end 88.684354 8.060182)
		(stroke
			(width 0.2)
			(type default)
		)
		(layer "In1.Cu")
	)
	(gr_line
		(start 88.684354 8.060182)
		(end 87.668354 8.060182)
		(stroke
			(width 0.2)
			(type default)
		)
		(layer "In1.Cu")
	)
	(gr_line
		(start 88.994488 4.807712)
		(end 90.010234 4.807712)
		(stroke
			(width 0.2)
			(type default)
		)
		(layer "In1.Cu")
	)
	(gr_arc
		(start 88.994488 5.523992)
		(mid 88.636348 5.165852)
		(end 88.994488 4.807712)
		(stroke
			(width 0.2)
			(type default)
		)
		(layer "In1.Cu")
	)
	(gr_arc
		(start 89.556844 -32.308546)
		(mid 89.31849 -31.592723)
		(end 88.60282 -31.83128)
		(stroke
			(width 0.2)
			(type default)
		)
		(layer "In1.Cu")
	)
	(gr_arc
		(start 89.556844 -11.988546)
		(mid 89.31849 -11.272723)
		(end 88.60282 -11.51128)
		(stroke
			(width 0.2)
			(type default)
		)
		(layer "In1.Cu")
	)
	(gr_line
		(start 89.60231 -27.808936)
		(end 90.602816 -29.808932)
		(stroke
			(width 0.2)
			(type default)
		)
		(layer "In1.Cu")
	)
	(gr_line
		(start 89.60231 -7.488936)
		(end 90.602816 -9.488932)
		(stroke
			(width 0.2)
			(type default)
		)
		(layer "In1.Cu")
	)
	(gr_arc
		(start 90.010234 4.807712)
		(mid 90.368628 5.165725)
		(end 90.010488 5.523992)
		(stroke
			(width 0.2)
			(type default)
		)
		(layer "In1.Cu")
	)
	(gr_line
		(start 90.010488 5.523992)
		(end 88.994488 5.523992)
		(stroke
			(width 0.2)
			(type default)
		)
		(layer "In1.Cu")
	)
	(gr_line
		(start 90.259154 7.343902)
		(end 91.2749 7.343902)
		(stroke
			(width 0.2)
			(type default)
		)
		(layer "In1.Cu")
	)
	(gr_arc
		(start 90.259154 8.060182)
		(mid 89.901014 7.702042)
		(end 90.259154 7.343902)
		(stroke
			(width 0.2)
			(type default)
		)
		(layer "In1.Cu")
	)
	(gr_arc
		(start 90.556334 -27.331416)
		(mid 89.840562 -27.093164)
		(end 89.60231 -27.808936)
		(stroke
			(width 0.2)
			(type default)
		)
		(layer "In1.Cu")
	)
	(gr_arc
		(start 90.556334 -7.011416)
		(mid 89.840562 -6.773164)
		(end 89.60231 -7.488936)
		(stroke
			(width 0.2)
			(type default)
		)
		(layer "In1.Cu")
	)
	(gr_line
		(start 90.602816 -29.808932)
		(end 90.60307 -29.808932)
		(stroke
			(width 0.2)
			(type default)
		)
		(layer "In1.Cu")
	)
	(gr_line
		(start 90.602816 -9.488932)
		(end 90.60307 -9.488932)
		(stroke
			(width 0.2)
			(type default)
		)
		(layer "In1.Cu")
	)
	(gr_arc
		(start 90.60307 -29.808932)
		(mid 91.31869 -30.047387)
		(end 91.557094 -29.331666)
		(stroke
			(width 0.2)
			(type default)
		)
		(layer "In1.Cu")
	)
	(gr_arc
		(start 90.60307 -9.488932)
		(mid 91.31869 -9.727387)
		(end 91.557094 -9.011666)
		(stroke
			(width 0.2)
			(type default)
		)
		(layer "In1.Cu")
	)
	(gr_arc
		(start 91.2749 7.343902)
		(mid 91.633294 7.701915)
		(end 91.275154 8.060182)
		(stroke
			(width 0.2)
			(type default)
		)
		(layer "In1.Cu")
	)
	(gr_line
		(start 91.275154 8.060182)
		(end 90.259154 8.060182)
		(stroke
			(width 0.2)
			(type default)
		)
		(layer "In1.Cu")
	)
	(gr_line
		(start 91.557094 -29.331666)
		(end 90.556334 -27.331416)
		(stroke
			(width 0.2)
			(type default)
		)
		(layer "In1.Cu")
	)
	(gr_line
		(start 91.557094 -9.011666)
		(end 90.556334 -7.011416)
		(stroke
			(width 0.2)
			(type default)
		)
		(layer "In1.Cu")
	)
	(gr_line
		(start 91.585288 4.807712)
		(end 92.601034 4.807712)
		(stroke
			(width 0.2)
			(type default)
		)
		(layer "In1.Cu")
	)
	(gr_arc
		(start 91.585288 5.523992)
		(mid 91.227148 5.165852)
		(end 91.585288 4.807712)
		(stroke
			(width 0.2)
			(type default)
		)
		(layer "In1.Cu")
	)
	(gr_arc
		(start 91.60256 -33.831276)
		(mid 91.840812 -34.547048)
		(end 92.556584 -34.308796)
		(stroke
			(width 0.2)
			(type default)
		)
		(layer "In1.Cu")
	)
	(gr_arc
		(start 91.60256 -13.511276)
		(mid 91.840812 -14.227048)
		(end 92.556584 -13.988796)
		(stroke
			(width 0.2)
			(type default)
		)
		(layer "In1.Cu")
	)
	(gr_line
		(start 92.556584 -34.308796)
		(end 93.557344 -32.3088)
		(stroke
			(width 0.2)
			(type default)
		)
		(layer "In1.Cu")
	)
	(gr_line
		(start 92.556584 -13.988796)
		(end 93.557344 -11.9888)
		(stroke
			(width 0.2)
			(type default)
		)
		(layer "In1.Cu")
	)
	(gr_arc
		(start 92.601034 4.807712)
		(mid 92.959428 5.165725)
		(end 92.601288 5.523992)
		(stroke
			(width 0.2)
			(type default)
		)
		(layer "In1.Cu")
	)
	(gr_line
		(start 92.601288 5.523992)
		(end 91.585288 5.523992)
		(stroke
			(width 0.2)
			(type default)
		)
		(layer "In1.Cu")
	)
	(gr_line
		(start 92.60332 -31.831026)
		(end 91.60256 -33.831276)
		(stroke
			(width 0.2)
			(type default)
		)
		(layer "In1.Cu")
	)
	(gr_line
		(start 92.60332 -11.511026)
		(end 91.60256 -13.511276)
		(stroke
			(width 0.2)
			(type default)
		)
		(layer "In1.Cu")
	)
	(gr_line
		(start 92.849954 7.343902)
		(end 93.8657 7.343902)
		(stroke
			(width 0.2)
			(type default)
		)
		(layer "In1.Cu")
	)
	(gr_arc
		(start 92.849954 8.060182)
		(mid 92.491814 7.702042)
		(end 92.849954 7.343902)
		(stroke
			(width 0.2)
			(type default)
		)
		(layer "In1.Cu")
	)
	(gr_line
		(start 93.557344 -32.3088)
		(end 93.557344 -32.308546)
		(stroke
			(width 0.2)
			(type default)
		)
		(layer "In1.Cu")
	)
	(gr_arc
		(start 93.557344 -32.308546)
		(mid 93.319092 -31.592774)
		(end 92.60332 -31.831026)
		(stroke
			(width 0.2)
			(type default)
		)
		(layer "In1.Cu")
	)
	(gr_line
		(start 93.557344 -11.9888)
		(end 93.557344 -11.988546)
		(stroke
			(width 0.2)
			(type default)
		)
		(layer "In1.Cu")
	)
	(gr_arc
		(start 93.557344 -11.988546)
		(mid 93.319092 -11.272774)
		(end 92.60332 -11.511026)
		(stroke
			(width 0.2)
			(type default)
		)
		(layer "In1.Cu")
	)
	(gr_line
		(start 93.602556 -27.808682)
		(end 94.602046 -29.808678)
		(stroke
			(width 0.2)
			(type default)
		)
		(layer "In1.Cu")
	)
	(gr_line
		(start 93.602556 -7.488682)
		(end 94.602046 -9.488678)
		(stroke
			(width 0.2)
			(type default)
		)
		(layer "In1.Cu")
	)
	(gr_line
		(start 93.60281 -27.808682)
		(end 93.602556 -27.808682)
		(stroke
			(width 0.2)
			(type default)
		)
		(layer "In1.Cu")
	)
	(gr_line
		(start 93.60281 -7.488682)
		(end 93.602556 -7.488682)
		(stroke
			(width 0.2)
			(type default)
		)
		(layer "In1.Cu")
	)
	(gr_arc
		(start 93.8657 7.343902)
		(mid 94.224094 7.701915)
		(end 93.865954 8.060182)
		(stroke
			(width 0.2)
			(type default)
		)
		(layer "In1.Cu")
	)
	(gr_line
		(start 93.865954 8.060182)
		(end 92.849954 8.060182)
		(stroke
			(width 0.2)
			(type default)
		)
		(layer "In1.Cu")
	)
	(gr_line
		(start 94.176088 4.807712)
		(end 95.191834 4.807712)
		(stroke
			(width 0.2)
			(type default)
		)
		(layer "In1.Cu")
	)
	(gr_arc
		(start 94.176088 5.523992)
		(mid 93.817948 5.165852)
		(end 94.176088 4.807712)
		(stroke
			(width 0.2)
			(type default)
		)
		(layer "In1.Cu")
	)
	(gr_arc
		(start 94.556834 -27.33167)
		(mid 93.841316 -27.093164)
		(end 93.60281 -27.808682)
		(stroke
			(width 0.2)
			(type default)
		)
		(layer "In1.Cu")
	)
	(gr_arc
		(start 94.556834 -7.01167)
		(mid 93.841316 -6.773164)
		(end 93.60281 -7.488682)
		(stroke
			(width 0.2)
			(type default)
		)
		(layer "In1.Cu")
	)
	(gr_line
		(start 94.557088 -27.33167)
		(end 94.556834 -27.33167)
		(stroke
			(width 0.2)
			(type default)
		)
		(layer "In1.Cu")
	)
	(gr_line
		(start 94.557088 -7.01167)
		(end 94.556834 -7.01167)
		(stroke
			(width 0.2)
			(type default)
		)
		(layer "In1.Cu")
	)
	(gr_arc
		(start 94.602046 -29.808678)
		(mid 95.317716 -30.047616)
		(end 95.556324 -29.33192)
		(stroke
			(width 0.2)
			(type default)
		)
		(layer "In1.Cu")
	)
	(gr_arc
		(start 94.602046 -9.488678)
		(mid 95.317716 -9.727616)
		(end 95.556324 -9.01192)
		(stroke
			(width 0.2)
			(type default)
		)
		(layer "In1.Cu")
	)
	(gr_arc
		(start 95.191834 4.807712)
		(mid 95.550228 5.165725)
		(end 95.192088 5.523992)
		(stroke
			(width 0.2)
			(type default)
		)
		(layer "In1.Cu")
	)
	(gr_line
		(start 95.192088 5.523992)
		(end 94.176088 5.523992)
		(stroke
			(width 0.2)
			(type default)
		)
		(layer "In1.Cu")
	)
	(gr_line
		(start 95.440754 7.343902)
		(end 96.4565 7.343902)
		(stroke
			(width 0.2)
			(type default)
		)
		(layer "In1.Cu")
	)
	(gr_arc
		(start 95.440754 8.060182)
		(mid 95.082614 7.702042)
		(end 95.440754 7.343902)
		(stroke
			(width 0.2)
			(type default)
		)
		(layer "In1.Cu")
	)
	(gr_line
		(start 95.556324 -29.33192)
		(end 95.556578 -29.33192)
		(stroke
			(width 0.2)
			(type default)
		)
		(layer "In1.Cu")
	)
	(gr_line
		(start 95.556324 -9.01192)
		(end 95.556578 -9.01192)
		(stroke
			(width 0.2)
			(type default)
		)
		(layer "In1.Cu")
	)
	(gr_line
		(start 95.556578 -29.33192)
		(end 94.557088 -27.33167)
		(stroke
			(width 0.2)
			(type default)
		)
		(layer "In1.Cu")
	)
	(gr_line
		(start 95.556578 -9.01192)
		(end 94.557088 -7.01167)
		(stroke
			(width 0.2)
			(type default)
		)
		(layer "In1.Cu")
	)
	(gr_line
		(start 95.602806 -33.83153)
		(end 95.60306 -33.83153)
		(stroke
			(width 0.2)
			(type default)
		)
		(layer "In1.Cu")
	)
	(gr_line
		(start 95.602806 -13.51153)
		(end 95.60306 -13.51153)
		(stroke
			(width 0.2)
			(type default)
		)
		(layer "In1.Cu")
	)
	(gr_arc
		(start 95.60306 -33.83153)
		(mid 95.841566 -34.547048)
		(end 96.557084 -34.308542)
		(stroke
			(width 0.2)
			(type default)
		)
		(layer "In1.Cu")
	)
	(gr_arc
		(start 95.60306 -13.51153)
		(mid 95.841566 -14.227048)
		(end 96.557084 -13.988542)
		(stroke
			(width 0.2)
			(type default)
		)
		(layer "In1.Cu")
	)
	(gr_arc
		(start 96.4565 7.343902)
		(mid 96.814894 7.701915)
		(end 96.456754 8.060182)
		(stroke
			(width 0.2)
			(type default)
		)
		(layer "In1.Cu")
	)
	(gr_line
		(start 96.456754 8.060182)
		(end 95.440754 8.060182)
		(stroke
			(width 0.2)
			(type default)
		)
		(layer "In1.Cu")
	)
	(gr_line
		(start 96.557084 -34.308542)
		(end 96.557338 -34.308542)
		(stroke
			(width 0.2)
			(type default)
		)
		(layer "In1.Cu")
	)
	(gr_line
		(start 96.557084 -13.988542)
		(end 96.557338 -13.988542)
		(stroke
			(width 0.2)
			(type default)
		)
		(layer "In1.Cu")
	)
	(gr_line
		(start 96.557338 -34.308542)
		(end 97.556574 -32.308546)
		(stroke
			(width 0.2)
			(type default)
		)
		(layer "In1.Cu")
	)
	(gr_line
		(start 96.557338 -13.988542)
		(end 97.556574 -11.988546)
		(stroke
			(width 0.2)
			(type default)
		)
		(layer "In1.Cu")
	)
	(gr_line
		(start 96.602296 -31.83128)
		(end 95.602806 -33.83153)
		(stroke
			(width 0.2)
			(type default)
		)
		(layer "In1.Cu")
	)
	(gr_line
		(start 96.602296 -11.51128)
		(end 95.602806 -13.51153)
		(stroke
			(width 0.2)
			(type default)
		)
		(layer "In1.Cu")
	)
	(gr_line
		(start 96.60255 -31.83128)
		(end 96.602296 -31.83128)
		(stroke
			(width 0.2)
			(type default)
		)
		(layer "In1.Cu")
	)
	(gr_line
		(start 96.60255 -11.51128)
		(end 96.602296 -11.51128)
		(stroke
			(width 0.2)
			(type default)
		)
		(layer "In1.Cu")
	)
	(gr_line
		(start 96.766888 4.807712)
		(end 97.782634 4.807712)
		(stroke
			(width 0.2)
			(type default)
		)
		(layer "In1.Cu")
	)
	(gr_arc
		(start 96.766888 5.523992)
		(mid 96.408748 5.165852)
		(end 96.766888 4.807712)
		(stroke
			(width 0.2)
			(type default)
		)
		(layer "In1.Cu")
	)
	(gr_arc
		(start 97.556574 -32.308546)
		(mid 97.31822 -31.592723)
		(end 96.60255 -31.83128)
		(stroke
			(width 0.2)
			(type default)
		)
		(layer "In1.Cu")
	)
	(gr_arc
		(start 97.556574 -11.988546)
		(mid 97.31822 -11.272723)
		(end 96.60255 -11.51128)
		(stroke
			(width 0.2)
			(type default)
		)
		(layer "In1.Cu")
	)
	(gr_line
		(start 97.603056 -27.808682)
		(end 98.602546 -29.808678)
		(stroke
			(width 0.2)
			(type default)
		)
		(layer "In1.Cu")
	)
	(gr_line
		(start 97.603056 -7.488682)
		(end 98.602546 -9.488678)
		(stroke
			(width 0.2)
			(type default)
		)
		(layer "In1.Cu")
	)
	(gr_line
		(start 97.60331 -27.808682)
		(end 97.603056 -27.808682)
		(stroke
			(width 0.2)
			(type default)
		)
		(layer "In1.Cu")
	)
	(gr_line
		(start 97.60331 -7.488682)
		(end 97.603056 -7.488682)
		(stroke
			(width 0.2)
			(type default)
		)
		(layer "In1.Cu")
	)
	(gr_arc
		(start 97.782634 4.807712)
		(mid 98.141028 5.165725)
		(end 97.782888 5.523992)
		(stroke
			(width 0.2)
			(type default)
		)
		(layer "In1.Cu")
	)
	(gr_line
		(start 97.782888 5.523992)
		(end 96.766888 5.523992)
		(stroke
			(width 0.2)
			(type default)
		)
		(layer "In1.Cu")
	)
	(gr_line
		(start 98.49993 14.53007)
		(end 99.000056 14.029944)
		(stroke
			(width 1.524)
			(type default)
		)
		(layer "In1.Cu")
	)
	(gr_arc
		(start 98.557334 -27.33167)
		(mid 97.841816 -27.093164)
		(end 97.60331 -27.808682)
		(stroke
			(width 0.2)
			(type default)
		)
		(layer "In1.Cu")
	)
	(gr_arc
		(start 98.557334 -7.01167)
		(mid 97.841816 -6.773164)
		(end 97.60331 -7.488682)
		(stroke
			(width 0.2)
			(type default)
		)
		(layer "In1.Cu")
	)
	(gr_line
		(start 98.557588 -27.33167)
		(end 98.557334 -27.33167)
		(stroke
			(width 0.2)
			(type default)
		)
		(layer "In1.Cu")
	)
	(gr_line
		(start 98.557588 -7.01167)
		(end 98.557334 -7.01167)
		(stroke
			(width 0.2)
			(type default)
		)
		(layer "In1.Cu")
	)
	(gr_arc
		(start 98.602546 -29.808678)
		(mid 99.318216 -30.047616)
		(end 99.556824 -29.33192)
		(stroke
			(width 0.2)
			(type default)
		)
		(layer "In1.Cu")
	)
	(gr_arc
		(start 98.602546 -9.488678)
		(mid 99.318216 -9.727616)
		(end 99.556824 -9.01192)
		(stroke
			(width 0.2)
			(type default)
		)
		(layer "In1.Cu")
	)
	(gr_arc
		(start 99.000056 6.729984)
		(mid 99.058605 6.588635)
		(end 99.199954 6.530086)
		(stroke
			(width 1.524)
			(type default)
		)
		(layer "In1.Cu")
	)
	(gr_line
		(start 99.000056 14.029944)
		(end 99.000056 6.729984)
		(stroke
			(width 1.524)
			(type default)
		)
		(layer "In1.Cu")
	)
	(gr_line
		(start 99.199954 6.530086)
		(end 107.750102 6.530086)
		(stroke
			(width 1.524)
			(type default)
		)
		(layer "In1.Cu")
	)
	(gr_line
		(start 99.556824 -29.33192)
		(end 99.557078 -29.33192)
		(stroke
			(width 0.2)
			(type default)
		)
		(layer "In1.Cu")
	)
	(gr_line
		(start 99.556824 -9.01192)
		(end 99.557078 -9.01192)
		(stroke
			(width 0.2)
			(type default)
		)
		(layer "In1.Cu")
	)
	(gr_line
		(start 99.557078 -29.33192)
		(end 98.557588 -27.33167)
		(stroke
			(width 0.2)
			(type default)
		)
		(layer "In1.Cu")
	)
	(gr_line
		(start 99.557078 -9.01192)
		(end 98.557588 -7.01167)
		(stroke
			(width 0.2)
			(type default)
		)
		(layer "In1.Cu")
	)
	(gr_arc
		(start 99.60229 -33.831276)
		(mid 99.840542 -34.547048)
		(end 100.556314 -34.308796)
		(stroke
			(width 0.2)
			(type default)
		)
		(layer "In1.Cu")
	)
	(gr_arc
		(start 99.60229 -13.511276)
		(mid 99.840542 -14.227048)
		(end 100.556314 -13.988796)
		(stroke
			(width 0.2)
			(type default)
		)
		(layer "In1.Cu")
	)
	(gr_line
		(start 100.556314 -34.308796)
		(end 101.557074 -32.3088)
		(stroke
			(width 0.2)
			(type default)
		)
		(layer "In1.Cu")
	)
	(gr_line
		(start 100.556314 -13.988796)
		(end 101.557074 -11.9888)
		(stroke
			(width 0.2)
			(type default)
		)
		(layer "In1.Cu")
	)
	(gr_line
		(start 100.60305 -31.831026)
		(end 99.60229 -33.831276)
		(stroke
			(width 0.2)
			(type default)
		)
		(layer "In1.Cu")
	)
	(gr_line
		(start 100.60305 -11.511026)
		(end 99.60229 -13.511276)
		(stroke
			(width 0.2)
			(type default)
		)
		(layer "In1.Cu")
	)
	(gr_line
		(start 101.557074 -32.3088)
		(end 101.557074 -32.308546)
		(stroke
			(width 0.2)
			(type default)
		)
		(layer "In1.Cu")
	)
	(gr_arc
		(start 101.557074 -32.308546)
		(mid 101.318822 -31.592774)
		(end 100.60305 -31.831026)
		(stroke
			(width 0.2)
			(type default)
		)
		(layer "In1.Cu")
	)
	(gr_line
		(start 101.557074 -11.9888)
		(end 101.557074 -11.988546)
		(stroke
			(width 0.2)
			(type default)
		)
		(layer "In1.Cu")
	)
	(gr_arc
		(start 101.557074 -11.988546)
		(mid 101.318822 -11.272774)
		(end 100.60305 -11.511026)
		(stroke
			(width 0.2)
			(type default)
		)
		(layer "In1.Cu")
	)
	(gr_line
		(start 101.60254 -27.808936)
		(end 102.603046 -29.808932)
		(stroke
			(width 0.2)
			(type default)
		)
		(layer "In1.Cu")
	)
	(gr_line
		(start 101.60254 -7.488936)
		(end 102.603046 -9.488932)
		(stroke
			(width 0.2)
			(type default)
		)
		(layer "In1.Cu")
	)
	(gr_arc
		(start 102.556564 -27.331416)
		(mid 101.840792 -27.093164)
		(end 101.60254 -27.808936)
		(stroke
			(width 0.2)
			(type default)
		)
		(layer "In1.Cu")
	)
	(gr_arc
		(start 102.556564 -7.011416)
		(mid 101.840792 -6.773164)
		(end 101.60254 -7.488936)
		(stroke
			(width 0.2)
			(type default)
		)
		(layer "In1.Cu")
	)
	(gr_line
		(start 102.603046 -29.808932)
		(end 102.6033 -29.808932)
		(stroke
			(width 0.2)
			(type default)
		)
		(layer "In1.Cu")
	)
	(gr_line
		(start 102.603046 -9.488932)
		(end 102.6033 -9.488932)
		(stroke
			(width 0.2)
			(type default)
		)
		(layer "In1.Cu")
	)
	(gr_arc
		(start 102.6033 -29.808932)
		(mid 103.31892 -30.047387)
		(end 103.557324 -29.331666)
		(stroke
			(width 0.2)
			(type default)
		)
		(layer "In1.Cu")
	)
	(gr_arc
		(start 102.6033 -9.488932)
		(mid 103.31892 -9.727387)
		(end 103.557324 -9.011666)
		(stroke
			(width 0.2)
			(type default)
		)
		(layer "In1.Cu")
	)
	(gr_line
		(start 103.557324 -29.331666)
		(end 102.556564 -27.331416)
		(stroke
			(width 0.2)
			(type default)
		)
		(layer "In1.Cu")
	)
	(gr_line
		(start 103.557324 -9.011666)
		(end 102.556564 -7.011416)
		(stroke
			(width 0.2)
			(type default)
		)
		(layer "In1.Cu")
	)
	(gr_line
		(start 103.602536 -33.83153)
		(end 103.60279 -33.83153)
		(stroke
			(width 0.2)
			(type default)
		)
		(layer "In1.Cu")
	)
	(gr_line
		(start 103.602536 -13.51153)
		(end 103.60279 -13.51153)
		(stroke
			(width 0.2)
			(type default)
		)
		(layer "In1.Cu")
	)
	(gr_arc
		(start 103.60279 -33.83153)
		(mid 103.841296 -34.547048)
		(end 104.556814 -34.308542)
		(stroke
			(width 0.2)
			(type default)
		)
		(layer "In1.Cu")
	)
	(gr_arc
		(start 103.60279 -13.51153)
		(mid 103.841296 -14.227048)
		(end 104.556814 -13.988542)
		(stroke
			(width 0.2)
			(type default)
		)
		(layer "In1.Cu")
	)
	(gr_line
		(start 104.556814 -34.308542)
		(end 104.557068 -34.308542)
		(stroke
			(width 0.2)
			(type default)
		)
		(layer "In1.Cu")
	)
	(gr_line
		(start 104.556814 -13.988542)
		(end 104.557068 -13.988542)
		(stroke
			(width 0.2)
			(type default)
		)
		(layer "In1.Cu")
	)
	(gr_line
		(start 104.557068 -34.308542)
		(end 105.556304 -32.308546)
		(stroke
			(width 0.2)
			(type default)
		)
		(layer "In1.Cu")
	)
	(gr_line
		(start 104.557068 -13.988542)
		(end 105.556304 -11.988546)
		(stroke
			(width 0.2)
			(type default)
		)
		(layer "In1.Cu")
	)
	(gr_line
		(start 104.602026 -31.83128)
		(end 103.602536 -33.83153)
		(stroke
			(width 0.2)
			(type default)
		)
		(layer "In1.Cu")
	)
	(gr_line
		(start 104.602026 -11.51128)
		(end 103.602536 -13.51153)
		(stroke
			(width 0.2)
			(type default)
		)
		(layer "In1.Cu")
	)
	(gr_line
		(start 104.60228 -31.83128)
		(end 104.602026 -31.83128)
		(stroke
			(width 0.2)
			(type default)
		)
		(layer "In1.Cu")
	)
	(gr_line
		(start 104.60228 -11.51128)
		(end 104.602026 -11.51128)
		(stroke
			(width 0.2)
			(type default)
		)
		(layer "In1.Cu")
	)
	(gr_arc
		(start 105.556304 -32.308546)
		(mid 105.31795 -31.592723)
		(end 104.60228 -31.83128)
		(stroke
			(width 0.2)
			(type default)
		)
		(layer "In1.Cu")
	)
	(gr_arc
		(start 105.556304 -11.988546)
		(mid 105.31795 -11.272723)
		(end 104.60228 -11.51128)
		(stroke
			(width 0.2)
			(type default)
		)
		(layer "In1.Cu")
	)
	(gr_line
		(start 105.602786 -27.808682)
		(end 106.602276 -29.808678)
		(stroke
			(width 0.2)
			(type default)
		)
		(layer "In1.Cu")
	)
	(gr_line
		(start 105.602786 -7.488682)
		(end 106.602276 -9.488678)
		(stroke
			(width 0.2)
			(type default)
		)
		(layer "In1.Cu")
	)
	(gr_line
		(start 105.60304 -27.808682)
		(end 105.602786 -27.808682)
		(stroke
			(width 0.2)
			(type default)
		)
		(layer "In1.Cu")
	)
	(gr_line
		(start 105.60304 -7.488682)
		(end 105.602786 -7.488682)
		(stroke
			(width 0.2)
			(type default)
		)
		(layer "In1.Cu")
	)
	(gr_arc
		(start 106.557064 -27.33167)
		(mid 105.841546 -27.093164)
		(end 105.60304 -27.808682)
		(stroke
			(width 0.2)
			(type default)
		)
		(layer "In1.Cu")
	)
	(gr_arc
		(start 106.557064 -7.01167)
		(mid 105.841546 -6.773164)
		(end 105.60304 -7.488682)
		(stroke
			(width 0.2)
			(type default)
		)
		(layer "In1.Cu")
	)
	(gr_line
		(start 106.557318 -27.33167)
		(end 106.557064 -27.33167)
		(stroke
			(width 0.2)
			(type default)
		)
		(layer "In1.Cu")
	)
	(gr_line
		(start 106.557318 -7.01167)
		(end 106.557064 -7.01167)
		(stroke
			(width 0.2)
			(type default)
		)
		(layer "In1.Cu")
	)
	(gr_arc
		(start 106.602276 -29.808678)
		(mid 107.317946 -30.047616)
		(end 107.556554 -29.33192)
		(stroke
			(width 0.2)
			(type default)
		)
		(layer "In1.Cu")
	)
	(gr_arc
		(start 106.602276 -9.488678)
		(mid 107.317946 -9.727616)
		(end 107.556554 -9.01192)
		(stroke
			(width 0.2)
			(type default)
		)
		(layer "In1.Cu")
	)
	(gr_line
		(start 107.556554 -29.33192)
		(end 107.556808 -29.33192)
		(stroke
			(width 0.2)
			(type default)
		)
		(layer "In1.Cu")
	)
	(gr_line
		(start 107.556554 -9.01192)
		(end 107.556808 -9.01192)
		(stroke
			(width 0.2)
			(type default)
		)
		(layer "In1.Cu")
	)
	(gr_line
		(start 107.556808 -29.33192)
		(end 106.557318 -27.33167)
		(stroke
			(width 0.2)
			(type default)
		)
		(layer "In1.Cu")
	)
	(gr_line
		(start 107.556808 -9.01192)
		(end 106.557318 -7.01167)
		(stroke
			(width 0.2)
			(type default)
		)
		(layer "In1.Cu")
	)
	(gr_line
		(start 107.603036 -33.83153)
		(end 107.60329 -33.83153)
		(stroke
			(width 0.2)
			(type default)
		)
		(layer "In1.Cu")
	)
	(gr_line
		(start 107.603036 -13.51153)
		(end 107.60329 -13.51153)
		(stroke
			(width 0.2)
			(type default)
		)
		(layer "In1.Cu")
	)
	(gr_arc
		(start 107.60329 -33.83153)
		(mid 107.841796 -34.547048)
		(end 108.557314 -34.308542)
		(stroke
			(width 0.2)
			(type default)
		)
		(layer "In1.Cu")
	)
	(gr_arc
		(start 107.60329 -13.51153)
		(mid 107.841796 -14.227048)
		(end 108.557314 -13.988542)
		(stroke
			(width 0.2)
			(type default)
		)
		(layer "In1.Cu")
	)
	(gr_arc
		(start 107.750102 6.530086)
		(mid 107.891451 6.588635)
		(end 107.95 6.729984)
		(stroke
			(width 1.524)
			(type default)
		)
		(layer "In1.Cu")
	)
	(gr_line
		(start 107.95 6.729984)
		(end 107.95 14.029944)
		(stroke
			(width 1.524)
			(type default)
		)
		(layer "In1.Cu")
	)
	(gr_line
		(start 107.95 14.029944)
		(end 108.450126 14.53007)
		(stroke
			(width 1.524)
			(type default)
		)
		(layer "In1.Cu")
	)
	(gr_line
		(start 108.450126 14.53007)
		(end 132.700014 14.53007)
		(stroke
			(width 7.5946)
			(type default)
		)
		(layer "In1.Cu")
	)
	(gr_line
		(start 108.557314 -34.308542)
		(end 108.557568 -34.308542)
		(stroke
			(width 0.2)
			(type default)
		)
		(layer "In1.Cu")
	)
	(gr_line
		(start 108.557314 -13.988542)
		(end 108.557568 -13.988542)
		(stroke
			(width 0.2)
			(type default)
		)
		(layer "In1.Cu")
	)
	(gr_line
		(start 108.557568 -34.308542)
		(end 109.556804 -32.308546)
		(stroke
			(width 0.2)
			(type default)
		)
		(layer "In1.Cu")
	)
	(gr_line
		(start 108.557568 -13.988542)
		(end 109.556804 -11.988546)
		(stroke
			(width 0.2)
			(type default)
		)
		(layer "In1.Cu")
	)
	(gr_line
		(start 108.602526 -31.83128)
		(end 107.603036 -33.83153)
		(stroke
			(width 0.2)
			(type default)
		)
		(layer "In1.Cu")
	)
	(gr_line
		(start 108.602526 -11.51128)
		(end 107.603036 -13.51153)
		(stroke
			(width 0.2)
			(type default)
		)
		(layer "In1.Cu")
	)
	(gr_line
		(start 108.60278 -31.83128)
		(end 108.602526 -31.83128)
		(stroke
			(width 0.2)
			(type default)
		)
		(layer "In1.Cu")
	)
	(gr_line
		(start 108.60278 -11.51128)
		(end 108.602526 -11.51128)
		(stroke
			(width 0.2)
			(type default)
		)
		(layer "In1.Cu")
	)
	(gr_line
		(start 109.242606 7.384542)
		(end 110.258352 7.384542)
		(stroke
			(width 0.2)
			(type default)
		)
		(layer "In1.Cu")
	)
	(gr_arc
		(start 109.242606 8.100822)
		(mid 108.884466 7.742682)
		(end 109.242606 7.384542)
		(stroke
			(width 0.2)
			(type default)
		)
		(layer "In1.Cu")
	)
	(gr_arc
		(start 109.556804 -32.308546)
		(mid 109.31845 -31.592723)
		(end 108.60278 -31.83128)
		(stroke
			(width 0.2)
			(type default)
		)
		(layer "In1.Cu")
	)
	(gr_arc
		(start 109.556804 -11.988546)
		(mid 109.31845 -11.272723)
		(end 108.60278 -11.51128)
		(stroke
			(width 0.2)
			(type default)
		)
		(layer "In1.Cu")
	)
	(gr_line
		(start 109.60227 -27.808936)
		(end 110.602776 -29.808932)
		(stroke
			(width 0.2)
			(type default)
		)
		(layer "In1.Cu")
	)
	(gr_line
		(start 109.60227 -7.488936)
		(end 110.602776 -9.488932)
		(stroke
			(width 0.2)
			(type default)
		)
		(layer "In1.Cu")
	)
	(gr_arc
		(start 110.258352 7.384542)
		(mid 110.616746 7.742555)
		(end 110.258606 8.100822)
		(stroke
			(width 0.2)
			(type default)
		)
		(layer "In1.Cu")
	)
	(gr_line
		(start 110.258606 8.100822)
		(end 109.242606 8.100822)
		(stroke
			(width 0.2)
			(type default)
		)
		(layer "In1.Cu")
	)
	(gr_arc
		(start 110.556294 -27.331416)
		(mid 109.840522 -27.093164)
		(end 109.60227 -27.808936)
		(stroke
			(width 0.2)
			(type default)
		)
		(layer "In1.Cu")
	)
	(gr_arc
		(start 110.556294 -7.011416)
		(mid 109.840522 -6.773164)
		(end 109.60227 -7.488936)
		(stroke
			(width 0.2)
			(type default)
		)
		(layer "In1.Cu")
	)
	(gr_line
		(start 110.56874 4.848352)
		(end 111.584486 4.848352)
		(stroke
			(width 0.2)
			(type default)
		)
		(layer "In1.Cu")
	)
	(gr_arc
		(start 110.56874 5.564632)
		(mid 110.2106 5.206492)
		(end 110.56874 4.848352)
		(stroke
			(width 0.2)
			(type default)
		)
		(layer "In1.Cu")
	)
	(gr_line
		(start 110.602776 -29.808932)
		(end 110.60303 -29.808932)
		(stroke
			(width 0.2)
			(type default)
		)
		(layer "In1.Cu")
	)
	(gr_line
		(start 110.602776 -9.488932)
		(end 110.60303 -9.488932)
		(stroke
			(width 0.2)
			(type default)
		)
		(layer "In1.Cu")
	)
	(gr_arc
		(start 110.60303 -29.808932)
		(mid 111.31865 -30.047387)
		(end 111.557054 -29.331666)
		(stroke
			(width 0.2)
			(type default)
		)
		(layer "In1.Cu")
	)
	(gr_arc
		(start 110.60303 -9.488932)
		(mid 111.31865 -9.727387)
		(end 111.557054 -9.011666)
		(stroke
			(width 0.2)
			(type default)
		)
		(layer "In1.Cu")
	)
	(gr_line
		(start 111.557054 -29.331666)
		(end 110.556294 -27.331416)
		(stroke
			(width 0.2)
			(type default)
		)
		(layer "In1.Cu")
	)
	(gr_line
		(start 111.557054 -9.011666)
		(end 110.556294 -7.011416)
		(stroke
			(width 0.2)
			(type default)
		)
		(layer "In1.Cu")
	)
	(gr_arc
		(start 111.584486 4.848352)
		(mid 111.94288 5.206365)
		(end 111.58474 5.564632)
		(stroke
			(width 0.2)
			(type default)
		)
		(layer "In1.Cu")
	)
	(gr_line
		(start 111.58474 5.564632)
		(end 110.56874 5.564632)
		(stroke
			(width 0.2)
			(type default)
		)
		(layer "In1.Cu")
	)
	(gr_arc
		(start 111.60252 -33.831276)
		(mid 111.840772 -34.547048)
		(end 112.556544 -34.308796)
		(stroke
			(width 0.2)
			(type default)
		)
		(layer "In1.Cu")
	)
	(gr_arc
		(start 111.60252 -13.511276)
		(mid 111.840772 -14.227048)
		(end 112.556544 -13.988796)
		(stroke
			(width 0.2)
			(type default)
		)
		(layer "In1.Cu")
	)
	(gr_line
		(start 111.833406 7.384542)
		(end 112.849152 7.384542)
		(stroke
			(width 0.2)
			(type default)
		)
		(layer "In1.Cu")
	)
	(gr_arc
		(start 111.833406 8.100822)
		(mid 111.475266 7.742682)
		(end 111.833406 7.384542)
		(stroke
			(width 0.2)
			(type default)
		)
		(layer "In1.Cu")
	)
	(gr_line
		(start 112.556544 -34.308796)
		(end 113.557304 -32.3088)
		(stroke
			(width 0.2)
			(type default)
		)
		(layer "In1.Cu")
	)
	(gr_line
		(start 112.556544 -13.988796)
		(end 113.557304 -11.9888)
		(stroke
			(width 0.2)
			(type default)
		)
		(layer "In1.Cu")
	)
	(gr_line
		(start 112.60328 -31.831026)
		(end 111.60252 -33.831276)
		(stroke
			(width 0.2)
			(type default)
		)
		(layer "In1.Cu")
	)
	(gr_line
		(start 112.60328 -11.511026)
		(end 111.60252 -13.511276)
		(stroke
			(width 0.2)
			(type default)
		)
		(layer "In1.Cu")
	)
	(gr_arc
		(start 112.849152 7.384542)
		(mid 113.207546 7.742555)
		(end 112.849406 8.100822)
		(stroke
			(width 0.2)
			(type default)
		)
		(layer "In1.Cu")
	)
	(gr_line
		(start 112.849406 8.100822)
		(end 111.833406 8.100822)
		(stroke
			(width 0.2)
			(type default)
		)
		(layer "In1.Cu")
	)
	(gr_line
		(start 113.15954 4.848352)
		(end 114.175286 4.848352)
		(stroke
			(width 0.2)
			(type default)
		)
		(layer "In1.Cu")
	)
	(gr_arc
		(start 113.15954 5.564632)
		(mid 112.8014 5.206492)
		(end 113.15954 4.848352)
		(stroke
			(width 0.2)
			(type default)
		)
		(layer "In1.Cu")
	)
	(gr_line
		(start 113.557304 -32.3088)
		(end 113.557304 -32.308546)
		(stroke
			(width 0.2)
			(type default)
		)
		(layer "In1.Cu")
	)
	(gr_arc
		(start 113.557304 -32.308546)
		(mid 113.319052 -31.592774)
		(end 112.60328 -31.831026)
		(stroke
			(width 0.2)
			(type default)
		)
		(layer "In1.Cu")
	)
	(gr_line
		(start 113.557304 -11.9888)
		(end 113.557304 -11.988546)
		(stroke
			(width 0.2)
			(type default)
		)
		(layer "In1.Cu")
	)
	(gr_arc
		(start 113.557304 -11.988546)
		(mid 113.319052 -11.272774)
		(end 112.60328 -11.511026)
		(stroke
			(width 0.2)
			(type default)
		)
		(layer "In1.Cu")
	)
	(gr_arc
		(start 114.175286 4.848352)
		(mid 114.53368 5.206365)
		(end 114.17554 5.564632)
		(stroke
			(width 0.2)
			(type default)
		)
		(layer "In1.Cu")
	)
	(gr_line
		(start 114.17554 5.564632)
		(end 113.15954 5.564632)
		(stroke
			(width 0.2)
			(type default)
		)
		(layer "In1.Cu")
	)
	(gr_line
		(start 114.424206 7.384542)
		(end 115.439952 7.384542)
		(stroke
			(width 0.2)
			(type default)
		)
		(layer "In1.Cu")
	)
	(gr_arc
		(start 114.424206 8.100822)
		(mid 114.066066 7.742682)
		(end 114.424206 7.384542)
		(stroke
			(width 0.2)
			(type default)
		)
		(layer "In1.Cu")
	)
	(gr_arc
		(start 115.439952 7.384542)
		(mid 115.798346 7.742555)
		(end 115.440206 8.100822)
		(stroke
			(width 0.2)
			(type default)
		)
		(layer "In1.Cu")
	)
	(gr_line
		(start 115.440206 8.100822)
		(end 114.424206 8.100822)
		(stroke
			(width 0.2)
			(type default)
		)
		(layer "In1.Cu")
	)
	(gr_line
		(start 115.75034 4.848352)
		(end 116.766086 4.848352)
		(stroke
			(width 0.2)
			(type default)
		)
		(layer "In1.Cu")
	)
	(gr_arc
		(start 115.75034 5.564632)
		(mid 115.3922 5.206492)
		(end 115.75034 4.848352)
		(stroke
			(width 0.2)
			(type default)
		)
		(layer "In1.Cu")
	)
	(gr_arc
		(start 115.78463 -32.885888)
		(mid 115.23726 -33.46069)
		(end 115.812062 -34.00806)
		(stroke
			(width 0.2)
			(type default)
		)
		(layer "In1.Cu")
	)
	(gr_line
		(start 115.78463 -32.883602)
		(end 115.78463 -32.885888)
		(stroke
			(width 0.2)
			(type default)
		)
		(layer "In1.Cu")
	)
	(gr_line
		(start 115.784884 -32.883348)
		(end 115.78463 -32.883602)
		(stroke
			(width 0.2)
			(type default)
		)
		(layer "In1.Cu")
	)
	(gr_line
		(start 115.812062 -34.0106)
		(end 116.675408 -33.989518)
		(stroke
			(width 0.2)
			(type default)
		)
		(layer "In1.Cu")
	)
	(gr_line
		(start 115.812062 -34.00806)
		(end 115.812062 -34.0106)
		(stroke
			(width 0.2)
			(type default)
		)
		(layer "In1.Cu")
	)
	(gr_line
		(start 116.647976 -32.864806)
		(end 116.647976 -32.862266)
		(stroke
			(width 0.2)
			(type default)
		)
		(layer "In1.Cu")
	)
	(gr_line
		(start 116.647976 -32.862266)
		(end 115.784884 -32.883348)
		(stroke
			(width 0.2)
			(type default)
		)
		(layer "In1.Cu")
	)
	(gr_line
		(start 116.675408 -33.989518)
		(end 116.675408 -33.987232)
		(stroke
			(width 0.2)
			(type default)
		)
		(layer "In1.Cu")
	)
	(gr_line
		(start 116.675408 -33.987232)
		(end 116.675408 -33.986978)
		(stroke
			(width 0.2)
			(type default)
		)
		(layer "In1.Cu")
	)
	(gr_arc
		(start 116.675408 -33.986978)
		(mid 117.222778 -33.412176)
		(end 116.647976 -32.864806)
		(stroke
			(width 0.2)
			(type default)
		)
		(layer "In1.Cu")
	)
	(gr_arc
		(start 116.766086 4.848352)
		(mid 117.12448 5.206365)
		(end 116.76634 5.564632)
		(stroke
			(width 0.2)
			(type default)
		)
		(layer "In1.Cu")
	)
	(gr_line
		(start 116.76634 5.564632)
		(end 115.75034 5.564632)
		(stroke
			(width 0.2)
			(type default)
		)
		(layer "In1.Cu")
	)
	(gr_line
		(start 117.015006 7.384542)
		(end 118.030752 7.384542)
		(stroke
			(width 0.2)
			(type default)
		)
		(layer "In1.Cu")
	)
	(gr_arc
		(start 117.015006 8.100822)
		(mid 116.656866 7.742682)
		(end 117.015006 7.384542)
		(stroke
			(width 0.2)
			(type default)
		)
		(layer "In1.Cu")
	)
	(gr_arc
		(start 118.030752 7.384542)
		(mid 118.389146 7.742555)
		(end 118.031006 8.100822)
		(stroke
			(width 0.2)
			(type default)
		)
		(layer "In1.Cu")
	)
	(gr_line
		(start 118.031006 8.100822)
		(end 117.015006 8.100822)
		(stroke
			(width 0.2)
			(type default)
		)
		(layer "In1.Cu")
	)
	(gr_line
		(start 118.34114 4.848352)
		(end 119.356886 4.848352)
		(stroke
			(width 0.2)
			(type default)
		)
		(layer "In1.Cu")
	)
	(gr_arc
		(start 118.34114 5.564632)
		(mid 117.983 5.206492)
		(end 118.34114 4.848352)
		(stroke
			(width 0.2)
			(type default)
		)
		(layer "In1.Cu")
	)
	(gr_arc
		(start 119.356886 4.848352)
		(mid 119.71528 5.206365)
		(end 119.35714 5.564632)
		(stroke
			(width 0.2)
			(type default)
		)
		(layer "In1.Cu")
	)
	(gr_line
		(start 119.35714 5.564632)
		(end 118.34114 5.564632)
		(stroke
			(width 0.2)
			(type default)
		)
		(layer "In1.Cu")
	)
	(gr_line
		(start 119.605806 7.384542)
		(end 120.621552 7.384542)
		(stroke
			(width 0.2)
			(type default)
		)
		(layer "In1.Cu")
	)
	(gr_arc
		(start 119.605806 8.100822)
		(mid 119.247666 7.742682)
		(end 119.605806 7.384542)
		(stroke
			(width 0.2)
			(type default)
		)
		(layer "In1.Cu")
	)
	(gr_arc
		(start 120.621552 7.384542)
		(mid 120.979946 7.742555)
		(end 120.621806 8.100822)
		(stroke
			(width 0.2)
			(type default)
		)
		(layer "In1.Cu")
	)
	(gr_line
		(start 120.621806 8.100822)
		(end 119.605806 8.100822)
		(stroke
			(width 0.2)
			(type default)
		)
		(layer "In1.Cu")
	)
	(gr_line
		(start 120.93194 4.848352)
		(end 121.947686 4.848352)
		(stroke
			(width 0.2)
			(type default)
		)
		(layer "In1.Cu")
	)
	(gr_arc
		(start 120.93194 5.564632)
		(mid 120.5738 5.206492)
		(end 120.93194 4.848352)
		(stroke
			(width 0.2)
			(type default)
		)
		(layer "In1.Cu")
	)
	(gr_arc
		(start 121.947686 4.848352)
		(mid 122.30608 5.206365)
		(end 121.94794 5.564632)
		(stroke
			(width 0.2)
			(type default)
		)
		(layer "In1.Cu")
	)
	(gr_line
		(start 121.94794 5.564632)
		(end 120.93194 5.564632)
		(stroke
			(width 0.2)
			(type default)
		)
		(layer "In1.Cu")
	)
	(gr_line
		(start 122.196606 7.384542)
		(end 123.212352 7.384542)
		(stroke
			(width 0.2)
			(type default)
		)
		(layer "In1.Cu")
	)
	(gr_arc
		(start 122.196606 8.100822)
		(mid 121.838466 7.742682)
		(end 122.196606 7.384542)
		(stroke
			(width 0.2)
			(type default)
		)
		(layer "In1.Cu")
	)
	(gr_arc
		(start 123.212352 7.384542)
		(mid 123.570746 7.742555)
		(end 123.212606 8.100822)
		(stroke
			(width 0.2)
			(type default)
		)
		(layer "In1.Cu")
	)
	(gr_line
		(start 123.212606 8.100822)
		(end 122.196606 8.100822)
		(stroke
			(width 0.2)
			(type default)
		)
		(layer "In1.Cu")
	)
	(gr_line
		(start 123.52274 4.848352)
		(end 124.538486 4.848352)
		(stroke
			(width 0.2)
			(type default)
		)
		(layer "In1.Cu")
	)
	(gr_arc
		(start 123.52274 5.564632)
		(mid 123.1646 5.206492)
		(end 123.52274 4.848352)
		(stroke
			(width 0.2)
			(type default)
		)
		(layer "In1.Cu")
	)
	(gr_arc
		(start 124.538486 4.848352)
		(mid 124.89688 5.206365)
		(end 124.53874 5.564632)
		(stroke
			(width 0.2)
			(type default)
		)
		(layer "In1.Cu")
	)
	(gr_line
		(start 124.53874 5.564632)
		(end 123.52274 5.564632)
		(stroke
			(width 0.2)
			(type default)
		)
		(layer "In1.Cu")
	)
	(gr_line
		(start 124.787406 7.384542)
		(end 125.803406 7.384542)
		(stroke
			(width 0.2)
			(type default)
		)
		(layer "In1.Cu")
	)
	(gr_arc
		(start 124.78766 8.100822)
		(mid 124.429266 7.742809)
		(end 124.787406 7.384542)
		(stroke
			(width 0.2)
			(type default)
		)
		(layer "In1.Cu")
	)
	(gr_line
		(start 125.639576 -34.426906)
		(end 126.51105 -34.426906)
		(stroke
			(width 0.2)
			(type default)
		)
		(layer "In1.Cu")
	)
	(gr_arc
		(start 125.639576 -33.304226)
		(mid 125.078236 -33.865566)
		(end 125.639576 -34.426906)
		(stroke
			(width 0.2)
			(type default)
		)
		(layer "In1.Cu")
	)
	(gr_arc
		(start 125.803406 7.384542)
		(mid 126.161546 7.742682)
		(end 125.803406 8.100822)
		(stroke
			(width 0.2)
			(type default)
		)
		(layer "In1.Cu")
	)
	(gr_line
		(start 125.803406 8.100822)
		(end 124.78766 8.100822)
		(stroke
			(width 0.2)
			(type default)
		)
		(layer "In1.Cu")
	)
	(gr_line
		(start 126.11354 4.848352)
		(end 127.129286 4.848352)
		(stroke
			(width 0.2)
			(type default)
		)
		(layer "In1.Cu")
	)
	(gr_arc
		(start 126.11354 5.564632)
		(mid 125.7554 5.206492)
		(end 126.11354 4.848352)
		(stroke
			(width 0.2)
			(type default)
		)
		(layer "In1.Cu")
	)
	(gr_arc
		(start 126.51105 -34.426906)
		(mid 127.072644 -33.865693)
		(end 126.511304 -33.304226)
		(stroke
			(width 0.2)
			(type default)
		)
		(layer "In1.Cu")
	)
	(gr_line
		(start 126.511304 -33.304226)
		(end 125.639576 -33.304226)
		(stroke
			(width 0.2)
			(type default)
		)
		(layer "In1.Cu")
	)
	(gr_arc
		(start 127.129286 4.848352)
		(mid 127.48768 5.206365)
		(end 127.12954 5.564632)
		(stroke
			(width 0.2)
			(type default)
		)
		(layer "In1.Cu")
	)
	(gr_line
		(start 127.12954 5.564632)
		(end 126.11354 5.564632)
		(stroke
			(width 0.2)
			(type default)
		)
		(layer "In1.Cu")
	)
	(gr_line
		(start 127.378206 7.384542)
		(end 128.393952 7.384542)
		(stroke
			(width 0.2)
			(type default)
		)
		(layer "In1.Cu")
	)
	(gr_arc
		(start 127.378206 8.100822)
		(mid 127.020066 7.742682)
		(end 127.378206 7.384542)
		(stroke
			(width 0.2)
			(type default)
		)
		(layer "In1.Cu")
	)
	(gr_arc
		(start 128.393952 7.384542)
		(mid 128.752346 7.742555)
		(end 128.394206 8.100822)
		(stroke
			(width 0.2)
			(type default)
		)
		(layer "In1.Cu")
	)
	(gr_line
		(start 128.394206 8.100822)
		(end 127.378206 8.100822)
		(stroke
			(width 0.2)
			(type default)
		)
		(layer "In1.Cu")
	)
	(gr_line
		(start 128.70434 4.848352)
		(end 129.720086 4.848352)
		(stroke
			(width 0.2)
			(type default)
		)
		(layer "In1.Cu")
	)
	(gr_arc
		(start 128.70434 5.564632)
		(mid 128.3462 5.206492)
		(end 128.70434 4.848352)
		(stroke
			(width 0.2)
			(type default)
		)
		(layer "In1.Cu")
	)
	(gr_arc
		(start 129.720086 4.848352)
		(mid 130.07848 5.206365)
		(end 129.72034 5.564632)
		(stroke
			(width 0.2)
			(type default)
		)
		(layer "In1.Cu")
	)
	(gr_line
		(start 129.72034 5.564632)
		(end 128.70434 5.564632)
		(stroke
			(width 0.2)
			(type default)
		)
		(layer "In1.Cu")
	)
	(gr_line
		(start 132.700014 14.53007)
		(end 133.199886 14.029944)
		(stroke
			(width 1.524)
			(type default)
		)
		(layer "In1.Cu")
	)
	(gr_arc
		(start 133.199886 0.199898)
		(mid 133.258599 0.058533)
		(end 133.400038 0)
		(stroke
			(width 1.524)
			(type default)
		)
		(layer "In1.Cu")
	)
	(gr_line
		(start 133.199886 14.029944)
		(end 133.199886 0.199898)
		(stroke
			(width 1.524)
			(type default)
		)
		(layer "In1.Cu")
	)
	(gr_line
		(start 133.400038 0)
		(end 137.385806 0)
		(stroke
			(width 1.524)
			(type default)
		)
		(layer "In1.Cu")
	)
	(gr_arc
		(start 138.092942 -0.292862)
		(mid 137.768489 -0.076142)
		(end 137.385806 0)
		(stroke
			(width 1.524)
			(type default)
		)
		(layer "In1.Cu")
	)
	(gr_line
		(start 138.092942 -0.292862)
		(end 138.507216 -0.707136)
		(stroke
			(width 1.524)
			(type default)
		)
		(layer "In1.Cu")
	)
	(gr_arc
		(start 138.800078 -7.590028)
		(mid 140.5001 -9.29005)
		(end 142.200122 -7.590028)
		(stroke
			(width 1.524)
			(type default)
		)
		(layer "In1.Cu")
	)
	(gr_arc
		(start 138.800078 -1.414272)
		(mid 138.724001 -1.031565)
		(end 138.507216 -0.707136)
		(stroke
			(width 1.524)
			(type default)
		)
		(layer "In1.Cu")
	)
	(gr_line
		(start 138.800078 -1.414272)
		(end 138.800078 -7.590028)
		(stroke
			(width 1.524)
			(type default)
		)
		(layer "In1.Cu")
	)
	(gr_line
		(start 142.200122 -7.590028)
		(end 142.200122 -1.414272)
		(stroke
			(width 1.524)
			(type default)
		)
		(layer "In1.Cu")
	)
	(gr_arc
		(start 142.492984 -0.707136)
		(mid 142.276252 -1.031587)
		(end 142.200122 -1.414272)
		(stroke
			(width 1.524)
			(type default)
		)
		(layer "In1.Cu")
	)
	(gr_line
		(start 142.492984 -0.707136)
		(end 142.907004 -0.292862)
		(stroke
			(width 1.524)
			(type default)
		)
		(layer "In1.Cu")
	)
	(gr_arc
		(start 143.61414 0)
		(mid 143.231439 -0.076086)
		(end 142.907004 -0.292862)
		(stroke
			(width 1.524)
			(type default)
		)
		(layer "In1.Cu")
	)
	(gr_line
		(start 143.61414 0)
		(end 146.500088 0)
		(stroke
			(width 1.524)
			(type default)
		)
		(layer "In1.Cu")
	)
	(gr_line
		(start 144.085818 -35.200082)
		(end 3.414268 -35.200082)
		(stroke
			(width 1.524)
			(type default)
		)
		(layer "In1.Cu")
	)
	(gr_arc
		(start 144.085818 -35.200082)
		(mid 144.468527 -35.124008)
		(end 144.792954 -34.90722)
		(stroke
			(width 1.524)
			(type default)
		)
		(layer "In1.Cu")
	)
	(gr_line
		(start 147.207224 -32.49295)
		(end 144.792954 -34.90722)
		(stroke
			(width 1.524)
			(type default)
		)
		(layer "In1.Cu")
	)
	(gr_arc
		(start 147.207224 -32.49295)
		(mid 147.423949 -32.168498)
		(end 147.500086 -31.785814)
		(stroke
			(width 1.524)
			(type default)
		)
		(layer "In1.Cu")
	)
	(gr_arc
		(start 147.500086 -0.999998)
		(mid 147.207192 -0.292898)
		(end 146.500088 0)
		(stroke
			(width 1.524)
			(type default)
		)
		(layer "In1.Cu")
	)
	(gr_line
		(start 147.500086 -0.999998)
		(end 147.500086 -31.785814)
		(stroke
			(width 1.524)
			(type default)
		)
		(layer "In1.Cu")
	)
	(gr_line
		(start 46.080172 -27.570176)
		(end 46.457616 -28.325826)
		(stroke
			(width 0.0635)
			(type default)
		)
		(layer "In2.Cu")
	)
	(gr_arc
		(start 46.457616 -28.325826)
		(mid 46.530925 -28.389557)
		(end 46.627796 -28.382722)
		(stroke
			(width 0.0635)
			(type default)
		)
		(layer "In2.Cu")
	)
	(gr_line
		(start 46.627796 -28.382722)
		(end 46.62805 -28.382722)
		(stroke
			(width 0.0635)
			(type default)
		)
		(layer "In2.Cu")
	)
	(gr_line
		(start 46.62805 -28.382722)
		(end 46.633384 -28.380182)
		(stroke
			(width 0.0635)
			(type default)
		)
		(layer "In2.Cu")
	)
	(gr_line
		(start 46.633384 -28.380182)
		(end 46.649894 -28.372054)
		(stroke
			(width 0.0635)
			(type default)
		)
		(layer "In2.Cu")
	)
	(gr_line
		(start 46.701964 -28.814268)
		(end 47.079662 -29.570426)
		(stroke
			(width 0.0635)
			(type default)
		)
		(layer "In2.Cu")
	)
	(gr_arc
		(start 46.75886 -28.643834)
		(mid 46.695097 -28.717287)
		(end 46.701964 -28.814268)
		(stroke
			(width 0.0635)
			(type default)
		)
		(layer "In2.Cu")
	)
	(gr_line
		(start 46.75886 -28.643834)
		(end 46.759114 -28.643834)
		(stroke
			(width 0.0635)
			(type default)
		)
		(layer "In2.Cu")
	)
	(gr_line
		(start 47.06874 -27.056588)
		(end 47.096172 -27.027886)
		(stroke
			(width 0.0635)
			(type default)
		)
		(layer "In2.Cu")
	)
	(gr_line
		(start 47.327566 -26.551636)
		(end 47.332392 -26.778204)
		(stroke
			(width 0.0635)
			(type default)
		)
		(layer "In2.Cu")
	)
	(gr_line
		(start 47.327566 -26.551636)
		(end 47.591218 -26.276808)
		(stroke
			(width 0.0635)
			(type default)
		)
		(layer "In2.Cu")
	)
	(gr_line
		(start 47.568866 -26.957528)
		(end 48.007016 -26.500582)
		(stroke
			(width 0.0635)
			(type default)
		)
		(layer "In2.Cu")
	)
	(gr_line
		(start 47.591218 -26.276808)
		(end 47.817786 -26.271982)
		(stroke
			(width 0.0635)
			(type default)
		)
		(layer "In2.Cu")
	)
	(gr_line
		(start 48.079914 -25.76703)
		(end 48.08474 -25.993598)
		(stroke
			(width 0.0635)
			(type default)
		)
		(layer "In2.Cu")
	)
	(gr_line
		(start 48.079914 -25.76703)
		(end 48.343566 -25.491948)
		(stroke
			(width 0.0635)
			(type default)
		)
		(layer "In2.Cu")
	)
	(gr_line
		(start 48.080422 -34.070036)
		(end 48.45812 -33.313878)
		(stroke
			(width 0.0635)
			(type default)
		)
		(layer "In2.Cu")
	)
	(gr_line
		(start 48.32096 -26.173176)
		(end 48.76038 -25.71496)
		(stroke
			(width 0.0635)
			(type default)
		)
		(layer "In2.Cu")
	)
	(gr_line
		(start 48.343566 -25.491948)
		(end 48.570388 -25.487122)
		(stroke
			(width 0.0635)
			(type default)
		)
		(layer "In2.Cu")
	)
	(gr_line
		(start 48.40097 -33.143444)
		(end 48.401224 -33.143444)
		(stroke
			(width 0.0635)
			(type default)
		)
		(layer "In2.Cu")
	)
	(gr_arc
		(start 48.45812 -33.313878)
		(mid 48.464879 -33.216933)
		(end 48.401224 -33.143444)
		(stroke
			(width 0.0635)
			(type default)
		)
		(layer "In2.Cu")
	)
	(gr_line
		(start 48.526192 -32.879538)
		(end 48.532034 -32.882332)
		(stroke
			(width 0.0635)
			(type default)
		)
		(layer "In2.Cu")
	)
	(gr_line
		(start 48.532034 -32.882332)
		(end 48.532288 -32.882332)
		(stroke
			(width 0.0635)
			(type default)
		)
		(layer "In2.Cu")
	)
	(gr_arc
		(start 48.532288 -32.882332)
		(mid 48.629146 -32.889111)
		(end 48.702468 -32.825436)
		(stroke
			(width 0.0635)
			(type default)
		)
		(layer "In2.Cu")
	)
	(gr_line
		(start 48.702468 -32.825436)
		(end 49.079912 -32.069786)
		(stroke
			(width 0.0635)
			(type default)
		)
		(layer "In2.Cu")
	)
	(gr_line
		(start 49.004982 -27.110436)
		(end 49.009554 -27.061922)
		(stroke
			(width 0.0635)
			(type default)
		)
		(layer "In2.Cu")
	)
	(gr_line
		(start 49.009554 -27.061922)
		(end 49.039018 -27.024076)
		(stroke
			(width 0.0635)
			(type default)
		)
		(layer "In2.Cu")
	)
	(gr_line
		(start 49.198022 -27.973274)
		(end 49.221644 -27.939492)
		(stroke
			(width 0.0635)
			(type default)
		)
		(layer "In2.Cu")
	)
	(gr_line
		(start 49.221644 -27.939492)
		(end 49.225454 -27.898598)
		(stroke
			(width 0.0635)
			(type default)
		)
		(layer "In2.Cu")
	)
	(gr_line
		(start 49.544224 -26.375106)
		(end 49.930812 -25.87879)
		(stroke
			(width 0.0635)
			(type default)
		)
		(layer "In2.Cu")
	)
	(gr_line
		(start 49.754282 -26.58491)
		(end 49.978818 -26.55697)
		(stroke
			(width 0.0635)
			(type default)
		)
		(layer "In2.Cu")
	)
	(gr_line
		(start 49.978818 -26.55697)
		(end 50.213006 -26.256488)
		(stroke
			(width 0.0635)
			(type default)
		)
		(layer "In2.Cu")
	)
	(gr_line
		(start 50.185066 -26.031698)
		(end 50.213006 -26.256488)
		(stroke
			(width 0.0635)
			(type default)
		)
		(layer "In2.Cu")
	)
	(gr_line
		(start 50.21072 -25.518618)
		(end 50.598578 -25.020778)
		(stroke
			(width 0.0635)
			(type default)
		)
		(layer "In2.Cu")
	)
	(gr_line
		(start 50.421794 -25.727152)
		(end 50.646584 -25.699212)
		(stroke
			(width 0.0635)
			(type default)
		)
		(layer "In2.Cu")
	)
	(gr_line
		(start 50.646584 -25.699212)
		(end 50.880772 -25.398476)
		(stroke
			(width 0.0635)
			(type default)
		)
		(layer "In2.Cu")
	)
	(gr_line
		(start 50.852832 -25.173686)
		(end 50.880772 -25.398476)
		(stroke
			(width 0.0635)
			(type default)
		)
		(layer "In2.Cu")
	)
	(gr_line
		(start 51.080162 -29.570426)
		(end 51.45786 -28.814268)
		(stroke
			(width 0.0635)
			(type default)
		)
		(layer "In2.Cu")
	)
	(gr_line
		(start 51.134264 -26.686256)
		(end 51.143408 -26.652728)
		(stroke
			(width 0.0635)
			(type default)
		)
		(layer "In2.Cu")
	)
	(gr_line
		(start 51.143408 -26.652728)
		(end 51.16703 -26.627836)
		(stroke
			(width 0.0635)
			(type default)
		)
		(layer "In2.Cu")
	)
	(gr_line
		(start 51.236626 -24.200612)
		(end 51.241452 -24.194516)
		(stroke
			(width 0.0635)
			(type default)
		)
		(layer "In2.Cu")
	)
	(gr_line
		(start 51.241452 -24.194516)
		(end 51.248056 -24.189944)
		(stroke
			(width 0.0635)
			(type default)
		)
		(layer "In2.Cu")
	)
	(gr_line
		(start 51.40071 -28.643834)
		(end 51.400964 -28.643834)
		(stroke
			(width 0.0635)
			(type default)
		)
		(layer "In2.Cu")
	)
	(gr_arc
		(start 51.45786 -28.814268)
		(mid 51.464619 -28.717323)
		(end 51.400964 -28.643834)
		(stroke
			(width 0.0635)
			(type default)
		)
		(layer "In2.Cu")
	)
	(gr_line
		(start 51.480212 -26.295604)
		(end 51.91379 -25.836118)
		(stroke
			(width 0.0635)
			(type default)
		)
		(layer "In2.Cu")
	)
	(gr_line
		(start 51.525932 -28.379928)
		(end 51.531774 -28.382722)
		(stroke
			(width 0.0635)
			(type default)
		)
		(layer "In2.Cu")
	)
	(gr_line
		(start 51.531774 -28.382722)
		(end 51.532028 -28.382722)
		(stroke
			(width 0.0635)
			(type default)
		)
		(layer "In2.Cu")
	)
	(gr_arc
		(start 51.532028 -28.382722)
		(mid 51.628916 -28.38954)
		(end 51.702208 -28.325826)
		(stroke
			(width 0.0635)
			(type default)
		)
		(layer "In2.Cu")
	)
	(gr_line
		(start 51.670458 -26.523442)
		(end 51.897026 -26.516838)
		(stroke
			(width 0.0635)
			(type default)
		)
		(layer "In2.Cu")
	)
	(gr_line
		(start 51.702208 -28.325826)
		(end 52.079652 -27.570176)
		(stroke
			(width 0.0635)
			(type default)
		)
		(layer "In2.Cu")
	)
	(gr_line
		(start 51.897026 -26.516838)
		(end 52.158646 -26.239724)
		(stroke
			(width 0.0635)
			(type default)
		)
		(layer "In2.Cu")
	)
	(gr_line
		(start 52.151788 -26.012902)
		(end 52.158646 -26.239724)
		(stroke
			(width 0.0635)
			(type default)
		)
		(layer "In2.Cu")
	)
	(gr_line
		(start 52.224432 -25.50668)
		(end 52.662328 -25.042368)
		(stroke
			(width 0.0635)
			(type default)
		)
		(layer "In2.Cu")
	)
	(gr_line
		(start 52.416202 -25.73274)
		(end 52.643278 -25.726136)
		(stroke
			(width 0.0635)
			(type default)
		)
		(layer "In2.Cu")
	)
	(gr_line
		(start 52.643278 -25.726136)
		(end 52.904644 -25.449022)
		(stroke
			(width 0.0635)
			(type default)
		)
		(layer "In2.Cu")
	)
	(gr_line
		(start 52.89804 -25.221692)
		(end 52.904644 -25.449022)
		(stroke
			(width 0.0635)
			(type default)
		)
		(layer "In2.Cu")
	)
	(gr_line
		(start 52.96027 -27.705304)
		(end 52.964334 -27.681682)
		(stroke
			(width 0.0635)
			(type default)
		)
		(layer "In2.Cu")
	)
	(gr_line
		(start 52.968906 -24.717248)
		(end 53.37429 -24.28748)
		(stroke
			(width 0.0635)
			(type default)
		)
		(layer "In2.Cu")
	)
	(gr_line
		(start 53.080412 -32.069786)
		(end 53.457856 -32.825436)
		(stroke
			(width 0.0635)
			(type default)
		)
		(layer "In2.Cu")
	)
	(gr_line
		(start 53.099462 -26.916634)
		(end 53.104288 -26.889456)
		(stroke
			(width 0.0635)
			(type default)
		)
		(layer "In2.Cu")
	)
	(gr_line
		(start 53.104288 -26.889456)
		(end 53.119782 -26.867866)
		(stroke
			(width 0.0635)
			(type default)
		)
		(layer "In2.Cu")
	)
	(gr_line
		(start 53.161946 -24.942038)
		(end 53.389276 -24.935434)
		(stroke
			(width 0.0635)
			(type default)
		)
		(layer "In2.Cu")
	)
	(gr_line
		(start 53.28285 -26.350976)
		(end 53.32222 -26.574242)
		(stroke
			(width 0.0635)
			(type default)
		)
		(layer "In2.Cu")
	)
	(gr_line
		(start 53.28285 -26.350976)
		(end 53.501544 -26.03881)
		(stroke
			(width 0.0635)
			(type default)
		)
		(layer "In2.Cu")
	)
	(gr_line
		(start 53.379878 -24.281384)
		(end 53.781198 -23.85568)
		(stroke
			(width 0.0635)
			(type default)
		)
		(layer "In2.Cu")
	)
	(gr_line
		(start 53.389276 -24.935434)
		(end 53.650896 -24.65832)
		(stroke
			(width 0.0635)
			(type default)
		)
		(layer "In2.Cu")
	)
	(gr_arc
		(start 53.457856 -32.825436)
		(mid 53.531162 -32.889129)
		(end 53.628036 -32.882332)
		(stroke
			(width 0.0635)
			(type default)
		)
		(layer "In2.Cu")
	)
	(gr_line
		(start 53.501544 -26.03881)
		(end 53.724556 -25.99944)
		(stroke
			(width 0.0635)
			(type default)
		)
		(layer "In2.Cu")
	)
	(gr_line
		(start 53.583332 -26.71445)
		(end 53.945028 -26.198068)
		(stroke
			(width 0.0635)
			(type default)
		)
		(layer "In2.Cu")
	)
	(gr_line
		(start 53.628036 -32.882332)
		(end 53.62829 -32.882332)
		(stroke
			(width 0.0635)
			(type default)
		)
		(layer "In2.Cu")
	)
	(gr_line
		(start 53.62829 -32.882332)
		(end 53.634132 -32.879538)
		(stroke
			(width 0.0635)
			(type default)
		)
		(layer "In2.Cu")
	)
	(gr_line
		(start 53.644038 -24.430736)
		(end 53.650896 -24.65832)
		(stroke
			(width 0.0635)
			(type default)
		)
		(layer "In2.Cu")
	)
	(gr_line
		(start 53.644038 -24.406098)
		(end 53.644038 -24.426926)
		(stroke
			(width 0.0635)
			(type default)
		)
		(layer "In2.Cu")
	)
	(gr_line
		(start 53.644038 -24.406098)
		(end 53.990748 -24.059388)
		(stroke
			(width 0.0635)
			(type default)
		)
		(layer "In2.Cu")
	)
	(gr_line
		(start 53.702204 -33.313878)
		(end 54.079902 -34.070036)
		(stroke
			(width 0.0635)
			(type default)
		)
		(layer "In2.Cu")
	)
	(gr_arc
		(start 53.7591 -33.143444)
		(mid 53.695337 -33.216897)
		(end 53.702204 -33.313878)
		(stroke
			(width 0.0635)
			(type default)
		)
		(layer "In2.Cu")
	)
	(gr_line
		(start 53.7591 -33.143444)
		(end 53.759354 -33.143444)
		(stroke
			(width 0.0635)
			(type default)
		)
		(layer "In2.Cu")
	)
	(gr_line
		(start 53.90642 -25.460452)
		(end 53.946044 -25.683464)
		(stroke
			(width 0.0635)
			(type default)
		)
		(layer "In2.Cu")
	)
	(gr_line
		(start 53.90642 -25.460452)
		(end 54.125114 -25.148286)
		(stroke
			(width 0.0635)
			(type default)
		)
		(layer "In2.Cu")
	)
	(gr_line
		(start 54.125114 -25.148286)
		(end 54.348126 -25.108916)
		(stroke
			(width 0.0635)
			(type default)
		)
		(layer "In2.Cu")
	)
	(gr_line
		(start 54.208426 -25.82164)
		(end 54.568852 -25.30729)
		(stroke
			(width 0.0635)
			(type default)
		)
		(layer "In2.Cu")
	)
	(gr_line
		(start 54.67858 -24.641302)
		(end 54.686454 -24.630126)
		(stroke
			(width 0.0635)
			(type default)
		)
		(layer "In2.Cu")
	)
	(gr_line
		(start 54.686454 -24.630126)
		(end 54.69763 -24.622252)
		(stroke
			(width 0.0635)
			(type default)
		)
		(layer "In2.Cu")
	)
	(gr_line
		(start 55.079392 -29.570426)
		(end 55.457598 -28.814522)
		(stroke
			(width 0.0635)
			(type default)
		)
		(layer "In2.Cu")
	)
	(gr_line
		(start 55.400702 -28.644088)
		(end 55.400956 -28.644088)
		(stroke
			(width 0.0635)
			(type default)
		)
		(layer "In2.Cu")
	)
	(gr_arc
		(start 55.457598 -28.814522)
		(mid 55.464575 -28.717574)
		(end 55.400956 -28.644088)
		(stroke
			(width 0.0635)
			(type default)
		)
		(layer "In2.Cu")
	)
	(gr_line
		(start 55.531258 -28.382468)
		(end 55.531512 -28.382468)
		(stroke
			(width 0.0635)
			(type default)
		)
		(layer "In2.Cu")
	)
	(gr_arc
		(start 55.531512 -28.382468)
		(mid 55.62846 -28.389445)
		(end 55.701946 -28.325826)
		(stroke
			(width 0.0635)
			(type default)
		)
		(layer "In2.Cu")
	)
	(gr_line
		(start 55.696612 -25.500838)
		(end 55.714646 -25.462738)
		(stroke
			(width 0.0635)
			(type default)
		)
		(layer "In2.Cu")
	)
	(gr_line
		(start 55.701946 -28.325826)
		(end 56.080152 -27.570176)
		(stroke
			(width 0.0635)
			(type default)
		)
		(layer "In2.Cu")
	)
	(gr_line
		(start 55.714646 -25.462738)
		(end 55.748936 -25.438862)
		(stroke
			(width 0.0635)
			(type default)
		)
		(layer "In2.Cu")
	)
	(gr_line
		(start 56.119776 -25.17902)
		(end 56.63946 -24.815292)
		(stroke
			(width 0.0635)
			(type default)
		)
		(layer "In2.Cu")
	)
	(gr_line
		(start 56.261254 -25.439624)
		(end 56.484774 -25.478994)
		(stroke
			(width 0.0635)
			(type default)
		)
		(layer "In2.Cu")
	)
	(gr_line
		(start 56.477916 -19.591528)
		(end 56.526176 -19.557746)
		(stroke
			(width 0.0635)
			(type default)
		)
		(layer "In2.Cu")
	)
	(gr_line
		(start 56.484774 -25.478994)
		(end 56.79694 -25.2603)
		(stroke
			(width 0.0635)
			(type default)
		)
		(layer "In2.Cu")
	)
	(gr_line
		(start 56.526176 -19.557746)
		(end 56.545226 -19.501358)
		(stroke
			(width 0.0635)
			(type default)
		)
		(layer "In2.Cu")
	)
	(gr_line
		(start 56.79694 -25.2603)
		(end 56.83631 -25.037034)
		(stroke
			(width 0.0635)
			(type default)
		)
		(layer "In2.Cu")
	)
	(gr_line
		(start 56.965088 -27.723592)
		(end 56.965342 -27.718004)
		(stroke
			(width 0.0635)
			(type default)
		)
		(layer "In2.Cu")
	)
	(gr_line
		(start 56.987186 -27.315414)
		(end 56.98744 -27.309826)
		(stroke
			(width 0.0635)
			(type default)
		)
		(layer "In2.Cu")
	)
	(gr_line
		(start 56.98744 -27.309826)
		(end 56.989472 -27.304492)
		(stroke
			(width 0.0635)
			(type default)
		)
		(layer "In2.Cu")
	)
	(gr_line
		(start 57.0103 -24.55545)
		(end 57.529984 -24.191722)
		(stroke
			(width 0.0635)
			(type default)
		)
		(layer "In2.Cu")
	)
	(gr_line
		(start 57.049924 -6.023102)
		(end 57.050686 -6.020054)
		(stroke
			(width 0.0635)
			(type default)
		)
		(layer "In2.Cu")
	)
	(gr_line
		(start 57.050686 -6.020054)
		(end 57.05221 -6.017514)
		(stroke
			(width 0.0635)
			(type default)
		)
		(layer "In2.Cu")
	)
	(gr_line
		(start 57.152032 -24.816054)
		(end 57.375298 -24.855424)
		(stroke
			(width 0.0635)
			(type default)
		)
		(layer "In2.Cu")
	)
	(gr_line
		(start 57.298336 -5.55244)
		(end 57.348374 -5.484368)
		(stroke
			(width 0.0635)
			(type default)
		)
		(layer "In2.Cu")
	)
	(gr_line
		(start 57.375298 -24.855424)
		(end 57.687464 -24.636984)
		(stroke
			(width 0.0635)
			(type default)
		)
		(layer "In2.Cu")
	)
	(gr_line
		(start 57.407556 -20.306538)
		(end 57.411112 -20.303998)
		(stroke
			(width 0.0635)
			(type default)
		)
		(layer "In2.Cu")
	)
	(gr_line
		(start 57.411112 -20.303998)
		(end 57.413906 -20.300696)
		(stroke
			(width 0.0635)
			(type default)
		)
		(layer "In2.Cu")
	)
	(gr_arc
		(start 57.458356 -32.825436)
		(mid 57.269346 -32.447437)
		(end 57.079642 -32.069786)
		(stroke
			(width 0.0635)
			(type default)
		)
		(layer "In2.Cu")
	)
	(gr_arc
		(start 57.458356 -32.825436)
		(mid 57.531662 -32.889129)
		(end 57.628536 -32.882332)
		(stroke
			(width 0.0635)
			(type default)
		)
		(layer "In2.Cu")
	)
	(gr_line
		(start 57.534556 -26.190956)
		(end 57.54751 -26.167842)
		(stroke
			(width 0.0635)
			(type default)
		)
		(layer "In2.Cu")
	)
	(gr_line
		(start 57.546494 -5.708142)
		(end 57.5564 -5.6896)
		(stroke
			(width 0.0635)
			(type default)
		)
		(layer "In2.Cu")
	)
	(gr_line
		(start 57.54751 -26.167842)
		(end 57.568592 -26.152348)
		(stroke
			(width 0.0635)
			(type default)
		)
		(layer "In2.Cu")
	)
	(gr_line
		(start 57.5564 -5.6896)
		(end 57.570624 -5.675376)
		(stroke
			(width 0.0635)
			(type default)
		)
		(layer "In2.Cu")
	)
	(gr_line
		(start 57.628536 -32.882332)
		(end 57.62879 -32.882332)
		(stroke
			(width 0.0635)
			(type default)
		)
		(layer "In2.Cu")
	)
	(gr_line
		(start 57.62879 -32.882332)
		(end 57.634632 -32.879538)
		(stroke
			(width 0.0635)
			(type default)
		)
		(layer "In2.Cu")
	)
	(gr_line
		(start 57.687464 -24.636984)
		(end 57.726834 -24.413464)
		(stroke
			(width 0.0635)
			(type default)
		)
		(layer "In2.Cu")
	)
	(gr_line
		(start 57.702704 -33.313878)
		(end 58.080402 -34.070036)
		(stroke
			(width 0.0635)
			(type default)
		)
		(layer "In2.Cu")
	)
	(gr_arc
		(start 57.7596 -33.143444)
		(mid 57.695837 -33.216897)
		(end 57.702704 -33.313878)
		(stroke
			(width 0.0635)
			(type default)
		)
		(layer "In2.Cu")
	)
	(gr_line
		(start 57.7596 -33.143444)
		(end 57.759854 -33.143444)
		(stroke
			(width 0.0635)
			(type default)
		)
		(layer "In2.Cu")
	)
	(gr_line
		(start 57.900824 -23.93188)
		(end 58.420508 -23.568152)
		(stroke
			(width 0.0635)
			(type default)
		)
		(layer "In2.Cu")
	)
	(gr_line
		(start 58.033412 -25.805384)
		(end 58.06694 -25.581356)
		(stroke
			(width 0.0635)
			(type default)
		)
		(layer "In2.Cu")
	)
	(gr_line
		(start 58.042556 -24.192484)
		(end 58.265822 -24.231854)
		(stroke
			(width 0.0635)
			(type default)
		)
		(layer "In2.Cu")
	)
	(gr_line
		(start 58.06694 -25.581356)
		(end 58.37301 -25.354534)
		(stroke
			(width 0.0635)
			(type default)
		)
		(layer "In2.Cu")
	)
	(gr_line
		(start 58.23712 -26.021284)
		(end 58.744358 -25.645872)
		(stroke
			(width 0.0635)
			(type default)
		)
		(layer "In2.Cu")
	)
	(gr_line
		(start 58.265822 -24.231854)
		(end 58.577988 -24.013414)
		(stroke
			(width 0.0635)
			(type default)
		)
		(layer "In2.Cu")
	)
	(gr_line
		(start 58.37301 -25.354534)
		(end 58.597038 -25.388062)
		(stroke
			(width 0.0635)
			(type default)
		)
		(layer "In2.Cu")
	)
	(gr_line
		(start 58.534808 -20.868386)
		(end 58.538618 -20.865592)
		(stroke
			(width 0.0635)
			(type default)
		)
		(layer "In2.Cu")
	)
	(gr_line
		(start 58.538618 -20.865592)
		(end 58.541412 -20.862036)
		(stroke
			(width 0.0635)
			(type default)
		)
		(layer "In2.Cu")
	)
	(gr_line
		(start 58.577988 -24.013414)
		(end 58.617358 -23.790148)
		(stroke
			(width 0.0635)
			(type default)
		)
		(layer "In2.Cu")
	)
	(gr_line
		(start 58.600594 -25.38857)
		(end 58.60542 -25.385014)
		(stroke
			(width 0.0635)
			(type default)
		)
		(layer "In2.Cu")
	)
	(gr_line
		(start 58.768488 -25.627584)
		(end 58.940192 -25.500584)
		(stroke
			(width 0.0635)
			(type default)
		)
		(layer "In2.Cu")
	)
	(gr_line
		(start 58.907172 -25.158446)
		(end 58.9407 -24.934418)
		(stroke
			(width 0.0635)
			(type default)
		)
		(layer "In2.Cu")
	)
	(gr_line
		(start 58.934604 -6.736588)
		(end 58.93562 -6.733032)
		(stroke
			(width 0.0635)
			(type default)
		)
		(layer "In2.Cu")
	)
	(gr_line
		(start 58.9407 -24.934418)
		(end 59.24677 -24.70785)
		(stroke
			(width 0.0635)
			(type default)
		)
		(layer "In2.Cu")
	)
	(gr_line
		(start 59.039252 -6.383528)
		(end 59.04484 -6.36524)
		(stroke
			(width 0.0635)
			(type default)
		)
		(layer "In2.Cu")
	)
	(gr_line
		(start 59.04484 -6.36524)
		(end 59.056524 -6.350254)
		(stroke
			(width 0.0635)
			(type default)
		)
		(layer "In2.Cu")
	)
	(gr_line
		(start 59.079892 -29.570426)
		(end 59.45759 -28.814268)
		(stroke
			(width 0.0635)
			(type default)
		)
		(layer "In2.Cu")
	)
	(gr_line
		(start 59.10961 -25.375362)
		(end 59.619134 -24.998172)
		(stroke
			(width 0.0635)
			(type default)
		)
		(layer "In2.Cu")
	)
	(gr_line
		(start 59.24677 -24.70785)
		(end 59.470798 -24.741124)
		(stroke
			(width 0.0635)
			(type default)
		)
		(layer "In2.Cu")
	)
	(gr_line
		(start 59.282838 -26.148792)
		(end 59.299094 -26.08961)
		(stroke
			(width 0.0635)
			(type default)
		)
		(layer "In2.Cu")
	)
	(gr_line
		(start 59.299094 -26.08961)
		(end 59.34964 -26.051256)
		(stroke
			(width 0.0635)
			(type default)
		)
		(layer "In2.Cu")
	)
	(gr_line
		(start 59.40044 -28.643834)
		(end 59.400694 -28.643834)
		(stroke
			(width 0.0635)
			(type default)
		)
		(layer "In2.Cu")
	)
	(gr_arc
		(start 59.45759 -28.814268)
		(mid 59.464445 -28.717273)
		(end 59.400694 -28.643834)
		(stroke
			(width 0.0635)
			(type default)
		)
		(layer "In2.Cu")
	)
	(gr_line
		(start 59.525662 -28.379928)
		(end 59.531504 -28.382722)
		(stroke
			(width 0.0635)
			(type default)
		)
		(layer "In2.Cu")
	)
	(gr_line
		(start 59.531504 -28.382722)
		(end 59.531758 -28.382722)
		(stroke
			(width 0.0635)
			(type default)
		)
		(layer "In2.Cu")
	)
	(gr_arc
		(start 59.531758 -28.382722)
		(mid 59.628632 -28.389519)
		(end 59.701938 -28.325826)
		(stroke
			(width 0.0635)
			(type default)
		)
		(layer "In2.Cu")
	)
	(gr_line
		(start 59.701938 -28.325826)
		(end 60.079382 -27.570176)
		(stroke
			(width 0.0635)
			(type default)
		)
		(layer "In2.Cu")
	)
	(gr_line
		(start 59.714638 -25.779984)
		(end 60.224924 -25.40127)
		(stroke
			(width 0.0635)
			(type default)
		)
		(layer "In2.Cu")
	)
	(gr_line
		(start 59.863482 -26.036524)
		(end 60.087764 -26.069798)
		(stroke
			(width 0.0635)
			(type default)
		)
		(layer "In2.Cu")
	)
	(gr_line
		(start 60.087764 -26.069798)
		(end 60.393834 -25.842722)
		(stroke
			(width 0.0635)
			(type default)
		)
		(layer "In2.Cu")
	)
	(gr_line
		(start 60.393834 -25.842722)
		(end 60.426854 -25.61844)
		(stroke
			(width 0.0635)
			(type default)
		)
		(layer "In2.Cu")
	)
	(gr_line
		(start 60.462414 -20.942554)
		(end 60.487052 -20.925282)
		(stroke
			(width 0.0635)
			(type default)
		)
		(layer "In2.Cu")
	)
	(gr_line
		(start 60.487052 -20.925282)
		(end 60.50153 -20.898866)
		(stroke
			(width 0.0635)
			(type default)
		)
		(layer "In2.Cu")
	)
	(gr_line
		(start 60.58662 -25.132792)
		(end 61.097922 -24.753316)
		(stroke
			(width 0.0635)
			(type default)
		)
		(layer "In2.Cu")
	)
	(gr_line
		(start 60.736226 -25.388824)
		(end 60.960762 -25.421844)
		(stroke
			(width 0.0635)
			(type default)
		)
		(layer "In2.Cu")
	)
	(gr_line
		(start 60.903866 -27.195526)
		(end 60.905136 -27.2288)
		(stroke
			(width 0.0635)
			(type default)
		)
		(layer "In2.Cu")
	)
	(gr_line
		(start 60.903866 -27.195526)
		(end 60.917582 -27.166062)
		(stroke
			(width 0.0635)
			(type default)
		)
		(layer "In2.Cu")
	)
	(gr_line
		(start 60.905136 -27.229054)
		(end 60.905136 -27.229562)
		(stroke
			(width 0.0635)
			(type default)
		)
		(layer "In2.Cu")
	)
	(gr_line
		(start 60.913772 -27.528774)
		(end 60.914788 -27.532838)
		(stroke
			(width 0.0635)
			(type default)
		)
		(layer "In2.Cu")
	)
	(gr_line
		(start 60.913772 -27.52852)
		(end 60.913772 -27.528774)
		(stroke
			(width 0.0635)
			(type default)
		)
		(layer "In2.Cu")
	)
	(gr_line
		(start 60.913772 -27.52852)
		(end 60.914534 -27.527758)
		(stroke
			(width 0.0635)
			(type default)
		)
		(layer "In2.Cu")
	)
	(gr_line
		(start 60.918852 -27.548586)
		(end 60.938156 -27.624024)
		(stroke
			(width 0.0635)
			(type default)
		)
		(layer "In2.Cu")
	)
	(gr_line
		(start 60.960762 -25.421844)
		(end 61.266832 -25.195022)
		(stroke
			(width 0.0635)
			(type default)
		)
		(layer "In2.Cu")
	)
	(gr_line
		(start 60.968382 -6.567932)
		(end 60.963556 -6.583934)
		(stroke
			(width 0.0635)
			(type default)
		)
		(layer "In2.Cu")
	)
	(gr_line
		(start 61.008006 -6.43763)
		(end 60.968382 -6.567932)
		(stroke
			(width 0.0635)
			(type default)
		)
		(layer "In2.Cu")
	)
	(gr_line
		(start 61.066426 -26.842974)
		(end 61.080142 -26.813002)
		(stroke
			(width 0.0635)
			(type default)
		)
		(layer "In2.Cu")
	)
	(gr_line
		(start 61.080142 -32.069786)
		(end 61.457586 -32.825436)
		(stroke
			(width 0.0635)
			(type default)
		)
		(layer "In2.Cu")
	)
	(gr_line
		(start 61.080142 -26.813002)
		(end 61.106558 -26.792428)
		(stroke
			(width 0.0635)
			(type default)
		)
		(layer "In2.Cu")
	)
	(gr_line
		(start 61.208666 -27.502358)
		(end 61.20892 -27.510994)
		(stroke
			(width 0.0635)
			(type default)
		)
		(layer "In2.Cu")
	)
	(gr_line
		(start 61.20892 -27.514296)
		(end 61.212476 -27.517344)
		(stroke
			(width 0.0635)
			(type default)
		)
		(layer "In2.Cu")
	)
	(gr_line
		(start 61.20892 -27.510994)
		(end 61.20892 -27.514296)
		(stroke
			(width 0.0635)
			(type default)
		)
		(layer "In2.Cu")
	)
	(gr_line
		(start 61.220604 -14.323568)
		(end 61.22416 -14.313662)
		(stroke
			(width 0.0635)
			(type default)
		)
		(layer "In2.Cu")
	)
	(gr_line
		(start 61.24829 -6.651752)
		(end 61.259974 -6.585458)
		(stroke
			(width 0.0635)
			(type default)
		)
		(layer "In2.Cu")
	)
	(gr_line
		(start 61.259974 -6.585458)
		(end 61.2775 -6.55574)
		(stroke
			(width 0.0635)
			(type default)
		)
		(layer "In2.Cu")
	)
	(gr_line
		(start 61.266832 -25.195022)
		(end 61.299852 -24.970486)
		(stroke
			(width 0.0635)
			(type default)
		)
		(layer "In2.Cu")
	)
	(gr_arc
		(start 61.457586 -32.825436)
		(mid 61.53089 -32.889117)
		(end 61.627766 -32.882332)
		(stroke
			(width 0.0635)
			(type default)
		)
		(layer "In2.Cu")
	)
	(gr_line
		(start 61.459618 -24.484838)
		(end 61.971428 -24.105108)
		(stroke
			(width 0.0635)
			(type default)
		)
		(layer "In2.Cu")
	)
	(gr_line
		(start 61.609478 -24.74087)
		(end 61.83376 -24.774144)
		(stroke
			(width 0.0635)
			(type default)
		)
		(layer "In2.Cu")
	)
	(gr_line
		(start 61.627766 -32.882332)
		(end 61.62802 -32.882332)
		(stroke
			(width 0.0635)
			(type default)
		)
		(layer "In2.Cu")
	)
	(gr_line
		(start 61.62802 -32.882332)
		(end 61.633862 -32.879538)
		(stroke
			(width 0.0635)
			(type default)
		)
		(layer "In2.Cu")
	)
	(gr_line
		(start 61.693806 -26.334974)
		(end 61.722508 -26.110184)
		(stroke
			(width 0.0635)
			(type default)
		)
		(layer "In2.Cu")
	)
	(gr_line
		(start 61.701934 -33.313878)
		(end 62.079632 -34.070036)
		(stroke
			(width 0.0635)
			(type default)
		)
		(layer "In2.Cu")
	)
	(gr_line
		(start 61.722508 -26.110184)
		(end 62.023752 -25.877012)
		(stroke
			(width 0.0635)
			(type default)
		)
		(layer "In2.Cu")
	)
	(gr_arc
		(start 61.75883 -33.143444)
		(mid 61.695178 -33.216906)
		(end 61.701934 -33.313878)
		(stroke
			(width 0.0635)
			(type default)
		)
		(layer "In2.Cu")
	)
	(gr_line
		(start 61.75883 -33.143444)
		(end 61.759084 -33.143444)
		(stroke
			(width 0.0635)
			(type default)
		)
		(layer "In2.Cu")
	)
	(gr_line
		(start 61.83376 -24.774144)
		(end 62.13983 -24.547068)
		(stroke
			(width 0.0635)
			(type default)
		)
		(layer "In2.Cu")
	)
	(gr_line
		(start 61.901832 -26.546302)
		(end 62.398402 -26.161746)
		(stroke
			(width 0.0635)
			(type default)
		)
		(layer "In2.Cu")
	)
	(gr_line
		(start 62.023752 -25.877012)
		(end 62.248288 -25.905714)
		(stroke
			(width 0.0635)
			(type default)
		)
		(layer "In2.Cu")
	)
	(gr_line
		(start 62.13983 -24.547068)
		(end 62.17285 -24.322532)
		(stroke
			(width 0.0635)
			(type default)
		)
		(layer "In2.Cu")
	)
	(gr_line
		(start 62.553596 -25.669494)
		(end 62.582298 -25.444958)
		(stroke
			(width 0.0635)
			(type default)
		)
		(layer "In2.Cu")
	)
	(gr_line
		(start 62.582298 -25.444958)
		(end 62.883542 -25.211786)
		(stroke
			(width 0.0635)
			(type default)
		)
		(layer "In2.Cu")
	)
	(gr_line
		(start 62.762892 -25.879806)
		(end 63.258954 -25.496012)
		(stroke
			(width 0.0635)
			(type default)
		)
		(layer "In2.Cu")
	)
	(gr_line
		(start 62.883542 -25.211786)
		(end 63.108078 -25.240234)
		(stroke
			(width 0.0635)
			(type default)
		)
		(layer "In2.Cu")
	)
	(gr_line
		(start 63.037466 -6.238748)
		(end 62.992762 -6.41985)
		(stroke
			(width 0.0635)
			(type default)
		)
		(layer "In2.Cu")
	)
	(gr_line
		(start 63.222124 -14.321028)
		(end 63.22441 -14.313662)
		(stroke
			(width 0.0635)
			(type default)
		)
		(layer "In2.Cu")
	)
	(gr_line
		(start 63.278766 -6.480302)
		(end 63.29807 -6.370574)
		(stroke
			(width 0.0635)
			(type default)
		)
		(layer "In2.Cu")
	)
	(gr_line
		(start 63.29807 -6.370574)
		(end 63.313056 -6.340856)
		(stroke
			(width 0.0635)
			(type default)
		)
		(layer "In2.Cu")
	)
	(gr_line
		(start 64.697356 -19.53006)
		(end 64.708532 -19.522186)
		(stroke
			(width 0.0635)
			(type default)
		)
		(layer "In2.Cu")
	)
	(gr_line
		(start 64.708532 -19.522186)
		(end 64.716406 -19.51101)
		(stroke
			(width 0.0635)
			(type default)
		)
		(layer "In2.Cu")
	)
	(gr_line
		(start 65.079372 -29.570426)
		(end 65.457578 -28.814522)
		(stroke
			(width 0.0635)
			(type default)
		)
		(layer "In2.Cu")
	)
	(gr_line
		(start 65.400682 -28.644088)
		(end 65.400936 -28.644088)
		(stroke
			(width 0.0635)
			(type default)
		)
		(layer "In2.Cu")
	)
	(gr_line
		(start 65.42151 -26.245566)
		(end 65.772792 -25.722326)
		(stroke
			(width 0.0635)
			(type default)
		)
		(layer "In2.Cu")
	)
	(gr_arc
		(start 65.457578 -28.814522)
		(mid 65.464555 -28.717574)
		(end 65.400936 -28.644088)
		(stroke
			(width 0.0635)
			(type default)
		)
		(layer "In2.Cu")
	)
	(gr_line
		(start 65.531238 -28.382468)
		(end 65.531492 -28.382468)
		(stroke
			(width 0.0635)
			(type default)
		)
		(layer "In2.Cu")
	)
	(gr_arc
		(start 65.531492 -28.382468)
		(mid 65.62844 -28.389445)
		(end 65.701926 -28.325826)
		(stroke
			(width 0.0635)
			(type default)
		)
		(layer "In2.Cu")
	)
	(gr_line
		(start 65.6463 -26.439114)
		(end 65.86855 -26.395426)
		(stroke
			(width 0.0635)
			(type default)
		)
		(layer "In2.Cu")
	)
	(gr_line
		(start 65.701926 -28.325826)
		(end 66.080132 -27.570176)
		(stroke
			(width 0.0635)
			(type default)
		)
		(layer "In2.Cu")
	)
	(gr_line
		(start 65.86855 -26.395426)
		(end 66.081148 -26.079196)
		(stroke
			(width 0.0635)
			(type default)
		)
		(layer "In2.Cu")
	)
	(gr_line
		(start 66.027046 -25.343612)
		(end 66.379598 -24.81834)
		(stroke
			(width 0.0635)
			(type default)
		)
		(layer "In2.Cu")
	)
	(gr_line
		(start 66.03746 -25.856946)
		(end 66.081148 -26.079196)
		(stroke
			(width 0.0635)
			(type default)
		)
		(layer "In2.Cu")
	)
	(gr_line
		(start 66.252344 -25.536652)
		(end 66.474848 -25.492964)
		(stroke
			(width 0.0635)
			(type default)
		)
		(layer "In2.Cu")
	)
	(gr_line
		(start 66.474848 -25.492964)
		(end 66.687192 -25.176734)
		(stroke
			(width 0.0635)
			(type default)
		)
		(layer "In2.Cu")
	)
	(gr_line
		(start 66.615818 -19.81835)
		(end 66.6242 -19.812)
		(stroke
			(width 0.0635)
			(type default)
		)
		(layer "In2.Cu")
	)
	(gr_line
		(start 66.6242 -19.812)
		(end 66.630042 -19.803364)
		(stroke
			(width 0.0635)
			(type default)
		)
		(layer "In2.Cu")
	)
	(gr_line
		(start 66.631312 -24.443436)
		(end 66.98615 -23.914862)
		(stroke
			(width 0.0635)
			(type default)
		)
		(layer "In2.Cu")
	)
	(gr_line
		(start 66.64325 -24.954484)
		(end 66.687192 -25.176734)
		(stroke
			(width 0.0635)
			(type default)
		)
		(layer "In2.Cu")
	)
	(gr_line
		(start 66.829178 -16.493744)
		(end 66.844418 -16.4719)
		(stroke
			(width 0.0635)
			(type default)
		)
		(layer "In2.Cu")
	)
	(gr_line
		(start 66.844418 -16.4719)
		(end 66.849244 -16.44523)
		(stroke
			(width 0.0635)
			(type default)
		)
		(layer "In2.Cu")
	)
	(gr_line
		(start 66.858134 -24.634444)
		(end 67.080892 -24.590502)
		(stroke
			(width 0.0635)
			(type default)
		)
		(layer "In2.Cu")
	)
	(gr_line
		(start 67.018916 -6.272784)
		(end 67.023742 -6.245606)
		(stroke
			(width 0.0635)
			(type default)
		)
		(layer "In2.Cu")
	)
	(gr_line
		(start 67.023742 -6.245606)
		(end 67.03949 -6.223)
		(stroke
			(width 0.0635)
			(type default)
		)
		(layer "In2.Cu")
	)
	(gr_line
		(start 67.047364 -27.022044)
		(end 67.050666 -27.008582)
		(stroke
			(width 0.0635)
			(type default)
		)
		(layer "In2.Cu")
	)
	(gr_line
		(start 67.050666 -27.008582)
		(end 67.058286 -26.996898)
		(stroke
			(width 0.0635)
			(type default)
		)
		(layer "In2.Cu")
	)
	(gr_line
		(start 67.080892 -24.590502)
		(end 67.293236 -24.274272)
		(stroke
			(width 0.0635)
			(type default)
		)
		(layer "In2.Cu")
	)
	(gr_line
		(start 67.249294 -24.051768)
		(end 67.293236 -24.274272)
		(stroke
			(width 0.0635)
			(type default)
		)
		(layer "In2.Cu")
	)
	(gr_arc
		(start 67.458336 -32.825436)
		(mid 67.269326 -32.447437)
		(end 67.079622 -32.069786)
		(stroke
			(width 0.0635)
			(type default)
		)
		(layer "In2.Cu")
	)
	(gr_arc
		(start 67.458336 -32.825436)
		(mid 67.531644 -32.889149)
		(end 67.628516 -32.882332)
		(stroke
			(width 0.0635)
			(type default)
		)
		(layer "In2.Cu")
	)
	(gr_line
		(start 67.603878 -26.224992)
		(end 67.761612 -26.058114)
		(stroke
			(width 0.0635)
			(type default)
		)
		(layer "In2.Cu")
	)
	(gr_line
		(start 67.627246 -22.962616)
		(end 67.634866 -22.951694)
		(stroke
			(width 0.0635)
			(type default)
		)
		(layer "In2.Cu")
	)
	(gr_line
		(start 67.628516 -32.882332)
		(end 67.62877 -32.882332)
		(stroke
			(width 0.0635)
			(type default)
		)
		(layer "In2.Cu")
	)
	(gr_line
		(start 67.62877 -32.882332)
		(end 67.634612 -32.879538)
		(stroke
			(width 0.0635)
			(type default)
		)
		(layer "In2.Cu")
	)
	(gr_line
		(start 67.634866 -22.951694)
		(end 67.646042 -22.94382)
		(stroke
			(width 0.0635)
			(type default)
		)
		(layer "In2.Cu")
	)
	(gr_line
		(start 67.702684 -33.313878)
		(end 68.080382 -34.070036)
		(stroke
			(width 0.0635)
			(type default)
		)
		(layer "In2.Cu")
	)
	(gr_line
		(start 67.755008 -25.828244)
		(end 67.761612 -26.054558)
		(stroke
			(width 0.0635)
			(type default)
		)
		(layer "In2.Cu")
	)
	(gr_line
		(start 67.755008 -25.828244)
		(end 68.016882 -25.551384)
		(stroke
			(width 0.0635)
			(type default)
		)
		(layer "In2.Cu")
	)
	(gr_arc
		(start 67.75958 -33.143444)
		(mid 67.695817 -33.216897)
		(end 67.702684 -33.313878)
		(stroke
			(width 0.0635)
			(type default)
		)
		(layer "In2.Cu")
	)
	(gr_line
		(start 67.75958 -33.143444)
		(end 67.759834 -33.143444)
		(stroke
			(width 0.0635)
			(type default)
		)
		(layer "In2.Cu")
	)
	(gr_line
		(start 67.780408 -26.463244)
		(end 67.977512 -26.254964)
		(stroke
			(width 0.0635)
			(type default)
		)
		(layer "In2.Cu")
	)
	(gr_line
		(start 68.00088 -26.230072)
		(end 68.432172 -25.773888)
		(stroke
			(width 0.0635)
			(type default)
		)
		(layer "In2.Cu")
	)
	(gr_line
		(start 68.016882 -25.551384)
		(end 68.243196 -25.545034)
		(stroke
			(width 0.0635)
			(type default)
		)
		(layer "In2.Cu")
	)
	(gr_line
		(start 68.502022 -25.038304)
		(end 68.508372 -25.264618)
		(stroke
			(width 0.0635)
			(type default)
		)
		(layer "In2.Cu")
	)
	(gr_line
		(start 68.502022 -25.038304)
		(end 68.763642 -24.761444)
		(stroke
			(width 0.0635)
			(type default)
		)
		(layer "In2.Cu")
	)
	(gr_line
		(start 68.74764 -25.440386)
		(end 69.178424 -24.984456)
		(stroke
			(width 0.0635)
			(type default)
		)
		(layer "In2.Cu")
	)
	(gr_line
		(start 68.763642 -24.761444)
		(end 68.989956 -24.755094)
		(stroke
			(width 0.0635)
			(type default)
		)
		(layer "In2.Cu")
	)
	(gr_line
		(start 69.006212 -6.34619)
		(end 69.011038 -6.319012)
		(stroke
			(width 0.0635)
			(type default)
		)
		(layer "In2.Cu")
	)
	(gr_line
		(start 69.011038 -6.319012)
		(end 69.026786 -6.296406)
		(stroke
			(width 0.0635)
			(type default)
		)
		(layer "In2.Cu")
	)
	(gr_line
		(start 69.079872 -29.570426)
		(end 69.458078 -28.814522)
		(stroke
			(width 0.0635)
			(type default)
		)
		(layer "In2.Cu")
	)
	(gr_line
		(start 69.193664 -26.123392)
		(end 69.20484 -26.07691)
		(stroke
			(width 0.0635)
			(type default)
		)
		(layer "In2.Cu")
	)
	(gr_line
		(start 69.20484 -26.07691)
		(end 69.238876 -26.04389)
		(stroke
			(width 0.0635)
			(type default)
		)
		(layer "In2.Cu")
	)
	(gr_line
		(start 69.26961 3.704082)
		(end 69.292216 3.71983)
		(stroke
			(width 0.0635)
			(type default)
		)
		(layer "In2.Cu")
	)
	(gr_line
		(start 69.292216 3.71983)
		(end 69.319394 3.724656)
		(stroke
			(width 0.0635)
			(type default)
		)
		(layer "In2.Cu")
	)
	(gr_line
		(start 69.401182 -28.644088)
		(end 69.401436 -28.644088)
		(stroke
			(width 0.0635)
			(type default)
		)
		(layer "In2.Cu")
	)
	(gr_arc
		(start 69.458078 -28.814522)
		(mid 69.465068 -28.717558)
		(end 69.401436 -28.644088)
		(stroke
			(width 0.0635)
			(type default)
		)
		(layer "In2.Cu")
	)
	(gr_line
		(start 69.531738 -28.382468)
		(end 69.531992 -28.382468)
		(stroke
			(width 0.0635)
			(type default)
		)
		(layer "In2.Cu")
	)
	(gr_arc
		(start 69.531992 -28.382468)
		(mid 69.62894 -28.389445)
		(end 69.702426 -28.325826)
		(stroke
			(width 0.0635)
			(type default)
		)
		(layer "In2.Cu")
	)
	(gr_line
		(start 69.552312 -2.634996)
		(end 69.560186 -2.62382)
		(stroke
			(width 0.0635)
			(type default)
		)
		(layer "In2.Cu")
	)
	(gr_line
		(start 69.560186 -2.62382)
		(end 69.571362 -2.615946)
		(stroke
			(width 0.0635)
			(type default)
		)
		(layer "In2.Cu")
	)
	(gr_line
		(start 69.567044 -25.725374)
		(end 70.018656 -25.28697)
		(stroke
			(width 0.0635)
			(type default)
		)
		(layer "In2.Cu")
	)
	(gr_line
		(start 69.702426 -28.325826)
		(end 70.079362 -27.570176)
		(stroke
			(width 0.0635)
			(type default)
		)
		(layer "In2.Cu")
	)
	(gr_line
		(start 69.746368 -25.961848)
		(end 69.972682 -25.965404)
		(stroke
			(width 0.0635)
			(type default)
		)
		(layer "In2.Cu")
	)
	(gr_line
		(start 69.828664 -20.411694)
		(end 69.839078 -20.403566)
		(stroke
			(width 0.0635)
			(type default)
		)
		(layer "In2.Cu")
	)
	(gr_line
		(start 69.839078 -20.403566)
		(end 69.846444 -20.392136)
		(stroke
			(width 0.0635)
			(type default)
		)
		(layer "In2.Cu")
	)
	(gr_line
		(start 69.972682 -25.965404)
		(end 70.24624 -25.699974)
		(stroke
			(width 0.0635)
			(type default)
		)
		(layer "In2.Cu")
	)
	(gr_line
		(start 70.24624 -25.699974)
		(end 70.249542 -25.47366)
		(stroke
			(width 0.0635)
			(type default)
		)
		(layer "In2.Cu")
	)
	(gr_line
		(start 70.345808 -24.969216)
		(end 70.800468 -24.527764)
		(stroke
			(width 0.0635)
			(type default)
		)
		(layer "In2.Cu")
	)
	(gr_line
		(start 70.347332 2.886456)
		(end 70.369938 2.902204)
		(stroke
			(width 0.0635)
			(type default)
		)
		(layer "In2.Cu")
	)
	(gr_line
		(start 70.369938 2.902204)
		(end 70.397116 2.90703)
		(stroke
			(width 0.0635)
			(type default)
		)
		(layer "In2.Cu")
	)
	(gr_line
		(start 70.498208 -16.75003)
		(end 70.501256 -16.742664)
		(stroke
			(width 0.0635)
			(type default)
		)
		(layer "In2.Cu")
	)
	(gr_line
		(start 70.501002 -16.73479)
		(end 70.50278 -16.739362)
		(stroke
			(width 0.0635)
			(type default)
		)
		(layer "In2.Cu")
	)
	(gr_line
		(start 70.501256 -16.742664)
		(end 70.50278 -16.739362)
		(stroke
			(width 0.0635)
			(type default)
		)
		(layer "In2.Cu")
	)
	(gr_line
		(start 70.526402 -25.204674)
		(end 70.75297 -25.20823)
		(stroke
			(width 0.0635)
			(type default)
		)
		(layer "In2.Cu")
	)
	(gr_line
		(start 70.692518 -17.030954)
		(end 70.70217 -17.02054)
		(stroke
			(width 0.0635)
			(type default)
		)
		(layer "In2.Cu")
	)
	(gr_line
		(start 70.70217 -17.02054)
		(end 70.707758 -17.007332)
		(stroke
			(width 0.0635)
			(type default)
		)
		(layer "In2.Cu")
	)
	(gr_line
		(start 70.75297 -25.20823)
		(end 71.026274 -24.9428)
		(stroke
			(width 0.0635)
			(type default)
		)
		(layer "In2.Cu")
	)
	(gr_line
		(start 70.770242 -16.856964)
		(end 70.771004 -16.854932)
		(stroke
			(width 0.0635)
			(type default)
		)
		(layer "In2.Cu")
	)
	(gr_line
		(start 70.771258 -16.854424)
		(end 70.772782 -16.851122)
		(stroke
			(width 0.0635)
			(type default)
		)
		(layer "In2.Cu")
	)
	(gr_line
		(start 70.77583 -16.849852)
		(end 70.777354 -16.84909)
		(stroke
			(width 0.0635)
			(type default)
		)
		(layer "In2.Cu")
	)
	(gr_line
		(start 70.777354 -16.84909)
		(end 70.77837 -16.843756)
		(stroke
			(width 0.0635)
			(type default)
		)
		(layer "In2.Cu")
	)
	(gr_line
		(start 70.78091 -16.82877)
		(end 70.794626 -16.752062)
		(stroke
			(width 0.0635)
			(type default)
		)
		(layer "In2.Cu")
	)
	(gr_line
		(start 70.950074 -3.549904)
		(end 70.957948 -3.538728)
		(stroke
			(width 0.0635)
			(type default)
		)
		(layer "In2.Cu")
	)
	(gr_line
		(start 70.95363 -27.310842)
		(end 70.95363 -27.314652)
		(stroke
			(width 0.0635)
			(type default)
		)
		(layer "In2.Cu")
	)
	(gr_line
		(start 70.95363 -27.310842)
		(end 70.954646 -27.307286)
		(stroke
			(width 0.0635)
			(type default)
		)
		(layer "In2.Cu")
	)
	(gr_line
		(start 70.957948 -3.538728)
		(end 70.969124 -3.530854)
		(stroke
			(width 0.0635)
			(type default)
		)
		(layer "In2.Cu")
	)
	(gr_line
		(start 71.005954 -6.340856)
		(end 71.01078 -6.313678)
		(stroke
			(width 0.0635)
			(type default)
		)
		(layer "In2.Cu")
	)
	(gr_line
		(start 71.01078 -6.313678)
		(end 71.026528 -6.291072)
		(stroke
			(width 0.0635)
			(type default)
		)
		(layer "In2.Cu")
	)
	(gr_line
		(start 71.026274 -24.9428)
		(end 71.02983 -24.716232)
		(stroke
			(width 0.0635)
			(type default)
		)
		(layer "In2.Cu")
	)
	(gr_line
		(start 71.080122 -32.069786)
		(end 71.457566 -32.825436)
		(stroke
			(width 0.0635)
			(type default)
		)
		(layer "In2.Cu")
	)
	(gr_line
		(start 71.087742 -26.788364)
		(end 71.097394 -26.751026)
		(stroke
			(width 0.0635)
			(type default)
		)
		(layer "In2.Cu")
	)
	(gr_line
		(start 71.097394 -26.751026)
		(end 71.124318 -26.722578)
		(stroke
			(width 0.0635)
			(type default)
		)
		(layer "In2.Cu")
	)
	(gr_line
		(start 71.125334 -24.212804)
		(end 71.579486 -23.772114)
		(stroke
			(width 0.0635)
			(type default)
		)
		(layer "In2.Cu")
	)
	(gr_line
		(start 71.306436 -24.447754)
		(end 71.533004 -24.451056)
		(stroke
			(width 0.0635)
			(type default)
		)
		(layer "In2.Cu")
	)
	(gr_line
		(start 71.399146 -26.204418)
		(end 71.402956 -26.430732)
		(stroke
			(width 0.0635)
			(type default)
		)
		(layer "In2.Cu")
	)
	(gr_line
		(start 71.399146 -26.204418)
		(end 71.663814 -25.930352)
		(stroke
			(width 0.0635)
			(type default)
		)
		(layer "In2.Cu")
	)
	(gr_arc
		(start 71.457566 -32.825436)
		(mid 71.530872 -32.889129)
		(end 71.627746 -32.882332)
		(stroke
			(width 0.0635)
			(type default)
		)
		(layer "In2.Cu")
	)
	(gr_line
		(start 71.513446 2.140458)
		(end 71.536052 2.156206)
		(stroke
			(width 0.0635)
			(type default)
		)
		(layer "In2.Cu")
	)
	(gr_line
		(start 71.533004 -24.451056)
		(end 71.806308 -24.185626)
		(stroke
			(width 0.0635)
			(type default)
		)
		(layer "In2.Cu")
	)
	(gr_line
		(start 71.536052 2.156206)
		(end 71.56323 2.161032)
		(stroke
			(width 0.0635)
			(type default)
		)
		(layer "In2.Cu")
	)
	(gr_line
		(start 71.627746 -32.882332)
		(end 71.628 -32.882332)
		(stroke
			(width 0.0635)
			(type default)
		)
		(layer "In2.Cu")
	)
	(gr_line
		(start 71.628 -32.882332)
		(end 71.633842 -32.879538)
		(stroke
			(width 0.0635)
			(type default)
		)
		(layer "In2.Cu")
	)
	(gr_line
		(start 71.639684 -26.609802)
		(end 72.078596 -26.155904)
		(stroke
			(width 0.0635)
			(type default)
		)
		(layer "In2.Cu")
	)
	(gr_line
		(start 71.663814 -25.930352)
		(end 71.890636 -25.926542)
		(stroke
			(width 0.0635)
			(type default)
		)
		(layer "In2.Cu")
	)
	(gr_line
		(start 71.701914 -33.313878)
		(end 72.079612 -34.070036)
		(stroke
			(width 0.0635)
			(type default)
		)
		(layer "In2.Cu")
	)
	(gr_arc
		(start 71.75881 -33.143444)
		(mid 71.695168 -33.216907)
		(end 71.701914 -33.313878)
		(stroke
			(width 0.0635)
			(type default)
		)
		(layer "In2.Cu")
	)
	(gr_line
		(start 71.75881 -33.143444)
		(end 71.759064 -33.143444)
		(stroke
			(width 0.0635)
			(type default)
		)
		(layer "In2.Cu")
	)
	(gr_line
		(start 71.806308 -24.185626)
		(end 71.809864 -23.959058)
		(stroke
			(width 0.0635)
			(type default)
		)
		(layer "In2.Cu")
	)
	(gr_line
		(start 71.969122 -20.273518)
		(end 71.980298 -20.265644)
		(stroke
			(width 0.0635)
			(type default)
		)
		(layer "In2.Cu")
	)
	(gr_line
		(start 71.980298 -20.265644)
		(end 71.988172 -20.254468)
		(stroke
			(width 0.0635)
			(type default)
		)
		(layer "In2.Cu")
	)
	(gr_line
		(start 72.154796 -25.42286)
		(end 72.158606 -25.649428)
		(stroke
			(width 0.0635)
			(type default)
		)
		(layer "In2.Cu")
	)
	(gr_line
		(start 72.154796 -25.42286)
		(end 72.419464 -25.149048)
		(stroke
			(width 0.0635)
			(type default)
		)
		(layer "In2.Cu")
	)
	(gr_line
		(start 72.394318 -25.829514)
		(end 72.835516 -25.37333)
		(stroke
			(width 0.0635)
			(type default)
		)
		(layer "In2.Cu")
	)
	(gr_line
		(start 72.419464 -25.149048)
		(end 72.64654 -25.144984)
		(stroke
			(width 0.0635)
			(type default)
		)
		(layer "In2.Cu")
	)
	(gr_line
		(start 72.870568 1.36271)
		(end 72.893174 1.378458)
		(stroke
			(width 0.0635)
			(type default)
		)
		(layer "In2.Cu")
	)
	(gr_line
		(start 72.893174 1.378458)
		(end 72.920352 1.383284)
		(stroke
			(width 0.0635)
			(type default)
		)
		(layer "In2.Cu")
	)
	(gr_line
		(start 72.9107 -3.60045)
		(end 72.918574 -3.589274)
		(stroke
			(width 0.0635)
			(type default)
		)
		(layer "In2.Cu")
	)
	(gr_line
		(start 72.918574 -3.589274)
		(end 72.92975 -3.5814)
		(stroke
			(width 0.0635)
			(type default)
		)
		(layer "In2.Cu")
	)
	(gr_line
		(start 73.037446 -6.164834)
		(end 73.042272 -6.137656)
		(stroke
			(width 0.0635)
			(type default)
		)
		(layer "In2.Cu")
	)
	(gr_line
		(start 73.042272 -6.137656)
		(end 73.05802 -6.11505)
		(stroke
			(width 0.0635)
			(type default)
		)
		(layer "In2.Cu")
	)
	(gr_line
		(start 73.080372 -29.570426)
		(end 73.458578 -28.814522)
		(stroke
			(width 0.0635)
			(type default)
		)
		(layer "In2.Cu")
	)
	(gr_line
		(start 73.209912 -14.929612)
		(end 73.22439 -14.901164)
		(stroke
			(width 0.0635)
			(type default)
		)
		(layer "In2.Cu")
	)
	(gr_line
		(start 73.322942 -26.299922)
		(end 73.328784 -26.287476)
		(stroke
			(width 0.0635)
			(type default)
		)
		(layer "In2.Cu")
	)
	(gr_line
		(start 73.328784 -26.287476)
		(end 73.339198 -26.276554)
		(stroke
			(width 0.0635)
			(type default)
		)
		(layer "In2.Cu")
	)
	(gr_line
		(start 73.401682 -28.644088)
		(end 73.401936 -28.644088)
		(stroke
			(width 0.0635)
			(type default)
		)
		(layer "In2.Cu")
	)
	(gr_arc
		(start 73.458578 -28.814522)
		(mid 73.465568 -28.717558)
		(end 73.401936 -28.644088)
		(stroke
			(width 0.0635)
			(type default)
		)
		(layer "In2.Cu")
	)
	(gr_line
		(start 73.532238 -28.382468)
		(end 73.532492 -28.382468)
		(stroke
			(width 0.0635)
			(type default)
		)
		(layer "In2.Cu")
	)
	(gr_arc
		(start 73.532492 -28.382468)
		(mid 73.62944 -28.389445)
		(end 73.702926 -28.325826)
		(stroke
			(width 0.0635)
			(type default)
		)
		(layer "In2.Cu")
	)
	(gr_line
		(start 73.666096 -25.955244)
		(end 74.1172 -25.512268)
		(stroke
			(width 0.0635)
			(type default)
		)
		(layer "In2.Cu")
	)
	(gr_line
		(start 73.702926 -28.325826)
		(end 74.079862 -27.570176)
		(stroke
			(width 0.0635)
			(type default)
		)
		(layer "In2.Cu")
	)
	(gr_line
		(start 73.847198 -26.190194)
		(end 74.073766 -26.19248)
		(stroke
			(width 0.0635)
			(type default)
		)
		(layer "In2.Cu")
	)
	(gr_line
		(start 74.061066 0.528066)
		(end 74.083672 0.543814)
		(stroke
			(width 0.0635)
			(type default)
		)
		(layer "In2.Cu")
	)
	(gr_line
		(start 74.073766 -26.19248)
		(end 74.3458 -25.925526)
		(stroke
			(width 0.0635)
			(type default)
		)
		(layer "In2.Cu")
	)
	(gr_line
		(start 74.083672 0.543814)
		(end 74.11085 0.54864)
		(stroke
			(width 0.0635)
			(type default)
		)
		(layer "In2.Cu")
	)
	(gr_line
		(start 74.20356 -4.47929)
		(end 74.211434 -4.468114)
		(stroke
			(width 0.0635)
			(type default)
		)
		(layer "In2.Cu")
	)
	(gr_line
		(start 74.211434 -4.468114)
		(end 74.22261 -4.46024)
		(stroke
			(width 0.0635)
			(type default)
		)
		(layer "In2.Cu")
	)
	(gr_line
		(start 74.3458 -25.925526)
		(end 74.347832 -25.698704)
		(stroke
			(width 0.0635)
			(type default)
		)
		(layer "In2.Cu")
	)
	(gr_line
		(start 74.440288 -25.195022)
		(end 74.893932 -24.749506)
		(stroke
			(width 0.0635)
			(type default)
		)
		(layer "In2.Cu")
	)
	(gr_line
		(start 74.62266 -25.428702)
		(end 74.849736 -25.430734)
		(stroke
			(width 0.0635)
			(type default)
		)
		(layer "In2.Cu")
	)
	(gr_line
		(start 74.849736 -25.430734)
		(end 75.121516 -25.16378)
		(stroke
			(width 0.0635)
			(type default)
		)
		(layer "In2.Cu")
	)
	(gr_line
		(start 74.897742 -16.099536)
		(end 74.91349 -16.07693)
		(stroke
			(width 0.0635)
			(type default)
		)
		(layer "In2.Cu")
	)
	(gr_line
		(start 74.91349 -16.07693)
		(end 74.918316 -16.049752)
		(stroke
			(width 0.0635)
			(type default)
		)
		(layer "In2.Cu")
	)
	(gr_line
		(start 75.073002 -6.46049)
		(end 75.078336 -6.430772)
		(stroke
			(width 0.0635)
			(type default)
		)
		(layer "In2.Cu")
	)
	(gr_line
		(start 75.078336 -6.430772)
		(end 75.095608 -6.40588)
		(stroke
			(width 0.0635)
			(type default)
		)
		(layer "In2.Cu")
	)
	(gr_line
		(start 75.082654 -26.919428)
		(end 75.083416 -26.918666)
		(stroke
			(width 0.0635)
			(type default)
		)
		(layer "In2.Cu")
	)
	(gr_line
		(start 75.121516 -25.16378)
		(end 75.123802 -24.936704)
		(stroke
			(width 0.0635)
			(type default)
		)
		(layer "In2.Cu")
	)
	(gr_line
		(start 75.21575 -24.433784)
		(end 75.669648 -23.988014)
		(stroke
			(width 0.0635)
			(type default)
		)
		(layer "In2.Cu")
	)
	(gr_line
		(start 75.330558 -26.409142)
		(end 75.34021 -26.635456)
		(stroke
			(width 0.0635)
			(type default)
		)
		(layer "In2.Cu")
	)
	(gr_line
		(start 75.330558 -26.409142)
		(end 75.588368 -26.128472)
		(stroke
			(width 0.0635)
			(type default)
		)
		(layer "In2.Cu")
	)
	(gr_line
		(start 75.332082 -6.069076)
		(end 75.340464 -6.057138)
		(stroke
			(width 0.0635)
			(type default)
		)
		(layer "In2.Cu")
	)
	(gr_line
		(start 75.340464 -6.057138)
		(end 75.352402 -6.048756)
		(stroke
			(width 0.0635)
			(type default)
		)
		(layer "In2.Cu")
	)
	(gr_line
		(start 75.398376 -24.66721)
		(end 75.625452 -24.669242)
		(stroke
			(width 0.0635)
			(type default)
		)
		(layer "In2.Cu")
	)
	(gr_arc
		(start 75.458066 -32.825436)
		(mid 75.269056 -32.447437)
		(end 75.079352 -32.069786)
		(stroke
			(width 0.0635)
			(type default)
		)
		(layer "In2.Cu")
	)
	(gr_arc
		(start 75.458066 -32.825436)
		(mid 75.531372 -32.88913)
		(end 75.628246 -32.882332)
		(stroke
			(width 0.0635)
			(type default)
		)
		(layer "In2.Cu")
	)
	(gr_line
		(start 75.581002 -26.808938)
		(end 76.007468 -26.344372)
		(stroke
			(width 0.0635)
			(type default)
		)
		(layer "In2.Cu")
	)
	(gr_line
		(start 75.588368 -26.128472)
		(end 75.814682 -26.119074)
		(stroke
			(width 0.0635)
			(type default)
		)
		(layer "In2.Cu")
	)
	(gr_line
		(start 75.625452 -24.669242)
		(end 75.897232 -24.402288)
		(stroke
			(width 0.0635)
			(type default)
		)
		(layer "In2.Cu")
	)
	(gr_line
		(start 75.628246 -32.882332)
		(end 75.6285 -32.882332)
		(stroke
			(width 0.0635)
			(type default)
		)
		(layer "In2.Cu")
	)
	(gr_line
		(start 75.6285 -32.882332)
		(end 75.634342 -32.879538)
		(stroke
			(width 0.0635)
			(type default)
		)
		(layer "In2.Cu")
	)
	(gr_line
		(start 75.702414 -33.313878)
		(end 76.080112 -34.070036)
		(stroke
			(width 0.0635)
			(type default)
		)
		(layer "In2.Cu")
	)
	(gr_arc
		(start 75.75931 -33.143444)
		(mid 75.695547 -33.216897)
		(end 75.702414 -33.313878)
		(stroke
			(width 0.0635)
			(type default)
		)
		(layer "In2.Cu")
	)
	(gr_line
		(start 75.75931 -33.143444)
		(end 75.759564 -33.143444)
		(stroke
			(width 0.0635)
			(type default)
		)
		(layer "In2.Cu")
	)
	(gr_line
		(start 75.870308 -0.09906)
		(end 75.892914 -0.083312)
		(stroke
			(width 0.0635)
			(type default)
		)
		(layer "In2.Cu")
	)
	(gr_line
		(start 75.892914 -0.083312)
		(end 75.920092 -0.078486)
		(stroke
			(width 0.0635)
			(type default)
		)
		(layer "In2.Cu")
	)
	(gr_line
		(start 75.897232 -24.402288)
		(end 75.899518 -24.175212)
		(stroke
			(width 0.0635)
			(type default)
		)
		(layer "In2.Cu")
	)
	(gr_line
		(start 76.066142 -25.608534)
		(end 76.07554 -25.834848)
		(stroke
			(width 0.0635)
			(type default)
		)
		(layer "In2.Cu")
	)
	(gr_line
		(start 76.066142 -25.608534)
		(end 76.323952 -25.327864)
		(stroke
			(width 0.0635)
			(type default)
		)
		(layer "In2.Cu")
	)
	(gr_line
		(start 76.31557 -26.009346)
		(end 76.74356 -25.54351)
		(stroke
			(width 0.0635)
			(type default)
		)
		(layer "In2.Cu")
	)
	(gr_line
		(start 76.323952 -25.327864)
		(end 76.550266 -25.318466)
		(stroke
			(width 0.0635)
			(type default)
		)
		(layer "In2.Cu")
	)
	(gr_line
		(start 76.674218 -0.959612)
		(end 76.696824 -0.943864)
		(stroke
			(width 0.0635)
			(type default)
		)
		(layer "In2.Cu")
	)
	(gr_line
		(start 76.696824 -0.943864)
		(end 76.724002 -0.939038)
		(stroke
			(width 0.0635)
			(type default)
		)
		(layer "In2.Cu")
	)
	(gr_line
		(start 76.862686 4.757928)
		(end 76.889864 4.762754)
		(stroke
			(width 0.0635)
			(type default)
		)
		(layer "In2.Cu")
	)
	(gr_line
		(start 76.889864 4.762754)
		(end 76.91247 4.778502)
		(stroke
			(width 0.0635)
			(type default)
		)
		(layer "In2.Cu")
	)
	(gr_line
		(start 77.031342 -6.698234)
		(end 77.036422 -6.669532)
		(stroke
			(width 0.0635)
			(type default)
		)
		(layer "In2.Cu")
	)
	(gr_line
		(start 77.036422 -6.669532)
		(end 77.052932 -6.646164)
		(stroke
			(width 0.0635)
			(type default)
		)
		(layer "In2.Cu")
	)
	(gr_line
		(start 77.07376 -15.104618)
		(end 77.089508 -15.082012)
		(stroke
			(width 0.0635)
			(type default)
		)
		(layer "In2.Cu")
	)
	(gr_line
		(start 77.079602 -29.570426)
		(end 77.457808 -28.814522)
		(stroke
			(width 0.0635)
			(type default)
		)
		(layer "In2.Cu")
	)
	(gr_line
		(start 77.089508 -15.082012)
		(end 77.094334 -15.054834)
		(stroke
			(width 0.0635)
			(type default)
		)
		(layer "In2.Cu")
	)
	(gr_line
		(start 77.244702 -6.371844)
		(end 77.2541 -6.358382)
		(stroke
			(width 0.0635)
			(type default)
		)
		(layer "In2.Cu")
	)
	(gr_line
		(start 77.2541 -6.358382)
		(end 77.267562 -6.348984)
		(stroke
			(width 0.0635)
			(type default)
		)
		(layer "In2.Cu")
	)
	(gr_line
		(start 77.359764 -26.219404)
		(end 77.37729 -26.181812)
		(stroke
			(width 0.0635)
			(type default)
		)
		(layer "In2.Cu")
	)
	(gr_line
		(start 77.37729 -26.181812)
		(end 77.41158 -26.157682)
		(stroke
			(width 0.0635)
			(type default)
		)
		(layer "In2.Cu")
	)
	(gr_line
		(start 77.400912 -28.644088)
		(end 77.401166 -28.644088)
		(stroke
			(width 0.0635)
			(type default)
		)
		(layer "In2.Cu")
	)
	(gr_line
		(start 77.451458 5.155946)
		(end 77.462634 5.16382)
		(stroke
			(width 0.0635)
			(type default)
		)
		(layer "In2.Cu")
	)
	(gr_arc
		(start 77.457808 -28.814522)
		(mid 77.464785 -28.717574)
		(end 77.401166 -28.644088)
		(stroke
			(width 0.0635)
			(type default)
		)
		(layer "In2.Cu")
	)
	(gr_line
		(start 77.462634 5.16382)
		(end 77.470508 5.174996)
		(stroke
			(width 0.0635)
			(type default)
		)
		(layer "In2.Cu")
	)
	(gr_line
		(start 77.531468 -28.382468)
		(end 77.531722 -28.382468)
		(stroke
			(width 0.0635)
			(type default)
		)
		(layer "In2.Cu")
	)
	(gr_arc
		(start 77.531722 -28.382468)
		(mid 77.628663 -28.389431)
		(end 77.702156 -28.325826)
		(stroke
			(width 0.0635)
			(type default)
		)
		(layer "In2.Cu")
	)
	(gr_arc
		(start 77.683614 7.250938)
		(mid 77.580345 7.548601)
		(end 77.305154 7.702042)
		(stroke
			(width 0.0635)
			(type default)
		)
		(layer "In2.Cu")
	)
	(gr_line
		(start 77.702156 -28.325826)
		(end 78.080362 -27.570176)
		(stroke
			(width 0.0635)
			(type default)
		)
		(layer "In2.Cu")
	)
	(gr_line
		(start 77.822044 5.677154)
		(end 77.837792 5.69976)
		(stroke
			(width 0.0635)
			(type default)
		)
		(layer "In2.Cu")
	)
	(gr_line
		(start 77.837792 5.69976)
		(end 77.842618 5.726938)
		(stroke
			(width 0.0635)
			(type default)
		)
		(layer "In2.Cu")
	)
	(gr_line
		(start 78.161896 -1.701546)
		(end 78.184502 -1.685798)
		(stroke
			(width 0.0635)
			(type default)
		)
		(layer "In2.Cu")
	)
	(gr_line
		(start 78.184502 -1.685798)
		(end 78.21168 -1.680972)
		(stroke
			(width 0.0635)
			(type default)
		)
		(layer "In2.Cu")
	)
	(gr_arc
		(start 78.321154 7.702042)
		(mid 78.07563 7.526718)
		(end 77.975714 7.242048)
		(stroke
			(width 0.0635)
			(type default)
		)
		(layer "In2.Cu")
	)
	(gr_line
		(start 78.489556 4.037076)
		(end 78.516734 4.041902)
		(stroke
			(width 0.0635)
			(type default)
		)
		(layer "In2.Cu")
	)
	(gr_line
		(start 78.516734 4.041902)
		(end 78.538324 4.057396)
		(stroke
			(width 0.0635)
			(type default)
		)
		(layer "In2.Cu")
	)
	(gr_line
		(start 78.968854 -27.323542)
		(end 78.968854 -27.328114)
		(stroke
			(width 0.0635)
			(type default)
		)
		(layer "In2.Cu")
	)
	(gr_line
		(start 78.968854 -27.323542)
		(end 78.970124 -27.31897)
		(stroke
			(width 0.0635)
			(type default)
		)
		(layer "In2.Cu")
	)
	(gr_arc
		(start 78.99146 4.838192)
		(mid 78.874772 5.071734)
		(end 78.631288 5.165852)
		(stroke
			(width 0.0635)
			(type default)
		)
		(layer "In2.Cu")
	)
	(gr_line
		(start 78.99146 4.838192)
		(end 78.99146 4.836414)
		(stroke
			(width 0.0635)
			(type default)
		)
		(layer "In2.Cu")
	)
	(gr_line
		(start 78.99273 4.832858)
		(end 78.992984 4.834382)
		(stroke
			(width 0.0635)
			(type default)
		)
		(layer "In2.Cu")
	)
	(gr_line
		(start 78.992984 4.83616)
		(end 78.992984 4.834382)
		(stroke
			(width 0.0635)
			(type default)
		)
		(layer "In2.Cu")
	)
	(gr_line
		(start 79.001366 -6.869176)
		(end 79.0067 -6.839458)
		(stroke
			(width 0.0635)
			(type default)
		)
		(layer "In2.Cu")
	)
	(gr_arc
		(start 79.00416 3.178302)
		(mid 79.06537 3.19613)
		(end 79.121254 3.226816)
		(stroke
			(width 0.0635)
			(type default)
		)
		(layer "In2.Cu")
	)
	(gr_line
		(start 79.0067 -6.839458)
		(end 79.023972 -6.815074)
		(stroke
			(width 0.0635)
			(type default)
		)
		(layer "In2.Cu")
	)
	(gr_line
		(start 79.079852 -32.069786)
		(end 79.457296 -32.825436)
		(stroke
			(width 0.0635)
			(type default)
		)
		(layer "In2.Cu")
	)
	(gr_arc
		(start 79.080614 4.436618)
		(mid 79.119581 4.469554)
		(end 79.152242 4.508754)
		(stroke
			(width 0.0635)
			(type default)
		)
		(layer "In2.Cu")
	)
	(gr_line
		(start 79.100172 -26.896314)
		(end 79.113888 -26.879804)
		(stroke
			(width 0.0635)
			(type default)
		)
		(layer "In2.Cu")
	)
	(gr_line
		(start 79.132176 -14.77391)
		(end 79.147924 -14.751304)
		(stroke
			(width 0.0635)
			(type default)
		)
		(layer "In2.Cu")
	)
	(gr_line
		(start 79.147924 -14.751304)
		(end 79.15275 -14.724126)
		(stroke
			(width 0.0635)
			(type default)
		)
		(layer "In2.Cu")
	)
	(gr_line
		(start 79.178404 -26.811224)
		(end 79.180944 -26.809192)
		(stroke
			(width 0.0635)
			(type default)
		)
		(layer "In2.Cu")
	)
	(gr_arc
		(start 79.226156 4.614164)
		(mid 79.25981 4.677564)
		(end 79.276956 4.74726)
		(stroke
			(width 0.0635)
			(type default)
		)
		(layer "In2.Cu")
	)
	(gr_line
		(start 79.283306 4.802378)
		(end 79.283306 4.8006)
		(stroke
			(width 0.0635)
			(type default)
		)
		(layer "In2.Cu")
	)
	(gr_line
		(start 79.30896 -6.407912)
		(end 79.318612 -6.394196)
		(stroke
			(width 0.0635)
			(type default)
		)
		(layer "In2.Cu")
	)
	(gr_line
		(start 79.318612 -6.394196)
		(end 79.332074 -6.384798)
		(stroke
			(width 0.0635)
			(type default)
		)
		(layer "In2.Cu")
	)
	(gr_line
		(start 79.3623 -27.0383)
		(end 79.371952 -27.03068)
		(stroke
			(width 0.0635)
			(type default)
		)
		(layer "In2.Cu")
	)
	(gr_line
		(start 79.45374 -26.587704)
		(end 79.478632 -26.362406)
		(stroke
			(width 0.0635)
			(type default)
		)
		(layer "In2.Cu")
	)
	(gr_arc
		(start 79.457296 -32.825436)
		(mid 79.530599 -32.889111)
		(end 79.627476 -32.882332)
		(stroke
			(width 0.0635)
			(type default)
		)
		(layer "In2.Cu")
	)
	(gr_line
		(start 79.478632 -26.362406)
		(end 79.775812 -26.124154)
		(stroke
			(width 0.0635)
			(type default)
		)
		(layer "In2.Cu")
	)
	(gr_line
		(start 79.627476 -32.882332)
		(end 79.62773 -32.882332)
		(stroke
			(width 0.0635)
			(type default)
		)
		(layer "In2.Cu")
	)
	(gr_line
		(start 79.62773 -32.882332)
		(end 79.633572 -32.879538)
		(stroke
			(width 0.0635)
			(type default)
		)
		(layer "In2.Cu")
	)
	(gr_arc
		(start 79.647288 5.165852)
		(mid 79.391358 5.059835)
		(end 79.285338 4.803902)
		(stroke
			(width 0.0635)
			(type default)
		)
		(layer "In2.Cu")
	)
	(gr_line
		(start 79.665576 -26.79573)
		(end 80.160622 -26.399236)
		(stroke
			(width 0.0635)
			(type default)
		)
		(layer "In2.Cu")
	)
	(gr_line
		(start 79.701644 -33.313878)
		(end 80.079342 -34.070036)
		(stroke
			(width 0.0635)
			(type default)
		)
		(layer "In2.Cu")
	)
	(gr_arc
		(start 79.75854 -33.143444)
		(mid 79.694777 -33.216897)
		(end 79.701644 -33.313878)
		(stroke
			(width 0.0635)
			(type default)
		)
		(layer "In2.Cu")
	)
	(gr_line
		(start 79.75854 -33.143444)
		(end 79.758794 -33.143444)
		(stroke
			(width 0.0635)
			(type default)
		)
		(layer "In2.Cu")
	)
	(gr_line
		(start 79.775812 -26.124154)
		(end 80.001618 -26.1493)
		(stroke
			(width 0.0635)
			(type default)
		)
		(layer "In2.Cu")
	)
	(gr_arc
		(start 80.006698 3.84683)
		(mid 80.04564 3.879516)
		(end 80.078326 3.918458)
		(stroke
			(width 0.0635)
			(type default)
		)
		(layer "In2.Cu")
	)
	(gr_line
		(start 80.057498 2.344674)
		(end 80.084676 2.3495)
		(stroke
			(width 0.0635)
			(type default)
		)
		(layer "In2.Cu")
	)
	(gr_line
		(start 80.084676 2.3495)
		(end 80.107282 2.365248)
		(stroke
			(width 0.0635)
			(type default)
		)
		(layer "In2.Cu")
	)
	(gr_line
		(start 80.202786 6.040882)
		(end 80.203802 6.048502)
		(stroke
			(width 0.0635)
			(type default)
		)
		(layer "In2.Cu")
	)
	(gr_line
		(start 80.202786 6.040882)
		(end 80.204056 6.033262)
		(stroke
			(width 0.0635)
			(type default)
		)
		(layer "In2.Cu")
	)
	(gr_arc
		(start 80.274414 7.2263)
		(mid 80.168254 7.530244)
		(end 79.895954 7.702042)
		(stroke
			(width 0.0635)
			(type default)
		)
		(layer "In2.Cu")
	)
	(gr_line
		(start 80.301846 -25.908762)
		(end 80.326992 -25.682702)
		(stroke
			(width 0.0635)
			(type default)
		)
		(layer "In2.Cu")
	)
	(gr_line
		(start 80.326992 -25.682702)
		(end 80.624172 -25.44445)
		(stroke
			(width 0.0635)
			(type default)
		)
		(layer "In2.Cu")
	)
	(gr_line
		(start 80.35417 -23.97506)
		(end 80.380586 -23.937722)
		(stroke
			(width 0.0635)
			(type default)
		)
		(layer "In2.Cu")
	)
	(gr_line
		(start 80.384142 -24.43353)
		(end 80.395318 -24.425656)
		(stroke
			(width 0.0635)
			(type default)
		)
		(layer "In2.Cu")
	)
	(gr_line
		(start 80.395318 -24.425656)
		(end 80.403192 -24.41448)
		(stroke
			(width 0.0635)
			(type default)
		)
		(layer "In2.Cu")
	)
	(gr_line
		(start 80.396588 -23.914354)
		(end 80.757776 -23.39848)
		(stroke
			(width 0.0635)
			(type default)
		)
		(layer "In2.Cu")
	)
	(gr_arc
		(start 80.439514 4.434078)
		(mid 80.470051 4.489853)
		(end 80.487774 4.550918)
		(stroke
			(width 0.0635)
			(type default)
		)
		(layer "In2.Cu")
	)
	(gr_line
		(start 80.508856 -26.120598)
		(end 81.014062 -25.71623)
		(stroke
			(width 0.0635)
			(type default)
		)
		(layer "In2.Cu")
	)
	(gr_line
		(start 80.54975 1.387094)
		(end 80.576928 1.39192)
		(stroke
			(width 0.0635)
			(type default)
		)
		(layer "In2.Cu")
	)
	(gr_line
		(start 80.576928 1.39192)
		(end 80.599534 1.407668)
		(stroke
			(width 0.0635)
			(type default)
		)
		(layer "In2.Cu")
	)
	(gr_arc
		(start 80.58023 5.074158)
		(mid 80.583499 5.099464)
		(end 80.584548 5.124958)
		(stroke
			(width 0.0635)
			(type default)
		)
		(layer "In2.Cu")
	)
	(gr_line
		(start 80.593438 -24.1427)
		(end 80.613758 -24.11349)
		(stroke
			(width 0.0635)
			(type default)
		)
		(layer "In2.Cu")
	)
	(gr_line
		(start 80.617314 -24.112982)
		(end 80.840326 -24.073612)
		(stroke
			(width 0.0635)
			(type default)
		)
		(layer "In2.Cu")
	)
	(gr_line
		(start 80.624172 -25.44445)
		(end 80.850994 -25.469342)
		(stroke
			(width 0.0635)
			(type default)
		)
		(layer "In2.Cu")
	)
	(gr_line
		(start 80.774794 -23.374604)
		(end 80.784446 -23.360634)
		(stroke
			(width 0.0635)
			(type default)
		)
		(layer "In2.Cu")
	)
	(gr_line
		(start 80.781144 -2.2479)
		(end 80.805528 -2.230628)
		(stroke
			(width 0.0635)
			(type default)
		)
		(layer "In2.Cu")
	)
	(gr_line
		(start 80.805528 -2.230628)
		(end 80.835246 -2.225294)
		(stroke
			(width 0.0635)
			(type default)
		)
		(layer "In2.Cu")
	)
	(gr_line
		(start 80.840326 -24.073612)
		(end 81.058766 -23.761446)
		(stroke
			(width 0.0635)
			(type default)
		)
		(layer "In2.Cu")
	)
	(gr_line
		(start 80.84439 -23.275036)
		(end 81.00187 -23.049992)
		(stroke
			(width 0.0635)
			(type default)
		)
		(layer "In2.Cu")
	)
	(gr_arc
		(start 80.911954 7.702042)
		(mid 80.660271 7.483003)
		(end 80.566514 7.1628)
		(stroke
			(width 0.0635)
			(type default)
		)
		(layer "In2.Cu")
	)
	(gr_line
		(start 81.002632 -6.731508)
		(end 81.007458 -6.70433)
		(stroke
			(width 0.0635)
			(type default)
		)
		(layer "In2.Cu")
	)
	(gr_line
		(start 81.007458 -6.70433)
		(end 81.023206 -6.681724)
		(stroke
			(width 0.0635)
			(type default)
		)
		(layer "In2.Cu")
	)
	(gr_line
		(start 81.019396 -23.538434)
		(end 81.058766 -23.761446)
		(stroke
			(width 0.0635)
			(type default)
		)
		(layer "In2.Cu")
	)
	(gr_line
		(start 81.01965 -23.024338)
		(end 81.382108 -22.506686)
		(stroke
			(width 0.0635)
			(type default)
		)
		(layer "In2.Cu")
	)
	(gr_line
		(start 81.092802 0.536194)
		(end 81.11998 0.54102)
		(stroke
			(width 0.0635)
			(type default)
		)
		(layer "In2.Cu")
	)
	(gr_line
		(start 81.11998 0.54102)
		(end 81.142586 0.556768)
		(stroke
			(width 0.0635)
			(type default)
		)
		(layer "In2.Cu")
	)
	(gr_line
		(start 81.125822 -14.812264)
		(end 81.14157 -14.789658)
		(stroke
			(width 0.0635)
			(type default)
		)
		(layer "In2.Cu")
	)
	(gr_line
		(start 81.14157 -14.789658)
		(end 81.146396 -14.76248)
		(stroke
			(width 0.0635)
			(type default)
		)
		(layer "In2.Cu")
	)
	(gr_line
		(start 81.240884 -23.222458)
		(end 81.463896 -23.183088)
		(stroke
			(width 0.0635)
			(type default)
		)
		(layer "In2.Cu")
	)
	(gr_line
		(start 81.35239 -6.21157)
		(end 81.360264 -6.200394)
		(stroke
			(width 0.0635)
			(type default)
		)
		(layer "In2.Cu")
	)
	(gr_line
		(start 81.360264 -6.200394)
		(end 81.37144 -6.19252)
		(stroke
			(width 0.0635)
			(type default)
		)
		(layer "In2.Cu")
	)
	(gr_line
		(start 81.463896 -23.183088)
		(end 81.682336 -22.870922)
		(stroke
			(width 0.0635)
			(type default)
		)
		(layer "In2.Cu")
	)
	(gr_line
		(start 81.468214 3.318256)
		(end 81.47939 3.32613)
		(stroke
			(width 0.0635)
			(type default)
		)
		(layer "In2.Cu")
	)
	(gr_line
		(start 81.47939 3.32613)
		(end 81.487264 3.337306)
		(stroke
			(width 0.0635)
			(type default)
		)
		(layer "In2.Cu")
	)
	(gr_arc
		(start 81.600548 4.71678)
		(mid 81.496708 5.013315)
		(end 81.222088 5.165852)
		(stroke
			(width 0.0635)
			(type default)
		)
		(layer "In2.Cu")
	)
	(gr_line
		(start 81.621884 -3.299968)
		(end 81.645252 -3.283458)
		(stroke
			(width 0.0635)
			(type default)
		)
		(layer "In2.Cu")
	)
	(gr_line
		(start 81.642712 -22.134322)
		(end 82.005932 -21.6154)
		(stroke
			(width 0.0635)
			(type default)
		)
		(layer "In2.Cu")
	)
	(gr_line
		(start 81.642966 -22.64791)
		(end 81.682336 -22.870922)
		(stroke
			(width 0.0635)
			(type default)
		)
		(layer "In2.Cu")
	)
	(gr_line
		(start 81.645252 -3.283204)
		(end 81.645252 -3.283458)
		(stroke
			(width 0.0635)
			(type default)
		)
		(layer "In2.Cu")
	)
	(gr_line
		(start 81.645252 -3.283204)
		(end 81.676494 -3.277616)
		(stroke
			(width 0.0635)
			(type default)
		)
		(layer "In2.Cu")
	)
	(gr_line
		(start 81.695544 -0.358648)
		(end 81.722722 -0.353822)
		(stroke
			(width 0.0635)
			(type default)
		)
		(layer "In2.Cu")
	)
	(gr_line
		(start 81.722722 -0.353822)
		(end 81.745328 -0.338074)
		(stroke
			(width 0.0635)
			(type default)
		)
		(layer "In2.Cu")
	)
	(gr_line
		(start 81.772252 3.744976)
		(end 81.787746 3.766566)
		(stroke
			(width 0.0635)
			(type default)
		)
		(layer "In2.Cu")
	)
	(gr_line
		(start 81.787746 3.766566)
		(end 81.792572 3.793744)
		(stroke
			(width 0.0635)
			(type default)
		)
		(layer "In2.Cu")
	)
	(gr_line
		(start 81.864454 -22.331934)
		(end 82.087466 -22.292564)
		(stroke
			(width 0.0635)
			(type default)
		)
		(layer "In2.Cu")
	)
	(gr_line
		(start 82.042 -1.302766)
		(end 82.069178 -1.29794)
		(stroke
			(width 0.0635)
			(type default)
		)
		(layer "In2.Cu")
	)
	(gr_line
		(start 82.069178 -1.29794)
		(end 82.091784 -1.282192)
		(stroke
			(width 0.0635)
			(type default)
		)
		(layer "In2.Cu")
	)
	(gr_line
		(start 82.079592 -27.570176)
		(end 82.457798 -28.325826)
		(stroke
			(width 0.0635)
			(type default)
		)
		(layer "In2.Cu")
	)
	(gr_line
		(start 82.087466 -22.292564)
		(end 82.305906 -21.980398)
		(stroke
			(width 0.0635)
			(type default)
		)
		(layer "In2.Cu")
	)
	(gr_line
		(start 82.148172 2.491994)
		(end 82.159348 2.499868)
		(stroke
			(width 0.0635)
			(type default)
		)
		(layer "In2.Cu")
	)
	(gr_line
		(start 82.159348 2.499868)
		(end 82.167222 2.511044)
		(stroke
			(width 0.0635)
			(type default)
		)
		(layer "In2.Cu")
	)
	(gr_line
		(start 82.266536 -21.757386)
		(end 82.305906 -21.980398)
		(stroke
			(width 0.0635)
			(type default)
		)
		(layer "In2.Cu")
	)
	(gr_line
		(start 82.275934 -3.469386)
		(end 82.304636 -3.464306)
		(stroke
			(width 0.0635)
			(type default)
		)
		(layer "In2.Cu")
	)
	(gr_line
		(start 82.291682 -24.693626)
		(end 82.307176 -24.68118)
		(stroke
			(width 0.0635)
			(type default)
		)
		(layer "In2.Cu")
	)
	(gr_line
		(start 82.304636 -3.464306)
		(end 82.328004 -3.447796)
		(stroke
			(width 0.0635)
			(type default)
		)
		(layer "In2.Cu")
	)
	(gr_line
		(start 82.307176 -24.68118)
		(end 82.31378 -24.671782)
		(stroke
			(width 0.0635)
			(type default)
		)
		(layer "In2.Cu")
	)
	(gr_line
		(start 82.347308 -2.256028)
		(end 82.374486 -2.251202)
		(stroke
			(width 0.0635)
			(type default)
		)
		(layer "In2.Cu")
	)
	(gr_line
		(start 82.374486 -2.251202)
		(end 82.397092 -2.235454)
		(stroke
			(width 0.0635)
			(type default)
		)
		(layer "In2.Cu")
	)
	(gr_arc
		(start 82.457798 -28.325826)
		(mid 82.531283 -28.389407)
		(end 82.628232 -28.382468)
		(stroke
			(width 0.0635)
			(type default)
		)
		(layer "In2.Cu")
	)
	(gr_line
		(start 82.628232 -28.382468)
		(end 82.628486 -28.382468)
		(stroke
			(width 0.0635)
			(type default)
		)
		(layer "In2.Cu")
	)
	(gr_line
		(start 82.702146 -28.814522)
		(end 83.080352 -29.570426)
		(stroke
			(width 0.0635)
			(type default)
		)
		(layer "In2.Cu")
	)
	(gr_arc
		(start 82.758788 -28.644088)
		(mid 82.695194 -28.717573)
		(end 82.702146 -28.814522)
		(stroke
			(width 0.0635)
			(type default)
		)
		(layer "In2.Cu")
	)
	(gr_line
		(start 82.758788 -28.644088)
		(end 82.759042 -28.644088)
		(stroke
			(width 0.0635)
			(type default)
		)
		(layer "In2.Cu")
	)
	(gr_line
		(start 82.84845 1.75133)
		(end 82.859626 1.759204)
		(stroke
			(width 0.0635)
			(type default)
		)
		(layer "In2.Cu")
	)
	(gr_line
		(start 82.859626 1.759204)
		(end 82.8675 1.77038)
		(stroke
			(width 0.0635)
			(type default)
		)
		(layer "In2.Cu")
	)
	(gr_arc
		(start 82.865214 7.250938)
		(mid 82.758059 7.545325)
		(end 82.486754 7.702042)
		(stroke
			(width 0.0635)
			(type default)
		)
		(layer "In2.Cu")
	)
	(gr_line
		(start 83.005422 -6.716776)
		(end 83.010248 -6.689598)
		(stroke
			(width 0.0635)
			(type default)
		)
		(layer "In2.Cu")
	)
	(gr_line
		(start 83.010248 -6.689598)
		(end 83.025996 -6.666992)
		(stroke
			(width 0.0635)
			(type default)
		)
		(layer "In2.Cu")
	)
	(gr_line
		(start 83.023456 -25.894792)
		(end 83.028282 -25.867614)
		(stroke
			(width 0.0635)
			(type default)
		)
		(layer "In2.Cu")
	)
	(gr_line
		(start 83.028282 -25.867614)
		(end 83.04403 -25.845008)
		(stroke
			(width 0.0635)
			(type default)
		)
		(layer "In2.Cu")
	)
	(gr_line
		(start 83.029298 3.742182)
		(end 83.045046 3.764788)
		(stroke
			(width 0.0635)
			(type default)
		)
		(layer "In2.Cu")
	)
	(gr_line
		(start 83.045046 3.764788)
		(end 83.049872 3.791966)
		(stroke
			(width 0.0635)
			(type default)
		)
		(layer "In2.Cu")
	)
	(gr_line
		(start 83.077304 -15.089886)
		(end 83.093052 -15.06728)
		(stroke
			(width 0.0635)
			(type default)
		)
		(layer "In2.Cu")
	)
	(gr_line
		(start 83.093052 -15.06728)
		(end 83.097878 -15.040102)
		(stroke
			(width 0.0635)
			(type default)
		)
		(layer "In2.Cu")
	)
	(gr_line
		(start 83.21294 -25.320752)
		(end 83.25231 -25.543764)
		(stroke
			(width 0.0635)
			(type default)
		)
		(layer "In2.Cu")
	)
	(gr_line
		(start 83.21294 -25.320752)
		(end 83.43138 -25.008586)
		(stroke
			(width 0.0635)
			(type default)
		)
		(layer "In2.Cu")
	)
	(gr_line
		(start 83.43138 -25.008586)
		(end 83.654392 -24.969216)
		(stroke
			(width 0.0635)
			(type default)
		)
		(layer "In2.Cu")
	)
	(gr_arc
		(start 83.502754 7.702042)
		(mid 83.25723 7.526718)
		(end 83.157314 7.242048)
		(stroke
			(width 0.0635)
			(type default)
		)
		(layer "In2.Cu")
	)
	(gr_line
		(start 83.514184 -25.68321)
		(end 83.875626 -25.167082)
		(stroke
			(width 0.0635)
			(type default)
		)
		(layer "In2.Cu")
	)
	(gr_line
		(start 83.646518 -5.78104)
		(end 83.654392 -5.769864)
		(stroke
			(width 0.0635)
			(type default)
		)
		(layer "In2.Cu")
	)
	(gr_line
		(start 83.654392 -5.769864)
		(end 83.665568 -5.76199)
		(stroke
			(width 0.0635)
			(type default)
		)
		(layer "In2.Cu")
	)
	(gr_line
		(start 83.662774 1.00457)
		(end 83.67395 1.012444)
		(stroke
			(width 0.0635)
			(type default)
		)
		(layer "In2.Cu")
	)
	(gr_line
		(start 83.67395 1.012444)
		(end 83.681824 1.02362)
		(stroke
			(width 0.0635)
			(type default)
		)
		(layer "In2.Cu")
	)
	(gr_line
		(start 83.727036 -30.20822)
		(end 83.72729 -30.20822)
		(stroke
			(width 0.0635)
			(type default)
		)
		(layer "In2.Cu")
	)
	(gr_line
		(start 83.836256 -24.430228)
		(end 83.87588 -24.65324)
		(stroke
			(width 0.0635)
			(type default)
		)
		(layer "In2.Cu")
	)
	(gr_line
		(start 83.836256 -24.430228)
		(end 84.05495 -24.118062)
		(stroke
			(width 0.0635)
			(type default)
		)
		(layer "In2.Cu")
	)
	(gr_line
		(start 84.05495 -24.118062)
		(end 84.277962 -24.078692)
		(stroke
			(width 0.0635)
			(type default)
		)
		(layer "In2.Cu")
	)
	(gr_line
		(start 84.079842 -34.070036)
		(end 84.457286 -33.314132)
		(stroke
			(width 0.0635)
			(type default)
		)
		(layer "In2.Cu")
	)
	(gr_line
		(start 84.138008 -24.792178)
		(end 84.497926 -24.277828)
		(stroke
			(width 0.0635)
			(type default)
		)
		(layer "In2.Cu")
	)
	(gr_line
		(start 84.182966 4.444238)
		(end 84.186522 4.46405)
		(stroke
			(width 0.0635)
			(type default)
		)
		(layer "In2.Cu")
	)
	(gr_line
		(start 84.186522 4.46405)
		(end 84.191094 4.703572)
		(stroke
			(width 0.0635)
			(type default)
		)
		(layer "In2.Cu")
	)
	(gr_arc
		(start 84.191348 4.714748)
		(mid 84.088206 5.012575)
		(end 83.812888 5.165852)
		(stroke
			(width 0.0635)
			(type default)
		)
		(layer "In2.Cu")
	)
	(gr_line
		(start 84.353146 0.301498)
		(end 84.364322 0.309372)
		(stroke
			(width 0.0635)
			(type default)
		)
		(layer "In2.Cu")
	)
	(gr_line
		(start 84.364322 0.309372)
		(end 84.372196 0.320548)
		(stroke
			(width 0.0635)
			(type default)
		)
		(layer "In2.Cu")
	)
	(gr_line
		(start 84.376514 3.92557)
		(end 84.392262 3.948176)
		(stroke
			(width 0.0635)
			(type default)
		)
		(layer "In2.Cu")
	)
	(gr_line
		(start 84.392262 3.948176)
		(end 84.397088 3.975354)
		(stroke
			(width 0.0635)
			(type default)
		)
		(layer "In2.Cu")
	)
	(gr_arc
		(start 84.457286 -33.314132)
		(mid 84.464073 -33.21726)
		(end 84.40039 -33.143952)
		(stroke
			(width 0.0635)
			(type default)
		)
		(layer "In2.Cu")
	)
	(gr_line
		(start 84.474304 4.414012)
		(end 84.483194 4.696206)
		(stroke
			(width 0.0635)
			(type default)
		)
		(layer "In2.Cu")
	)
	(gr_arc
		(start 84.531454 -32.882586)
		(mid 84.62851 -32.889527)
		(end 84.701888 -32.82569)
		(stroke
			(width 0.0635)
			(type default)
		)
		(layer "In2.Cu")
	)
	(gr_line
		(start 84.701888 -32.82569)
		(end 85.079332 -32.069786)
		(stroke
			(width 0.0635)
			(type default)
		)
		(layer "In2.Cu")
	)
	(gr_arc
		(start 84.828888 5.165852)
		(mid 84.583364 4.990528)
		(end 84.483448 4.705858)
		(stroke
			(width 0.0635)
			(type default)
		)
		(layer "In2.Cu")
	)
	(gr_line
		(start 84.989162 -6.464046)
		(end 84.993988 -6.436868)
		(stroke
			(width 0.0635)
			(type default)
		)
		(layer "In2.Cu")
	)
	(gr_line
		(start 84.993988 -6.436868)
		(end 85.009482 -6.415278)
		(stroke
			(width 0.0635)
			(type default)
		)
		(layer "In2.Cu")
	)
	(gr_line
		(start 85.09381 -14.565122)
		(end 85.104224 -14.548612)
		(stroke
			(width 0.0635)
			(type default)
		)
		(layer "In2.Cu")
	)
	(gr_line
		(start 85.104224 -14.548612)
		(end 85.10778 -14.529562)
		(stroke
			(width 0.0635)
			(type default)
		)
		(layer "In2.Cu")
	)
	(gr_line
		(start 85.244432 -25.654508)
		(end 85.406484 -25.42286)
		(stroke
			(width 0.0635)
			(type default)
		)
		(layer "In2.Cu")
	)
	(gr_line
		(start 85.412834 6.001004)
		(end 85.45322 5.674614)
		(stroke
			(width 0.0635)
			(type default)
		)
		(layer "In2.Cu")
	)
	(gr_line
		(start 85.426042 -25.395174)
		(end 85.786722 -24.880062)
		(stroke
			(width 0.0635)
			(type default)
		)
		(layer "In2.Cu")
	)
	(gr_arc
		(start 85.456014 7.250938)
		(mid 85.352745 7.548601)
		(end 85.077554 7.702042)
		(stroke
			(width 0.0635)
			(type default)
		)
		(layer "In2.Cu")
	)
	(gr_line
		(start 85.472016 4.575556)
		(end 85.474048 4.58724)
		(stroke
			(width 0.0635)
			(type default)
		)
		(layer "In2.Cu")
	)
	(gr_line
		(start 85.474048 4.599686)
		(end 85.474048 4.58724)
		(stroke
			(width 0.0635)
			(type default)
		)
		(layer "In2.Cu")
	)
	(gr_line
		(start 85.517736 -5.688584)
		(end 85.52561 -5.677408)
		(stroke
			(width 0.0635)
			(type default)
		)
		(layer "In2.Cu")
	)
	(gr_line
		(start 85.52561 -5.677408)
		(end 85.536786 -5.669534)
		(stroke
			(width 0.0635)
			(type default)
		)
		(layer "In2.Cu")
	)
	(gr_line
		(start 85.526372 -25.761188)
		(end 85.642958 -25.594564)
		(stroke
			(width 0.0635)
			(type default)
		)
		(layer "In2.Cu")
	)
	(gr_line
		(start 85.61832 3.788918)
		(end 85.634068 3.811524)
		(stroke
			(width 0.0635)
			(type default)
		)
		(layer "In2.Cu")
	)
	(gr_line
		(start 85.634068 3.811524)
		(end 85.638894 3.838702)
		(stroke
			(width 0.0635)
			(type default)
		)
		(layer "In2.Cu")
	)
	(gr_line
		(start 85.646514 -25.593802)
		(end 85.869526 -25.554686)
		(stroke
			(width 0.0635)
			(type default)
		)
		(layer "In2.Cu")
	)
	(gr_line
		(start 85.703918 6.026404)
		(end 85.743034 5.710428)
		(stroke
			(width 0.0635)
			(type default)
		)
		(layer "In2.Cu")
	)
	(gr_line
		(start 85.703918 6.027166)
		(end 85.703918 6.026404)
		(stroke
			(width 0.0635)
			(type default)
		)
		(layer "In2.Cu")
	)
	(gr_line
		(start 85.766148 4.58724)
		(end 85.76183 4.536694)
		(stroke
			(width 0.0635)
			(type default)
		)
		(layer "In2.Cu")
	)
	(gr_line
		(start 85.869526 -25.554686)
		(end 86.087966 -25.24252)
		(stroke
			(width 0.0635)
			(type default)
		)
		(layer "In2.Cu")
	)
	(gr_line
		(start 86.024974 -24.539702)
		(end 86.029546 -24.533098)
		(stroke
			(width 0.0635)
			(type default)
		)
		(layer "In2.Cu")
	)
	(gr_line
		(start 86.048596 -25.019508)
		(end 86.087966 -25.24252)
		(stroke
			(width 0.0635)
			(type default)
		)
		(layer "In2.Cu")
	)
	(gr_line
		(start 86.049358 -24.504904)
		(end 86.410546 -23.98903)
		(stroke
			(width 0.0635)
			(type default)
		)
		(layer "In2.Cu")
	)
	(gr_line
		(start 86.080092 -27.570176)
		(end 86.458298 -28.325826)
		(stroke
			(width 0.0635)
			(type default)
		)
		(layer "In2.Cu")
	)
	(gr_arc
		(start 86.093554 7.702042)
		(mid 85.84803 7.526718)
		(end 85.748114 7.242048)
		(stroke
			(width 0.0635)
			(type default)
		)
		(layer "In2.Cu")
	)
	(gr_line
		(start 86.21141 -24.78278)
		(end 86.266528 -24.70404)
		(stroke
			(width 0.0635)
			(type default)
		)
		(layer "In2.Cu")
	)
	(gr_line
		(start 86.270084 -24.703532)
		(end 86.493096 -24.664162)
		(stroke
			(width 0.0635)
			(type default)
		)
		(layer "In2.Cu")
	)
	(gr_line
		(start 86.293706 0.493268)
		(end 86.319614 0.511302)
		(stroke
			(width 0.0635)
			(type default)
		)
		(layer "In2.Cu")
	)
	(gr_line
		(start 86.319614 0.511302)
		(end 86.334346 0.539242)
		(stroke
			(width 0.0635)
			(type default)
		)
		(layer "In2.Cu")
	)
	(gr_arc
		(start 86.458298 -28.325826)
		(mid 86.531784 -28.389445)
		(end 86.628732 -28.382468)
		(stroke
			(width 0.0635)
			(type default)
		)
		(layer "In2.Cu")
	)
	(gr_line
		(start 86.493096 -24.664162)
		(end 86.711536 -24.351996)
		(stroke
			(width 0.0635)
			(type default)
		)
		(layer "In2.Cu")
	)
	(gr_line
		(start 86.628732 -28.382468)
		(end 86.628986 -28.382468)
		(stroke
			(width 0.0635)
			(type default)
		)
		(layer "In2.Cu")
	)
	(gr_line
		(start 86.672166 -24.128984)
		(end 86.711536 -24.351996)
		(stroke
			(width 0.0635)
			(type default)
		)
		(layer "In2.Cu")
	)
	(gr_line
		(start 86.702646 -28.814522)
		(end 87.079582 -29.570426)
		(stroke
			(width 0.0635)
			(type default)
		)
		(layer "In2.Cu")
	)
	(gr_arc
		(start 86.759288 -28.644088)
		(mid 86.695669 -28.717574)
		(end 86.702646 -28.814522)
		(stroke
			(width 0.0635)
			(type default)
		)
		(layer "In2.Cu")
	)
	(gr_line
		(start 86.759288 -28.644088)
		(end 86.759542 -28.644088)
		(stroke
			(width 0.0635)
			(type default)
		)
		(layer "In2.Cu")
	)
	(gr_line
		(start 86.99627 -6.352794)
		(end 87.001096 -6.325616)
		(stroke
			(width 0.0635)
			(type default)
		)
		(layer "In2.Cu")
	)
	(gr_line
		(start 87.001096 -6.325616)
		(end 87.01659 -6.304026)
		(stroke
			(width 0.0635)
			(type default)
		)
		(layer "In2.Cu")
	)
	(gr_line
		(start 87.126826 -14.81201)
		(end 87.142574 -14.789404)
		(stroke
			(width 0.0635)
			(type default)
		)
		(layer "In2.Cu")
	)
	(gr_line
		(start 87.142574 -14.789404)
		(end 87.1474 -14.762226)
		(stroke
			(width 0.0635)
			(type default)
		)
		(layer "In2.Cu")
	)
	(gr_line
		(start 87.158068 -26.313384)
		(end 87.16264 -26.289254)
		(stroke
			(width 0.0635)
			(type default)
		)
		(layer "In2.Cu")
	)
	(gr_line
		(start 87.16264 -26.289254)
		(end 87.177372 -26.268172)
		(stroke
			(width 0.0635)
			(type default)
		)
		(layer "In2.Cu")
	)
	(gr_line
		(start 87.341202 -25.750774)
		(end 87.380572 -25.974294)
		(stroke
			(width 0.0635)
			(type default)
		)
		(layer "In2.Cu")
	)
	(gr_line
		(start 87.341202 -25.750774)
		(end 87.559896 -25.438608)
		(stroke
			(width 0.0635)
			(type default)
		)
		(layer "In2.Cu")
	)
	(gr_arc
		(start 87.419688 5.165852)
		(mid 87.174193 4.990517)
		(end 87.074248 4.705858)
		(stroke
			(width 0.0635)
			(type default)
		)
		(layer "In2.Cu")
	)
	(gr_line
		(start 87.557356 0.21336)
		(end 87.581994 0.230632)
		(stroke
			(width 0.0635)
			(type default)
		)
		(layer "In2.Cu")
	)
	(gr_line
		(start 87.559896 -25.438608)
		(end 87.783162 -25.399238)
		(stroke
			(width 0.0635)
			(type default)
		)
		(layer "In2.Cu")
	)
	(gr_line
		(start 87.578946 -5.500116)
		(end 87.58682 -5.48894)
		(stroke
			(width 0.0635)
			(type default)
		)
		(layer "In2.Cu")
	)
	(gr_line
		(start 87.581994 0.230632)
		(end 87.595964 0.25654)
		(stroke
			(width 0.0635)
			(type default)
		)
		(layer "In2.Cu")
	)
	(gr_line
		(start 87.58682 -5.48894)
		(end 87.597996 -5.481066)
		(stroke
			(width 0.0635)
			(type default)
		)
		(layer "In2.Cu")
	)
	(gr_line
		(start 87.640668 -26.11628)
		(end 88.004396 -25.59685)
		(stroke
			(width 0.0635)
			(type default)
		)
		(layer "In2.Cu")
	)
	(gr_line
		(start 87.727536 -30.20822)
		(end 87.72779 -30.20822)
		(stroke
			(width 0.0635)
			(type default)
		)
		(layer "In2.Cu")
	)
	(gr_line
		(start 87.964772 -24.86025)
		(end 88.004142 -25.083516)
		(stroke
			(width 0.0635)
			(type default)
		)
		(layer "In2.Cu")
	)
	(gr_line
		(start 87.964772 -24.86025)
		(end 88.183212 -24.548084)
		(stroke
			(width 0.0635)
			(type default)
		)
		(layer "In2.Cu")
	)
	(gr_arc
		(start 88.046814 7.250938)
		(mid 87.943672 7.548765)
		(end 87.668354 7.702042)
		(stroke
			(width 0.0635)
			(type default)
		)
		(layer "In2.Cu")
	)
	(gr_line
		(start 88.080342 -34.070036)
		(end 88.457786 -33.314132)
		(stroke
			(width 0.0635)
			(type default)
		)
		(layer "In2.Cu")
	)
	(gr_line
		(start 88.183212 -24.548084)
		(end 88.406732 -24.508714)
		(stroke
			(width 0.0635)
			(type default)
		)
		(layer "In2.Cu")
	)
	(gr_line
		(start 88.234266 -0.509016)
		(end 88.247728 -0.499618)
		(stroke
			(width 0.0635)
			(type default)
		)
		(layer "In2.Cu")
	)
	(gr_line
		(start 88.247728 -0.499618)
		(end 88.257126 -0.486156)
		(stroke
			(width 0.0635)
			(type default)
		)
		(layer "In2.Cu")
	)
	(gr_line
		(start 88.264492 -25.225756)
		(end 88.629236 -24.704802)
		(stroke
			(width 0.0635)
			(type default)
		)
		(layer "In2.Cu")
	)
	(gr_arc
		(start 88.457786 -33.314132)
		(mid 88.464573 -33.21726)
		(end 88.40089 -33.143952)
		(stroke
			(width 0.0635)
			(type default)
		)
		(layer "In2.Cu")
	)
	(gr_arc
		(start 88.531954 -32.882586)
		(mid 88.62901 -32.889527)
		(end 88.702388 -32.82569)
		(stroke
			(width 0.0635)
			(type default)
		)
		(layer "In2.Cu")
	)
	(gr_arc
		(start 88.684354 7.702042)
		(mid 88.447078 7.415507)
		(end 88.362028 7.053326)
		(stroke
			(width 0.0635)
			(type default)
		)
		(layer "In2.Cu")
	)
	(gr_line
		(start 88.702388 -32.82569)
		(end 89.079832 -32.069786)
		(stroke
			(width 0.0635)
			(type default)
		)
		(layer "In2.Cu")
	)
	(gr_line
		(start 89.028016 -6.247384)
		(end 89.032842 -6.220206)
		(stroke
			(width 0.0635)
			(type default)
		)
		(layer "In2.Cu")
	)
	(gr_line
		(start 89.032842 -6.220206)
		(end 89.048336 -6.198616)
		(stroke
			(width 0.0635)
			(type default)
		)
		(layer "In2.Cu")
	)
	(gr_line
		(start 89.095326 -14.993366)
		(end 89.111074 -14.97076)
		(stroke
			(width 0.0635)
			(type default)
		)
		(layer "In2.Cu")
	)
	(gr_line
		(start 89.106756 -1.133856)
		(end 89.117932 -1.125982)
		(stroke
			(width 0.0635)
			(type default)
		)
		(layer "In2.Cu")
	)
	(gr_line
		(start 89.111074 -14.97076)
		(end 89.1159 -14.943582)
		(stroke
			(width 0.0635)
			(type default)
		)
		(layer "In2.Cu")
	)
	(gr_line
		(start 89.117932 -1.125982)
		(end 89.125806 -1.114806)
		(stroke
			(width 0.0635)
			(type default)
		)
		(layer "In2.Cu")
	)
	(gr_line
		(start 89.287604 -25.593802)
		(end 89.407492 -25.422352)
		(stroke
			(width 0.0635)
			(type default)
		)
		(layer "In2.Cu")
	)
	(gr_arc
		(start 89.372948 4.714748)
		(mid 89.269678 5.012415)
		(end 88.994488 5.165852)
		(stroke
			(width 0.0635)
			(type default)
		)
		(layer "In2.Cu")
	)
	(gr_line
		(start 89.426542 -25.395174)
		(end 89.787476 -24.879554)
		(stroke
			(width 0.0635)
			(type default)
		)
		(layer "In2.Cu")
	)
	(gr_line
		(start 89.526872 -25.761188)
		(end 89.643458 -25.594564)
		(stroke
			(width 0.0635)
			(type default)
		)
		(layer "In2.Cu")
	)
	(gr_line
		(start 89.551764 -5.47878)
		(end 89.559638 -5.467604)
		(stroke
			(width 0.0635)
			(type default)
		)
		(layer "In2.Cu")
	)
	(gr_line
		(start 89.559638 -5.467604)
		(end 89.570814 -5.45973)
		(stroke
			(width 0.0635)
			(type default)
		)
		(layer "In2.Cu")
	)
	(gr_line
		(start 89.647014 -25.593802)
		(end 89.870026 -25.554686)
		(stroke
			(width 0.0635)
			(type default)
		)
		(layer "In2.Cu")
	)
	(gr_line
		(start 89.870026 -25.554686)
		(end 90.088466 -25.24252)
		(stroke
			(width 0.0635)
			(type default)
		)
		(layer "In2.Cu")
	)
	(gr_line
		(start 89.900506 -1.7526)
		(end 89.911682 -1.744726)
		(stroke
			(width 0.0635)
			(type default)
		)
		(layer "In2.Cu")
	)
	(gr_line
		(start 89.911682 -1.744726)
		(end 89.919556 -1.73355)
		(stroke
			(width 0.0635)
			(type default)
		)
		(layer "In2.Cu")
	)
	(gr_arc
		(start 90.010488 5.165852)
		(mid 89.764964 4.990528)
		(end 89.665048 4.705858)
		(stroke
			(width 0.0635)
			(type default)
		)
		(layer "In2.Cu")
	)
	(gr_line
		(start 90.021918 -24.544782)
		(end 90.028522 -24.535384)
		(stroke
			(width 0.0635)
			(type default)
		)
		(layer "In2.Cu")
	)
	(gr_line
		(start 90.049096 -25.019508)
		(end 90.088466 -25.24252)
		(stroke
			(width 0.0635)
			(type default)
		)
		(layer "In2.Cu")
	)
	(gr_line
		(start 90.05062 -24.504142)
		(end 90.410538 -23.990046)
		(stroke
			(width 0.0635)
			(type default)
		)
		(layer "In2.Cu")
	)
	(gr_line
		(start 90.079322 -27.570176)
		(end 90.457528 -28.325826)
		(stroke
			(width 0.0635)
			(type default)
		)
		(layer "In2.Cu")
	)
	(gr_line
		(start 90.21191 -24.78278)
		(end 90.267028 -24.70404)
		(stroke
			(width 0.0635)
			(type default)
		)
		(layer "In2.Cu")
	)
	(gr_line
		(start 90.270584 -24.703532)
		(end 90.493596 -24.664162)
		(stroke
			(width 0.0635)
			(type default)
		)
		(layer "In2.Cu")
	)
	(gr_arc
		(start 90.457528 -28.325826)
		(mid 90.531019 -28.389452)
		(end 90.627962 -28.382468)
		(stroke
			(width 0.0635)
			(type default)
		)
		(layer "In2.Cu")
	)
	(gr_line
		(start 90.493596 -24.664162)
		(end 90.712036 -24.351996)
		(stroke
			(width 0.0635)
			(type default)
		)
		(layer "In2.Cu")
	)
	(gr_line
		(start 90.627962 -28.382468)
		(end 90.628216 -28.382468)
		(stroke
			(width 0.0635)
			(type default)
		)
		(layer "In2.Cu")
	)
	(gr_arc
		(start 90.637614 7.250938)
		(mid 90.534345 7.548601)
		(end 90.259154 7.702042)
		(stroke
			(width 0.0635)
			(type default)
		)
		(layer "In2.Cu")
	)
	(gr_line
		(start 90.654886 2.938018)
		(end 90.670634 2.960624)
		(stroke
			(width 0.0635)
			(type default)
		)
		(layer "In2.Cu")
	)
	(gr_line
		(start 90.670634 2.960624)
		(end 90.67546 2.987802)
		(stroke
			(width 0.0635)
			(type default)
		)
		(layer "In2.Cu")
	)
	(gr_line
		(start 90.672666 -24.128984)
		(end 90.712036 -24.351996)
		(stroke
			(width 0.0635)
			(type default)
		)
		(layer "In2.Cu")
	)
	(gr_line
		(start 90.674444 -23.613364)
		(end 91.033854 -23.100284)
		(stroke
			(width 0.0635)
			(type default)
		)
		(layer "In2.Cu")
	)
	(gr_line
		(start 90.701876 -28.814522)
		(end 91.080082 -29.570426)
		(stroke
			(width 0.0635)
			(type default)
		)
		(layer "In2.Cu")
	)
	(gr_arc
		(start 90.758518 -28.644088)
		(mid 90.694899 -28.717574)
		(end 90.701876 -28.814522)
		(stroke
			(width 0.0635)
			(type default)
		)
		(layer "In2.Cu")
	)
	(gr_line
		(start 90.758518 -28.644088)
		(end 90.758772 -28.644088)
		(stroke
			(width 0.0635)
			(type default)
		)
		(layer "In2.Cu")
	)
	(gr_line
		(start 90.894154 -23.813008)
		(end 91.117166 -23.773638)
		(stroke
			(width 0.0635)
			(type default)
		)
		(layer "In2.Cu")
	)
	(gr_line
		(start 90.930476 -2.24917)
		(end 90.941652 -2.241296)
		(stroke
			(width 0.0635)
			(type default)
		)
		(layer "In2.Cu")
	)
	(gr_line
		(start 90.930984 5.5626)
		(end 90.930984 5.562346)
		(stroke
			(width 0.0635)
			(type default)
		)
		(layer "In2.Cu")
	)
	(gr_arc
		(start 90.930984 6.210554)
		(mid 90.932699 6.227279)
		(end 90.93327 6.244082)
		(stroke
			(width 0.0635)
			(type default)
		)
		(layer "In2.Cu")
	)
	(gr_line
		(start 90.941652 -2.241296)
		(end 90.949526 -2.23012)
		(stroke
			(width 0.0635)
			(type default)
		)
		(layer "In2.Cu")
	)
	(gr_line
		(start 91.021154 -26.998422)
		(end 91.021662 -26.997406)
		(stroke
			(width 0.0635)
			(type default)
		)
		(layer "In2.Cu")
	)
	(gr_line
		(start 91.021916 -26.997406)
		(end 91.022424 -26.99639)
		(stroke
			(width 0.0635)
			(type default)
		)
		(layer "In2.Cu")
	)
	(gr_line
		(start 91.070938 -5.997702)
		(end 91.080336 -5.944362)
		(stroke
			(width 0.0635)
			(type default)
		)
		(layer "In2.Cu")
	)
	(gr_line
		(start 91.117166 -23.773638)
		(end 91.335606 -23.461472)
		(stroke
			(width 0.0635)
			(type default)
		)
		(layer "In2.Cu")
	)
	(gr_line
		(start 91.126056 -14.812264)
		(end 91.141804 -14.789658)
		(stroke
			(width 0.0635)
			(type default)
		)
		(layer "In2.Cu")
	)
	(gr_line
		(start 91.13266 -26.297128)
		(end 91.215718 -26.507948)
		(stroke
			(width 0.0635)
			(type default)
		)
		(layer "In2.Cu")
	)
	(gr_line
		(start 91.13266 -26.297128)
		(end 91.284298 -25.947624)
		(stroke
			(width 0.0635)
			(type default)
		)
		(layer "In2.Cu")
	)
	(gr_line
		(start 91.141804 -14.789658)
		(end 91.14663 -14.76248)
		(stroke
			(width 0.0635)
			(type default)
		)
		(layer "In2.Cu")
	)
	(gr_arc
		(start 91.275154 7.702042)
		(mid 91.02963 7.526718)
		(end 90.929714 7.242048)
		(stroke
			(width 0.0635)
			(type default)
		)
		(layer "In2.Cu")
	)
	(gr_line
		(start 91.284298 -25.947624)
		(end 91.495118 -25.864566)
		(stroke
			(width 0.0635)
			(type default)
		)
		(layer "In2.Cu")
	)
	(gr_line
		(start 91.296236 -23.23846)
		(end 91.335606 -23.461472)
		(stroke
			(width 0.0635)
			(type default)
		)
		(layer "In2.Cu")
	)
	(gr_line
		(start 91.300808 -27.085036)
		(end 91.301316 -27.08402)
		(stroke
			(width 0.0635)
			(type default)
		)
		(layer "In2.Cu")
	)
	(gr_line
		(start 91.30157 -27.08656)
		(end 91.302078 -27.085544)
		(stroke
			(width 0.0635)
			(type default)
		)
		(layer "In2.Cu")
	)
	(gr_line
		(start 91.500198 -26.592022)
		(end 91.750642 -26.015188)
		(stroke
			(width 0.0635)
			(type default)
		)
		(layer "In2.Cu")
	)
	(gr_line
		(start 91.565476 -25.299924)
		(end 91.648788 -25.51049)
		(stroke
			(width 0.0635)
			(type default)
		)
		(layer "In2.Cu")
	)
	(gr_line
		(start 91.565476 -25.299924)
		(end 91.717368 -24.95042)
		(stroke
			(width 0.0635)
			(type default)
		)
		(layer "In2.Cu")
	)
	(gr_line
		(start 91.63685 -3.0099)
		(end 91.648026 -3.002026)
		(stroke
			(width 0.0635)
			(type default)
		)
		(layer "In2.Cu")
	)
	(gr_line
		(start 91.638374 -25.54097)
		(end 91.650058 -25.513792)
		(stroke
			(width 0.0635)
			(type default)
		)
		(layer "In2.Cu")
	)
	(gr_line
		(start 91.648026 -3.002026)
		(end 91.6559 -2.99085)
		(stroke
			(width 0.0635)
			(type default)
		)
		(layer "In2.Cu")
	)
	(gr_line
		(start 91.717368 -24.95042)
		(end 91.927934 -24.867362)
		(stroke
			(width 0.0635)
			(type default)
		)
		(layer "In2.Cu")
	)
	(gr_line
		(start 91.726766 -30.20822)
		(end 91.72702 -30.20822)
		(stroke
			(width 0.0635)
			(type default)
		)
		(layer "In2.Cu")
	)
	(gr_line
		(start 91.90609 -25.657302)
		(end 91.92006 -25.625298)
		(stroke
			(width 0.0635)
			(type default)
		)
		(layer "In2.Cu")
	)
	(gr_line
		(start 91.931236 -24.866092)
		(end 92.002864 -24.700738)
		(stroke
			(width 0.0635)
			(type default)
		)
		(layer "In2.Cu")
	)
	(gr_line
		(start 91.933522 -25.59431)
		(end 92.183712 -25.017984)
		(stroke
			(width 0.0635)
			(type default)
		)
		(layer "In2.Cu")
	)
	(gr_arc
		(start 91.947238 4.751324)
		(mid 91.844015 5.026477)
		(end 91.585288 5.165852)
		(stroke
			(width 0.0635)
			(type default)
		)
		(layer "In2.Cu")
	)
	(gr_line
		(start 91.992196 -4.12115)
		(end 92.003372 -4.113276)
		(stroke
			(width 0.0635)
			(type default)
		)
		(layer "In2.Cu")
	)
	(gr_line
		(start 92.003372 -4.113276)
		(end 92.011246 -4.1021)
		(stroke
			(width 0.0635)
			(type default)
		)
		(layer "In2.Cu")
	)
	(gr_line
		(start 92.033852 3.039618)
		(end 92.049346 3.061208)
		(stroke
			(width 0.0635)
			(type default)
		)
		(layer "In2.Cu")
	)
	(gr_line
		(start 92.049346 3.061208)
		(end 92.054172 3.088386)
		(stroke
			(width 0.0635)
			(type default)
		)
		(layer "In2.Cu")
	)
	(gr_line
		(start 92.079572 -34.070036)
		(end 92.457016 -33.314132)
		(stroke
			(width 0.0635)
			(type default)
		)
		(layer "In2.Cu")
	)
	(gr_line
		(start 92.19692 -24.987504)
		(end 92.577158 -24.111712)
		(stroke
			(width 0.0635)
			(type default)
		)
		(layer "In2.Cu")
	)
	(gr_arc
		(start 92.457016 -33.314132)
		(mid 92.463809 -33.217265)
		(end 92.40012 -33.143952)
		(stroke
			(width 0.0635)
			(type default)
		)
		(layer "In2.Cu")
	)
	(gr_arc
		(start 92.531184 -32.882586)
		(mid 92.62824 -32.889527)
		(end 92.701618 -32.82569)
		(stroke
			(width 0.0635)
			(type default)
		)
		(layer "In2.Cu")
	)
	(gr_arc
		(start 92.601288 5.165852)
		(mid 92.34256 5.026477)
		(end 92.239338 4.751324)
		(stroke
			(width 0.0635)
			(type default)
		)
		(layer "In2.Cu")
	)
	(gr_line
		(start 92.701618 -32.82569)
		(end 93.080332 -32.069786)
		(stroke
			(width 0.0635)
			(type default)
		)
		(layer "In2.Cu")
	)
	(gr_line
		(start 93.014038 -26.89987)
		(end 93.0148 -26.895552)
		(stroke
			(width 0.0635)
			(type default)
		)
		(layer "In2.Cu")
	)
	(gr_line
		(start 93.0148 -26.895552)
		(end 93.017086 -26.89098)
		(stroke
			(width 0.0635)
			(type default)
		)
		(layer "In2.Cu")
	)
	(gr_line
		(start 93.156532 4.577334)
		(end 93.156786 4.577588)
		(stroke
			(width 0.0635)
			(type default)
		)
		(layer "In2.Cu")
	)
	(gr_line
		(start 93.156532 4.577334)
		(end 93.15704 4.577334)
		(stroke
			(width 0.0635)
			(type default)
		)
		(layer "In2.Cu")
	)
	(gr_line
		(start 93.156786 4.57708)
		(end 93.15704 4.577334)
		(stroke
			(width 0.0635)
			(type default)
		)
		(layer "In2.Cu")
	)
	(gr_line
		(start 93.157294 4.580636)
		(end 93.209872 4.851654)
		(stroke
			(width 0.0635)
			(type default)
		)
		(layer "In2.Cu")
	)
	(gr_line
		(start 93.217746 -5.512308)
		(end 93.222572 -5.48513)
		(stroke
			(width 0.0635)
			(type default)
		)
		(layer "In2.Cu")
	)
	(gr_line
		(start 93.22181 -26.481786)
		(end 93.504258 -25.917398)
		(stroke
			(width 0.0635)
			(type default)
		)
		(layer "In2.Cu")
	)
	(gr_line
		(start 93.222572 -5.48513)
		(end 93.23832 -5.462524)
		(stroke
			(width 0.0635)
			(type default)
		)
		(layer "In2.Cu")
	)
	(gr_arc
		(start 93.228414 7.250938)
		(mid 93.125145 7.548601)
		(end 92.849954 7.702042)
		(stroke
			(width 0.0635)
			(type default)
		)
		(layer "In2.Cu")
	)
	(gr_arc
		(start 93.228414 7.250938)
		(mid 93.228732 6.951344)
		(end 93.229684 6.651752)
		(stroke
			(width 0.0635)
			(type default)
		)
		(layer "In2.Cu")
	)
	(gr_line
		(start 93.256862 3.03403)
		(end 93.277436 3.06324)
		(stroke
			(width 0.0635)
			(type default)
		)
		(layer "In2.Cu")
	)
	(gr_line
		(start 93.277436 3.06324)
		(end 93.281754 3.099816)
		(stroke
			(width 0.0635)
			(type default)
		)
		(layer "In2.Cu")
	)
	(gr_line
		(start 93.445584 4.532884)
		(end 93.447108 4.543552)
		(stroke
			(width 0.0635)
			(type default)
		)
		(layer "In2.Cu")
	)
	(gr_line
		(start 93.447108 4.543552)
		(end 93.447362 4.543806)
		(stroke
			(width 0.0635)
			(type default)
		)
		(layer "In2.Cu")
	)
	(gr_line
		(start 93.447362 4.543806)
		(end 93.447616 4.543806)
		(stroke
			(width 0.0635)
			(type default)
		)
		(layer "In2.Cu")
	)
	(gr_line
		(start 93.447616 4.543806)
		(end 93.44787 4.54406)
		(stroke
			(width 0.0635)
			(type default)
		)
		(layer "In2.Cu")
	)
	(gr_line
		(start 93.469206 -26.64587)
		(end 93.68409 -26.574242)
		(stroke
			(width 0.0635)
			(type default)
		)
		(layer "In2.Cu")
	)
	(gr_line
		(start 93.521784 7.03199)
		(end 93.521784 6.946392)
		(stroke
			(width 0.0635)
			(type default)
		)
		(layer "In2.Cu")
	)
	(gr_arc
		(start 93.649038 7.413244)
		(mid 93.554437 7.232955)
		(end 93.521784 7.03199)
		(stroke
			(width 0.0635)
			(type default)
		)
		(layer "In2.Cu")
	)
	(gr_line
		(start 93.649038 7.413244)
		(end 93.865954 7.702042)
		(stroke
			(width 0.0635)
			(type default)
		)
		(layer "In2.Cu")
	)
	(gr_line
		(start 93.68409 -26.574242)
		(end 93.854778 -26.233374)
		(stroke
			(width 0.0635)
			(type default)
		)
		(layer "In2.Cu")
	)
	(gr_line
		(start 93.708474 -25.509474)
		(end 93.989906 -24.947372)
		(stroke
			(width 0.0635)
			(type default)
		)
		(layer "In2.Cu")
	)
	(gr_line
		(start 93.78315 -26.018744)
		(end 93.854778 -26.233374)
		(stroke
			(width 0.0635)
			(type default)
		)
		(layer "In2.Cu")
	)
	(gr_line
		(start 93.95587 -25.673558)
		(end 94.170754 -25.60193)
		(stroke
			(width 0.0635)
			(type default)
		)
		(layer "In2.Cu")
	)
	(gr_line
		(start 94.004892 -24.917654)
		(end 94.009464 -24.908002)
		(stroke
			(width 0.0635)
			(type default)
		)
		(layer "In2.Cu")
	)
	(gr_line
		(start 94.079822 -27.570176)
		(end 94.458028 -28.325826)
		(stroke
			(width 0.0635)
			(type default)
		)
		(layer "In2.Cu")
	)
	(gr_line
		(start 94.170754 -25.60193)
		(end 94.341188 -25.261316)
		(stroke
			(width 0.0635)
			(type default)
		)
		(layer "In2.Cu")
	)
	(gr_line
		(start 94.19463 -24.538178)
		(end 94.476824 -23.974552)
		(stroke
			(width 0.0635)
			(type default)
		)
		(layer "In2.Cu")
	)
	(gr_line
		(start 94.268544 -25.04313)
		(end 94.306898 -24.966676)
		(stroke
			(width 0.0635)
			(type default)
		)
		(layer "In2.Cu")
	)
	(gr_line
		(start 94.269814 -25.046686)
		(end 94.341188 -25.261316)
		(stroke
			(width 0.0635)
			(type default)
		)
		(layer "In2.Cu")
	)
	(gr_line
		(start 94.442534 -24.7015)
		(end 94.657164 -24.629872)
		(stroke
			(width 0.0635)
			(type default)
		)
		(layer "In2.Cu")
	)
	(gr_arc
		(start 94.458028 -28.325826)
		(mid 94.531519 -28.389452)
		(end 94.628462 -28.382468)
		(stroke
			(width 0.0635)
			(type default)
		)
		(layer "In2.Cu")
	)
	(gr_line
		(start 94.546166 4.444238)
		(end 94.549722 4.46405)
		(stroke
			(width 0.0635)
			(type default)
		)
		(layer "In2.Cu")
	)
	(gr_line
		(start 94.549722 4.46405)
		(end 94.554294 4.703572)
		(stroke
			(width 0.0635)
			(type default)
		)
		(layer "In2.Cu")
	)
	(gr_arc
		(start 94.554548 4.714748)
		(mid 94.451278 5.012415)
		(end 94.176088 5.165852)
		(stroke
			(width 0.0635)
			(type default)
		)
		(layer "In2.Cu")
	)
	(gr_line
		(start 94.564708 2.932684)
		(end 94.580456 2.95529)
		(stroke
			(width 0.0635)
			(type default)
		)
		(layer "In2.Cu")
	)
	(gr_line
		(start 94.580456 2.95529)
		(end 94.585282 2.982468)
		(stroke
			(width 0.0635)
			(type default)
		)
		(layer "In2.Cu")
	)
	(gr_line
		(start 94.628462 -28.382468)
		(end 94.628716 -28.382468)
		(stroke
			(width 0.0635)
			(type default)
		)
		(layer "In2.Cu")
	)
	(gr_line
		(start 94.657164 -24.629872)
		(end 94.827852 -24.289258)
		(stroke
			(width 0.0635)
			(type default)
		)
		(layer "In2.Cu")
	)
	(gr_line
		(start 94.702376 -28.814522)
		(end 95.079312 -29.570426)
		(stroke
			(width 0.0635)
			(type default)
		)
		(layer "In2.Cu")
	)
	(gr_line
		(start 94.756224 -24.074374)
		(end 94.827852 -24.289258)
		(stroke
			(width 0.0635)
			(type default)
		)
		(layer "In2.Cu")
	)
	(gr_arc
		(start 94.759018 -28.644088)
		(mid 94.695399 -28.717574)
		(end 94.702376 -28.814522)
		(stroke
			(width 0.0635)
			(type default)
		)
		(layer "In2.Cu")
	)
	(gr_line
		(start 94.759018 -28.644088)
		(end 94.759272 -28.644088)
		(stroke
			(width 0.0635)
			(type default)
		)
		(layer "In2.Cu")
	)
	(gr_line
		(start 94.837504 4.414012)
		(end 94.846394 4.696206)
		(stroke
			(width 0.0635)
			(type default)
		)
		(layer "In2.Cu")
	)
	(gr_line
		(start 94.981776 -15.632176)
		(end 94.997524 -15.60957)
		(stroke
			(width 0.0635)
			(type default)
		)
		(layer "In2.Cu")
	)
	(gr_line
		(start 94.997524 -15.60957)
		(end 95.00235 -15.582392)
		(stroke
			(width 0.0635)
			(type default)
		)
		(layer "In2.Cu")
	)
	(gr_arc
		(start 95.192088 5.165852)
		(mid 94.946564 4.990528)
		(end 94.846648 4.705858)
		(stroke
			(width 0.0635)
			(type default)
		)
		(layer "In2.Cu")
	)
	(gr_line
		(start 95.345758 -4.788916)
		(end 95.350584 -4.761738)
		(stroke
			(width 0.0635)
			(type default)
		)
		(layer "In2.Cu")
	)
	(gr_line
		(start 95.350584 -4.761738)
		(end 95.366332 -4.739132)
		(stroke
			(width 0.0635)
			(type default)
		)
		(layer "In2.Cu")
	)
	(gr_line
		(start 95.406718 -25.055576)
		(end 95.41129 -25.031446)
		(stroke
			(width 0.0635)
			(type default)
		)
		(layer "In2.Cu")
	)
	(gr_line
		(start 95.41129 -25.031446)
		(end 95.426022 -25.010364)
		(stroke
			(width 0.0635)
			(type default)
		)
		(layer "In2.Cu")
	)
	(gr_line
		(start 95.589852 -24.492966)
		(end 95.629222 -24.716232)
		(stroke
			(width 0.0635)
			(type default)
		)
		(layer "In2.Cu")
	)
	(gr_line
		(start 95.589852 -24.492966)
		(end 95.808546 -24.1808)
		(stroke
			(width 0.0635)
			(type default)
		)
		(layer "In2.Cu")
	)
	(gr_line
		(start 95.683578 2.760472)
		(end 95.697548 2.780538)
		(stroke
			(width 0.0635)
			(type default)
		)
		(layer "In2.Cu")
	)
	(gr_line
		(start 95.697548 2.780538)
		(end 95.701866 2.803906)
		(stroke
			(width 0.0635)
			(type default)
		)
		(layer "In2.Cu")
	)
	(gr_line
		(start 95.727266 -30.20822)
		(end 95.72752 -30.20822)
		(stroke
			(width 0.0635)
			(type default)
		)
		(layer "In2.Cu")
	)
	(gr_line
		(start 95.808546 -24.1808)
		(end 96.031812 -24.14143)
		(stroke
			(width 0.0635)
			(type default)
		)
		(layer "In2.Cu")
	)
	(gr_arc
		(start 95.819214 7.250938)
		(mid 95.716072 7.548765)
		(end 95.440754 7.702042)
		(stroke
			(width 0.0635)
			(type default)
		)
		(layer "In2.Cu")
	)
	(gr_arc
		(start 95.820484 6.651752)
		(mid 95.820166 6.951346)
		(end 95.819214 7.250938)
		(stroke
			(width 0.0635)
			(type default)
		)
		(layer "In2.Cu")
	)
	(gr_line
		(start 95.889318 -24.858472)
		(end 96.2533 -24.338788)
		(stroke
			(width 0.0635)
			(type default)
		)
		(layer "In2.Cu")
	)
	(gr_line
		(start 96.080072 -34.070036)
		(end 96.457516 -33.314132)
		(stroke
			(width 0.0635)
			(type default)
		)
		(layer "In2.Cu")
	)
	(gr_line
		(start 96.112584 7.237984)
		(end 96.112584 6.946392)
		(stroke
			(width 0.0635)
			(type default)
		)
		(layer "In2.Cu")
	)
	(gr_line
		(start 96.213422 -23.602442)
		(end 96.252792 -23.825708)
		(stroke
			(width 0.0635)
			(type default)
		)
		(layer "In2.Cu")
	)
	(gr_line
		(start 96.213422 -23.602442)
		(end 96.431862 -23.290276)
		(stroke
			(width 0.0635)
			(type default)
		)
		(layer "In2.Cu")
	)
	(gr_line
		(start 96.431862 -23.290276)
		(end 96.655128 -23.250906)
		(stroke
			(width 0.0635)
			(type default)
		)
		(layer "In2.Cu")
	)
	(gr_arc
		(start 96.456754 7.702042)
		(mid 96.20806 7.526845)
		(end 96.112584 7.237984)
		(stroke
			(width 0.0635)
			(type default)
		)
		(layer "In2.Cu")
	)
	(gr_arc
		(start 96.457516 -33.314132)
		(mid 96.464309 -33.217265)
		(end 96.40062 -33.143952)
		(stroke
			(width 0.0635)
			(type default)
		)
		(layer "In2.Cu")
	)
	(gr_line
		(start 96.498664 -0.805942)
		(end 96.506538 -0.794766)
		(stroke
			(width 0.0635)
			(type default)
		)
		(layer "In2.Cu")
	)
	(gr_line
		(start 96.506538 -0.794766)
		(end 96.517714 -0.786892)
		(stroke
			(width 0.0635)
			(type default)
		)
		(layer "In2.Cu")
	)
	(gr_line
		(start 96.51365 -23.966678)
		(end 96.876362 -23.448772)
		(stroke
			(width 0.0635)
			(type default)
		)
		(layer "In2.Cu")
	)
	(gr_arc
		(start 96.531684 -32.882586)
		(mid 96.62874 -32.889527)
		(end 96.702118 -32.82569)
		(stroke
			(width 0.0635)
			(type default)
		)
		(layer "In2.Cu")
	)
	(gr_line
		(start 96.702118 -32.82569)
		(end 97.079562 -32.069786)
		(stroke
			(width 0.0635)
			(type default)
		)
		(layer "In2.Cu")
	)
	(gr_line
		(start 96.93529 -27.159712)
		(end 96.940624 -27.162252)
		(stroke
			(width 0.0635)
			(type default)
		)
		(layer "In2.Cu")
	)
	(gr_line
		(start 96.93529 -27.159712)
		(end 96.951038 -27.127708)
		(stroke
			(width 0.0635)
			(type default)
		)
		(layer "In2.Cu")
	)
	(gr_line
		(start 96.9391 -27.22118)
		(end 96.940116 -27.18308)
		(stroke
			(width 0.0635)
			(type default)
		)
		(layer "In2.Cu")
	)
	(gr_line
		(start 96.940116 -27.182826)
		(end 96.940116 -27.18308)
		(stroke
			(width 0.0635)
			(type default)
		)
		(layer "In2.Cu")
	)
	(gr_line
		(start 96.940624 -27.162252)
		(end 96.940624 -27.1653)
		(stroke
			(width 0.0635)
			(type default)
		)
		(layer "In2.Cu")
	)
	(gr_line
		(start 97.136966 4.444238)
		(end 97.140522 4.46405)
		(stroke
			(width 0.0635)
			(type default)
		)
		(layer "In2.Cu")
	)
	(gr_line
		(start 97.140522 4.46405)
		(end 97.145094 4.703572)
		(stroke
			(width 0.0635)
			(type default)
		)
		(layer "In2.Cu")
	)
	(gr_arc
		(start 97.145348 4.714748)
		(mid 97.042078 5.012415)
		(end 96.766888 5.165852)
		(stroke
			(width 0.0635)
			(type default)
		)
		(layer "In2.Cu")
	)
	(gr_line
		(start 97.151444 -26.721562)
		(end 97.432368 -26.152094)
		(stroke
			(width 0.0635)
			(type default)
		)
		(layer "In2.Cu")
	)
	(gr_line
		(start 97.228914 3.349244)
		(end 97.244662 3.37185)
		(stroke
			(width 0.0635)
			(type default)
		)
		(layer "In2.Cu")
	)
	(gr_line
		(start 97.229168 -27.22499)
		(end 97.2312 -27.228546)
		(stroke
			(width 0.0635)
			(type default)
		)
		(layer "In2.Cu")
	)
	(gr_line
		(start 97.229168 -27.22499)
		(end 97.2312 -27.220672)
		(stroke
			(width 0.0635)
			(type default)
		)
		(layer "In2.Cu")
	)
	(gr_line
		(start 97.244662 3.37185)
		(end 97.249488 3.399028)
		(stroke
			(width 0.0635)
			(type default)
		)
		(layer "In2.Cu")
	)
	(gr_line
		(start 97.344992 -4.564126)
		(end 97.349818 -4.536948)
		(stroke
			(width 0.0635)
			(type default)
		)
		(layer "In2.Cu")
	)
	(gr_line
		(start 97.349818 -4.536948)
		(end 97.365566 -4.514342)
		(stroke
			(width 0.0635)
			(type default)
		)
		(layer "In2.Cu")
	)
	(gr_line
		(start 97.400618 -26.882344)
		(end 97.615502 -26.809446)
		(stroke
			(width 0.0635)
			(type default)
		)
		(layer "In2.Cu")
	)
	(gr_line
		(start 97.428304 4.414012)
		(end 97.437194 4.696206)
		(stroke
			(width 0.0635)
			(type default)
		)
		(layer "In2.Cu")
	)
	(gr_line
		(start 97.46742 2.44856)
		(end 97.475802 2.460498)
		(stroke
			(width 0.0635)
			(type default)
		)
		(layer "In2.Cu")
	)
	(gr_line
		(start 97.475802 2.460498)
		(end 97.48774 2.46888)
		(stroke
			(width 0.0635)
			(type default)
		)
		(layer "In2.Cu")
	)
	(gr_line
		(start 97.615502 -26.809446)
		(end 97.783904 -26.467816)
		(stroke
			(width 0.0635)
			(type default)
		)
		(layer "In2.Cu")
	)
	(gr_line
		(start 97.632774 -25.745694)
		(end 97.912682 -25.178512)
		(stroke
			(width 0.0635)
			(type default)
		)
		(layer "In2.Cu")
	)
	(gr_line
		(start 97.71126 -26.252932)
		(end 97.783904 -26.467816)
		(stroke
			(width 0.0635)
			(type default)
		)
		(layer "In2.Cu")
	)
	(gr_arc
		(start 97.782888 5.165852)
		(mid 97.537364 4.990528)
		(end 97.437448 4.705858)
		(stroke
			(width 0.0635)
			(type default)
		)
		(layer "In2.Cu")
	)
	(gr_line
		(start 97.881694 -25.907238)
		(end 98.096324 -25.834594)
		(stroke
			(width 0.0635)
			(type default)
		)
		(layer "In2.Cu")
	)
	(gr_line
		(start 98.020124 -0.949706)
		(end 98.027998 -0.93853)
		(stroke
			(width 0.0635)
			(type default)
		)
		(layer "In2.Cu")
	)
	(gr_line
		(start 98.027998 -0.93853)
		(end 98.039174 -0.930656)
		(stroke
			(width 0.0635)
			(type default)
		)
		(layer "In2.Cu")
	)
	(gr_line
		(start 98.080322 -27.570176)
		(end 98.458528 -28.325826)
		(stroke
			(width 0.0635)
			(type default)
		)
		(layer "In2.Cu")
	)
	(gr_line
		(start 98.096324 -25.834594)
		(end 98.26498 -25.49271)
		(stroke
			(width 0.0635)
			(type default)
		)
		(layer "In2.Cu")
	)
	(gr_line
		(start 98.112834 -24.77262)
		(end 98.394012 -24.202898)
		(stroke
			(width 0.0635)
			(type default)
		)
		(layer "In2.Cu")
	)
	(gr_line
		(start 98.192082 -25.27808)
		(end 98.26498 -25.49271)
		(stroke
			(width 0.0635)
			(type default)
		)
		(layer "In2.Cu")
	)
	(gr_line
		(start 98.36277 -24.932386)
		(end 98.5774 -24.859488)
		(stroke
			(width 0.0635)
			(type default)
		)
		(layer "In2.Cu")
	)
	(gr_arc
		(start 98.458528 -28.325826)
		(mid 98.532019 -28.389452)
		(end 98.628962 -28.382468)
		(stroke
			(width 0.0635)
			(type default)
		)
		(layer "In2.Cu")
	)
	(gr_line
		(start 98.5774 -24.859488)
		(end 98.746056 -24.517858)
		(stroke
			(width 0.0635)
			(type default)
		)
		(layer "In2.Cu")
	)
	(gr_line
		(start 98.628962 -28.382468)
		(end 98.629216 -28.382468)
		(stroke
			(width 0.0635)
			(type default)
		)
		(layer "In2.Cu")
	)
	(gr_line
		(start 98.673158 -24.303228)
		(end 98.746056 -24.517858)
		(stroke
			(width 0.0635)
			(type default)
		)
		(layer "In2.Cu")
	)
	(gr_line
		(start 98.702876 -28.814522)
		(end 99.079812 -29.570426)
		(stroke
			(width 0.0635)
			(type default)
		)
		(layer "In2.Cu")
	)
	(gr_arc
		(start 98.759518 -28.644088)
		(mid 98.695908 -28.717571)
		(end 98.702876 -28.814522)
		(stroke
			(width 0.0635)
			(type default)
		)
		(layer "In2.Cu")
	)
	(gr_line
		(start 98.759518 -28.644088)
		(end 98.759772 -28.644088)
		(stroke
			(width 0.0635)
			(type default)
		)
		(layer "In2.Cu")
	)
	(gr_line
		(start 98.988372 -6.614922)
		(end 98.993198 -6.587744)
		(stroke
			(width 0.0635)
			(type default)
		)
		(layer "In2.Cu")
	)
	(gr_line
		(start 98.993198 -6.587744)
		(end 99.008692 -6.566154)
		(stroke
			(width 0.0635)
			(type default)
		)
		(layer "In2.Cu")
	)
	(gr_line
		(start 99.057968 -26.439622)
		(end 99.152456 -26.645616)
		(stroke
			(width 0.0635)
			(type default)
		)
		(layer "In2.Cu")
	)
	(gr_line
		(start 99.057968 -26.439622)
		(end 99.191064 -26.082752)
		(stroke
			(width 0.0635)
			(type default)
		)
		(layer "In2.Cu")
	)
	(gr_line
		(start 99.191064 -26.082752)
		(end 99.397058 -25.988264)
		(stroke
			(width 0.0635)
			(type default)
		)
		(layer "In2.Cu")
	)
	(gr_line
		(start 99.211892 -14.516862)
		(end 99.22002 -14.497558)
		(stroke
			(width 0.0635)
			(type default)
		)
		(layer "In2.Cu")
	)
	(gr_line
		(start 99.38893 3.80111)
		(end 99.411536 3.816858)
		(stroke
			(width 0.0635)
			(type default)
		)
		(layer "In2.Cu")
	)
	(gr_line
		(start 99.411536 3.816858)
		(end 99.438714 3.821684)
		(stroke
			(width 0.0635)
			(type default)
		)
		(layer "In2.Cu")
	)
	(gr_line
		(start 99.416616 -1.463802)
		(end 99.419156 -1.459738)
		(stroke
			(width 0.0635)
			(type default)
		)
		(layer "In2.Cu")
	)
	(gr_line
		(start 99.419156 -1.459738)
		(end 99.422966 -1.456436)
		(stroke
			(width 0.0635)
			(type default)
		)
		(layer "In2.Cu")
	)
	(gr_line
		(start 99.437444 -25.420828)
		(end 99.531678 -25.627076)
		(stroke
			(width 0.0635)
			(type default)
		)
		(layer "In2.Cu")
	)
	(gr_line
		(start 99.437444 -25.420828)
		(end 99.570286 -25.063958)
		(stroke
			(width 0.0635)
			(type default)
		)
		(layer "In2.Cu")
	)
	(gr_line
		(start 99.440746 -26.715466)
		(end 99.661218 -26.123646)
		(stroke
			(width 0.0635)
			(type default)
		)
		(layer "In2.Cu")
	)
	(gr_line
		(start 99.570286 -25.063958)
		(end 99.776534 -24.96947)
		(stroke
			(width 0.0635)
			(type default)
		)
		(layer "In2.Cu")
	)
	(gr_line
		(start 99.726496 -30.20822)
		(end 99.72675 -30.20822)
		(stroke
			(width 0.0635)
			(type default)
		)
		(layer "In2.Cu")
	)
	(gr_line
		(start 99.81946 -25.698196)
		(end 100.040186 -25.105868)
		(stroke
			(width 0.0635)
			(type default)
		)
		(layer "In2.Cu")
	)
	(gr_line
		(start 100.079302 -34.070036)
		(end 100.456746 -33.314132)
		(stroke
			(width 0.0635)
			(type default)
		)
		(layer "In2.Cu")
	)
	(gr_line
		(start 100.149914 -23.973536)
		(end 100.150168 -23.973282)
		(stroke
			(width 0.0635)
			(type default)
		)
		(layer "In2.Cu")
	)
	(gr_line
		(start 100.367592 3.985514)
		(end 100.3808 3.9878)
		(stroke
			(width 0.0635)
			(type default)
		)
		(layer "In2.Cu")
	)
	(gr_line
		(start 100.3808 3.9878)
		(end 100.394008 3.985514)
		(stroke
			(width 0.0635)
			(type default)
		)
		(layer "In2.Cu")
	)
	(gr_arc
		(start 100.456746 -33.314132)
		(mid 100.463543 -33.217258)
		(end 100.39985 -33.143952)
		(stroke
			(width 0.0635)
			(type default)
		)
		(layer "In2.Cu")
	)
	(gr_line
		(start 100.470462 -0.530098)
		(end 100.482146 -0.519684)
		(stroke
			(width 0.0635)
			(type default)
		)
		(layer "In2.Cu")
	)
	(gr_line
		(start 100.482146 -0.519684)
		(end 100.497132 -0.514096)
		(stroke
			(width 0.0635)
			(type default)
		)
		(layer "In2.Cu")
	)
	(gr_arc
		(start 100.530914 -32.882586)
		(mid 100.62797 -32.889527)
		(end 100.701348 -32.82569)
		(stroke
			(width 0.0635)
			(type default)
		)
		(layer "In2.Cu")
	)
	(gr_line
		(start 100.701348 -32.82569)
		(end 101.080062 -32.069786)
		(stroke
			(width 0.0635)
			(type default)
		)
		(layer "In2.Cu")
	)
	(gr_line
		(start 100.97643 -6.7437)
		(end 100.94087 -6.8834)
		(stroke
			(width 0.0635)
			(type default)
		)
		(layer "In2.Cu")
	)
	(gr_line
		(start 101.072696 2.402586)
		(end 101.095302 2.418334)
		(stroke
			(width 0.0635)
			(type default)
		)
		(layer "In2.Cu")
	)
	(gr_line
		(start 101.095302 2.418334)
		(end 101.12248 2.42316)
		(stroke
			(width 0.0635)
			(type default)
		)
		(layer "In2.Cu")
	)
	(gr_line
		(start 101.137974 -14.58595)
		(end 101.152452 -14.565122)
		(stroke
			(width 0.0635)
			(type default)
		)
		(layer "In2.Cu")
	)
	(gr_line
		(start 101.152452 -14.565122)
		(end 101.157278 -14.540484)
		(stroke
			(width 0.0635)
			(type default)
		)
		(layer "In2.Cu")
	)
	(gr_line
		(start 101.23297 -6.8834)
		(end 101.23297 -6.919976)
		(stroke
			(width 0.0635)
			(type default)
		)
		(layer "In2.Cu")
	)
	(gr_line
		(start 101.23297 -6.8834)
		(end 101.250496 -6.851396)
		(stroke
			(width 0.0635)
			(type default)
		)
		(layer "In2.Cu")
	)
	(gr_line
		(start 101.269292 -25.954736)
		(end 101.273864 -25.933908)
		(stroke
			(width 0.0635)
			(type default)
		)
		(layer "In2.Cu")
	)
	(gr_line
		(start 101.273864 -25.933908)
		(end 101.286564 -25.915874)
		(stroke
			(width 0.0635)
			(type default)
		)
		(layer "In2.Cu")
	)
	(gr_line
		(start 101.521768 1.507998)
		(end 101.544374 1.523746)
		(stroke
			(width 0.0635)
			(type default)
		)
		(layer "In2.Cu")
	)
	(gr_line
		(start 101.544374 1.523746)
		(end 101.571552 1.528572)
		(stroke
			(width 0.0635)
			(type default)
		)
		(layer "In2.Cu")
	)
	(gr_line
		(start 101.548438 -25.544526)
		(end 101.913182 -25.026366)
		(stroke
			(width 0.0635)
			(type default)
		)
		(layer "In2.Cu")
	)
	(gr_line
		(start 101.769164 -25.742392)
		(end 101.992684 -25.70353)
		(stroke
			(width 0.0635)
			(type default)
		)
		(layer "In2.Cu")
	)
	(gr_line
		(start 101.79812 3.441192)
		(end 101.811328 3.438906)
		(stroke
			(width 0.0635)
			(type default)
		)
		(layer "In2.Cu")
	)
	(gr_line
		(start 101.811328 3.438906)
		(end 101.824536 3.441192)
		(stroke
			(width 0.0635)
			(type default)
		)
		(layer "In2.Cu")
	)
	(gr_line
		(start 101.992684 -25.70353)
		(end 102.21214 -25.392126)
		(stroke
			(width 0.0635)
			(type default)
		)
		(layer "In2.Cu")
	)
	(gr_line
		(start 102.079552 -27.570176)
		(end 102.457758 -28.325826)
		(stroke
			(width 0.0635)
			(type default)
		)
		(layer "In2.Cu")
	)
	(gr_line
		(start 102.173278 -25.16886)
		(end 102.21214 -25.392126)
		(stroke
			(width 0.0635)
			(type default)
		)
		(layer "In2.Cu")
	)
	(gr_line
		(start 102.173786 -24.656288)
		(end 102.538784 -24.138128)
		(stroke
			(width 0.0635)
			(type default)
		)
		(layer "In2.Cu")
	)
	(gr_line
		(start 102.395274 -24.853646)
		(end 102.618794 -24.814784)
		(stroke
			(width 0.0635)
			(type default)
		)
		(layer "In2.Cu")
	)
	(gr_arc
		(start 102.457758 -28.325826)
		(mid 102.531244 -28.389445)
		(end 102.628192 -28.382468)
		(stroke
			(width 0.0635)
			(type default)
		)
		(layer "In2.Cu")
	)
	(gr_line
		(start 102.618794 -24.814784)
		(end 102.837996 -24.50338)
		(stroke
			(width 0.0635)
			(type default)
		)
		(layer "In2.Cu")
	)
	(gr_line
		(start 102.628192 -28.382468)
		(end 102.628446 -28.382468)
		(stroke
			(width 0.0635)
			(type default)
		)
		(layer "In2.Cu")
	)
	(gr_line
		(start 102.702106 -28.814522)
		(end 103.080312 -29.570426)
		(stroke
			(width 0.0635)
			(type default)
		)
		(layer "In2.Cu")
	)
	(gr_arc
		(start 102.758748 -28.644088)
		(mid 102.695123 -28.717569)
		(end 102.702106 -28.814522)
		(stroke
			(width 0.0635)
			(type default)
		)
		(layer "In2.Cu")
	)
	(gr_line
		(start 102.758748 -28.644088)
		(end 102.759002 -28.644088)
		(stroke
			(width 0.0635)
			(type default)
		)
		(layer "In2.Cu")
	)
	(gr_line
		(start 102.799388 -24.280114)
		(end 102.837996 -24.50338)
		(stroke
			(width 0.0635)
			(type default)
		)
		(layer "In2.Cu")
	)
	(gr_line
		(start 102.800658 -23.767034)
		(end 103.164894 -23.249636)
		(stroke
			(width 0.0635)
			(type default)
		)
		(layer "In2.Cu")
	)
	(gr_line
		(start 102.989634 -27.803348)
		(end 102.989634 -27.803602)
		(stroke
			(width 0.0635)
			(type default)
		)
		(layer "In2.Cu")
	)
	(gr_line
		(start 102.99065 -27.801062)
		(end 102.99065 -27.802332)
		(stroke
			(width 0.0635)
			(type default)
		)
		(layer "In2.Cu")
	)
	(gr_line
		(start 102.991158 -27.81427)
		(end 102.994968 -27.840178)
		(stroke
			(width 0.0635)
			(type default)
		)
		(layer "In2.Cu")
	)
	(gr_line
		(start 103.021384 -23.9649)
		(end 103.244904 -23.926038)
		(stroke
			(width 0.0635)
			(type default)
		)
		(layer "In2.Cu")
	)
	(gr_line
		(start 103.090472 -26.60523)
		(end 103.090726 -26.603706)
		(stroke
			(width 0.0635)
			(type default)
		)
		(layer "In2.Cu")
	)
	(gr_line
		(start 103.090726 -26.603706)
		(end 103.091234 -26.60269)
		(stroke
			(width 0.0635)
			(type default)
		)
		(layer "In2.Cu")
	)
	(gr_line
		(start 103.137716 -5.620004)
		(end 103.142542 -5.592826)
		(stroke
			(width 0.0635)
			(type default)
		)
		(layer "In2.Cu")
	)
	(gr_line
		(start 103.142542 -5.592826)
		(end 103.15829 -5.57022)
		(stroke
			(width 0.0635)
			(type default)
		)
		(layer "In2.Cu")
	)
	(gr_line
		(start 103.157782 -14.477492)
		(end 103.170228 -14.459712)
		(stroke
			(width 0.0635)
			(type default)
		)
		(layer "In2.Cu")
	)
	(gr_line
		(start 103.170228 -14.459712)
		(end 103.1748 -14.438122)
		(stroke
			(width 0.0635)
			(type default)
		)
		(layer "In2.Cu")
	)
	(gr_line
		(start 103.244904 -23.926038)
		(end 103.464106 -23.614634)
		(stroke
			(width 0.0635)
			(type default)
		)
		(layer "In2.Cu")
	)
	(gr_line
		(start 103.279956 -27.66822)
		(end 103.279956 -27.668474)
		(stroke
			(width 0.0635)
			(type default)
		)
		(layer "In2.Cu")
	)
	(gr_line
		(start 103.28148 -27.735784)
		(end 103.28275 -27.79522)
		(stroke
			(width 0.0635)
			(type default)
		)
		(layer "In2.Cu")
	)
	(gr_line
		(start 103.28275 -27.79649)
		(end 103.28402 -27.79776)
		(stroke
			(width 0.0635)
			(type default)
		)
		(layer "In2.Cu")
	)
	(gr_line
		(start 103.28275 -27.79522)
		(end 103.28275 -27.79649)
		(stroke
			(width 0.0635)
			(type default)
		)
		(layer "In2.Cu")
	)
	(gr_line
		(start 103.425498 -23.391368)
		(end 103.464106 -23.614634)
		(stroke
			(width 0.0635)
			(type default)
		)
		(layer "In2.Cu")
	)
	(gr_line
		(start 103.601012 -25.177242)
		(end 103.643176 -25.399746)
		(stroke
			(width 0.0635)
			(type default)
		)
		(layer "In2.Cu")
	)
	(gr_line
		(start 103.601012 -25.177242)
		(end 103.815896 -24.862536)
		(stroke
			(width 0.0635)
			(type default)
		)
		(layer "In2.Cu")
	)
	(gr_line
		(start 103.726996 -30.20822)
		(end 103.72725 -30.20822)
		(stroke
			(width 0.0635)
			(type default)
		)
		(layer "In2.Cu")
	)
	(gr_line
		(start 103.815896 -24.862536)
		(end 104.038654 -24.82088)
		(stroke
			(width 0.0635)
			(type default)
		)
		(layer "In2.Cu")
	)
	(gr_line
		(start 103.906066 -25.53716)
		(end 104.26192 -25.016206)
		(stroke
			(width 0.0635)
			(type default)
		)
		(layer "In2.Cu")
	)
	(gr_line
		(start 104.042464 -0.731266)
		(end 104.068626 -0.705104)
		(stroke
			(width 0.0635)
			(type default)
		)
		(layer "In2.Cu")
	)
	(gr_line
		(start 104.068626 -0.705104)
		(end 104.103678 -0.694436)
		(stroke
			(width 0.0635)
			(type default)
		)
		(layer "In2.Cu")
	)
	(gr_line
		(start 104.079802 -34.070036)
		(end 104.457246 -33.314132)
		(stroke
			(width 0.0635)
			(type default)
		)
		(layer "In2.Cu")
	)
	(gr_line
		(start 104.214168 -24.279606)
		(end 104.256332 -24.50211)
		(stroke
			(width 0.0635)
			(type default)
		)
		(layer "In2.Cu")
	)
	(gr_line
		(start 104.214168 -24.279606)
		(end 104.429052 -23.9649)
		(stroke
			(width 0.0635)
			(type default)
		)
		(layer "In2.Cu")
	)
	(gr_line
		(start 104.36733 -3.843782)
		(end 104.375204 -3.832606)
		(stroke
			(width 0.0635)
			(type default)
		)
		(layer "In2.Cu")
	)
	(gr_line
		(start 104.375204 -3.832606)
		(end 104.38638 -3.824732)
		(stroke
			(width 0.0635)
			(type default)
		)
		(layer "In2.Cu")
	)
	(gr_line
		(start 104.429052 -23.9649)
		(end 104.65181 -23.922736)
		(stroke
			(width 0.0635)
			(type default)
		)
		(layer "In2.Cu")
	)
	(gr_arc
		(start 104.457246 -33.314132)
		(mid 104.464043 -33.217258)
		(end 104.40035 -33.143952)
		(stroke
			(width 0.0635)
			(type default)
		)
		(layer "In2.Cu")
	)
	(gr_line
		(start 104.519222 -24.639524)
		(end 104.875838 -24.117554)
		(stroke
			(width 0.0635)
			(type default)
		)
		(layer "In2.Cu")
	)
	(gr_arc
		(start 104.531414 -32.882586)
		(mid 104.628425 -32.889445)
		(end 104.701848 -32.82569)
		(stroke
			(width 0.0635)
			(type default)
		)
		(layer "In2.Cu")
	)
	(gr_line
		(start 104.701848 -32.82569)
		(end 105.079292 -32.069786)
		(stroke
			(width 0.0635)
			(type default)
		)
		(layer "In2.Cu")
	)
	(gr_line
		(start 104.72293 -15.007844)
		(end 104.72547 -15.003272)
		(stroke
			(width 0.0635)
			(type default)
		)
		(layer "In2.Cu")
	)
	(gr_line
		(start 104.725216 -15.003272)
		(end 104.72547 -15.003272)
		(stroke
			(width 0.0635)
			(type default)
		)
		(layer "In2.Cu")
	)
	(gr_line
		(start 104.725216 -15.003272)
		(end 104.725978 -15.002002)
		(stroke
			(width 0.0635)
			(type default)
		)
		(layer "In2.Cu")
	)
	(gr_line
		(start 104.725724 -15.000732)
		(end 104.725978 -15.002002)
		(stroke
			(width 0.0635)
			(type default)
		)
		(layer "In2.Cu")
	)
	(gr_line
		(start 104.766364 -1.51257)
		(end 104.78643 -1.499108)
		(stroke
			(width 0.0635)
			(type default)
		)
		(layer "In2.Cu")
	)
	(gr_line
		(start 104.78643 -1.499108)
		(end 104.80929 -1.495044)
		(stroke
			(width 0.0635)
			(type default)
		)
		(layer "In2.Cu")
	)
	(gr_line
		(start 104.869742 -14.653514)
		(end 104.87279 -14.646148)
		(stroke
			(width 0.0635)
			(type default)
		)
		(layer "In2.Cu")
	)
	(gr_line
		(start 104.872536 -14.638274)
		(end 104.874314 -14.642846)
		(stroke
			(width 0.0635)
			(type default)
		)
		(layer "In2.Cu")
	)
	(gr_line
		(start 104.87279 -14.646148)
		(end 104.873552 -14.644624)
		(stroke
			(width 0.0635)
			(type default)
		)
		(layer "In2.Cu")
	)
	(gr_line
		(start 104.873552 -14.644624)
		(end 104.874314 -14.6431)
		(stroke
			(width 0.0635)
			(type default)
		)
		(layer "In2.Cu")
	)
	(gr_line
		(start 104.874314 -14.642846)
		(end 104.874314 -14.6431)
		(stroke
			(width 0.0635)
			(type default)
		)
		(layer "In2.Cu")
	)
	(gr_line
		(start 104.965246 -27.269694)
		(end 104.965246 -27.305)
		(stroke
			(width 0.0635)
			(type default)
		)
		(layer "In2.Cu")
	)
	(gr_line
		(start 104.965246 -27.25039)
		(end 104.965246 -27.25166)
		(stroke
			(width 0.0635)
			(type default)
		)
		(layer "In2.Cu")
	)
	(gr_line
		(start 104.965246 -27.25039)
		(end 104.9655 -27.250136)
		(stroke
			(width 0.0635)
			(type default)
		)
		(layer "In2.Cu")
	)
	(gr_line
		(start 104.965246 -27.25039)
		(end 104.968294 -27.248358)
		(stroke
			(width 0.0635)
			(type default)
		)
		(layer "In2.Cu")
	)
	(gr_line
		(start 104.987344 -15.132812)
		(end 105.002584 -15.095982)
		(stroke
			(width 0.0635)
			(type default)
		)
		(layer "In2.Cu")
	)
	(gr_line
		(start 105.140252 -14.763496)
		(end 105.142792 -14.757908)
		(stroke
			(width 0.0635)
			(type default)
		)
		(layer "In2.Cu")
	)
	(gr_line
		(start 105.142792 -14.757908)
		(end 105.144316 -14.754606)
		(stroke
			(width 0.0635)
			(type default)
		)
		(layer "In2.Cu")
	)
	(gr_line
		(start 105.147364 -14.753336)
		(end 105.148888 -14.752574)
		(stroke
			(width 0.0635)
			(type default)
		)
		(layer "In2.Cu")
	)
	(gr_line
		(start 105.148888 -14.752574)
		(end 105.149904 -14.74724)
		(stroke
			(width 0.0635)
			(type default)
		)
		(layer "In2.Cu")
	)
	(gr_line
		(start 105.152444 -14.732254)
		(end 105.16616 -14.655038)
		(stroke
			(width 0.0635)
			(type default)
		)
		(layer "In2.Cu")
	)
	(gr_line
		(start 105.161588 -26.678128)
		(end 105.39476 -26.088086)
		(stroke
			(width 0.0635)
			(type default)
		)
		(layer "In2.Cu")
	)
	(gr_line
		(start 105.255568 -27.301952)
		(end 105.257346 -27.292554)
		(stroke
			(width 0.0635)
			(type default)
		)
		(layer "In2.Cu")
	)
	(gr_line
		(start 105.255568 -27.301952)
		(end 105.2576 -27.305)
		(stroke
			(width 0.0635)
			(type default)
		)
		(layer "In2.Cu")
	)
	(gr_line
		(start 105.30459 -4.682744)
		(end 105.309416 -4.655566)
		(stroke
			(width 0.0635)
			(type default)
		)
		(layer "In2.Cu")
	)
	(gr_line
		(start 105.309416 -4.655566)
		(end 105.325164 -4.63296)
		(stroke
			(width 0.0635)
			(type default)
		)
		(layer "In2.Cu")
	)
	(gr_line
		(start 105.422446 -26.818844)
		(end 105.630472 -26.728928)
		(stroke
			(width 0.0635)
			(type default)
		)
		(layer "In2.Cu")
	)
	(gr_line
		(start 105.56113 -25.667462)
		(end 105.794302 -25.07742)
		(stroke
			(width 0.0635)
			(type default)
		)
		(layer "In2.Cu")
	)
	(gr_line
		(start 105.630472 -26.728928)
		(end 105.77068 -26.374598)
		(stroke
			(width 0.0635)
			(type default)
		)
		(layer "In2.Cu")
	)
	(gr_line
		(start 105.680764 -26.166318)
		(end 105.77068 -26.374598)
		(stroke
			(width 0.0635)
			(type default)
		)
		(layer "In2.Cu")
	)
	(gr_line
		(start 105.766362 -4.00304)
		(end 105.774236 -3.991864)
		(stroke
			(width 0.0635)
			(type default)
		)
		(layer "In2.Cu")
	)
	(gr_line
		(start 105.774236 -3.991864)
		(end 105.785412 -3.98399)
		(stroke
			(width 0.0635)
			(type default)
		)
		(layer "In2.Cu")
	)
	(gr_line
		(start 105.822496 -25.807924)
		(end 106.030522 -25.718008)
		(stroke
			(width 0.0635)
			(type default)
		)
		(layer "In2.Cu")
	)
	(gr_line
		(start 105.960164 -24.658574)
		(end 106.194606 -24.065738)
		(stroke
			(width 0.0635)
			(type default)
		)
		(layer "In2.Cu")
	)
	(gr_line
		(start 106.030522 -25.718008)
		(end 106.17073 -25.363678)
		(stroke
			(width 0.0635)
			(type default)
		)
		(layer "In2.Cu")
	)
	(gr_line
		(start 106.080052 -27.570176)
		(end 106.458258 -28.325826)
		(stroke
			(width 0.0635)
			(type default)
		)
		(layer "In2.Cu")
	)
	(gr_line
		(start 106.08056 -25.155398)
		(end 106.17073 -25.363678)
		(stroke
			(width 0.0635)
			(type default)
		)
		(layer "In2.Cu")
	)
	(gr_line
		(start 106.222038 -24.797258)
		(end 106.430572 -24.707088)
		(stroke
			(width 0.0635)
			(type default)
		)
		(layer "In2.Cu")
	)
	(gr_line
		(start 106.430572 -24.707088)
		(end 106.570526 -24.352758)
		(stroke
			(width 0.0635)
			(type default)
		)
		(layer "In2.Cu")
	)
	(gr_line
		(start 106.458258 -28.325826)
		(end 106.5149 -28.382468)
		(stroke
			(width 0.0635)
			(type default)
		)
		(layer "In2.Cu")
	)
	(gr_line
		(start 106.480356 -24.144478)
		(end 106.570526 -24.352758)
		(stroke
			(width 0.0635)
			(type default)
		)
		(layer "In2.Cu")
	)
	(gr_line
		(start 106.535982 -23.202646)
		(end 106.536744 -23.201122)
		(stroke
			(width 0.0635)
			(type default)
		)
		(layer "In2.Cu")
	)
	(gr_line
		(start 106.536744 -23.201122)
		(end 106.537506 -23.200106)
		(stroke
			(width 0.0635)
			(type default)
		)
		(layer "In2.Cu")
	)
	(gr_line
		(start 106.702606 -28.814522)
		(end 107.079542 -29.570426)
		(stroke
			(width 0.0635)
			(type default)
		)
		(layer "In2.Cu")
	)
	(gr_line
		(start 106.708448 -2.198624)
		(end 106.731054 -2.182876)
		(stroke
			(width 0.0635)
			(type default)
		)
		(layer "In2.Cu")
	)
	(gr_arc
		(start 106.720132 -28.674568)
		(mid 106.690171 -28.741884)
		(end 106.702606 -28.814522)
		(stroke
			(width 0.0635)
			(type default)
		)
		(layer "In2.Cu")
	)
	(gr_line
		(start 106.731054 -2.182876)
		(end 106.758232 -2.17805)
		(stroke
			(width 0.0635)
			(type default)
		)
		(layer "In2.Cu")
	)
	(gr_line
		(start 106.9975 -27.293062)
		(end 106.9975 -27.317192)
		(stroke
			(width 0.0635)
			(type default)
		)
		(layer "In2.Cu")
	)
	(gr_line
		(start 106.9975 -27.293062)
		(end 107.007406 -27.270964)
		(stroke
			(width 0.0635)
			(type default)
		)
		(layer "In2.Cu")
	)
	(gr_line
		(start 107.01655 -3.121914)
		(end 107.039156 -3.106166)
		(stroke
			(width 0.0635)
			(type default)
		)
		(layer "In2.Cu")
	)
	(gr_line
		(start 107.024424 -28.400248)
		(end 107.03052 -28.386532)
		(stroke
			(width 0.0635)
			(type default)
		)
		(layer "In2.Cu")
	)
	(gr_line
		(start 107.039156 -3.106166)
		(end 107.066334 -3.10134)
		(stroke
			(width 0.0635)
			(type default)
		)
		(layer "In2.Cu")
	)
	(gr_line
		(start 107.070652 -26.730452)
		(end 107.151678 -26.942034)
		(stroke
			(width 0.0635)
			(type default)
		)
		(layer "In2.Cu")
	)
	(gr_line
		(start 107.070652 -26.730452)
		(end 107.2261 -26.382472)
		(stroke
			(width 0.0635)
			(type default)
		)
		(layer "In2.Cu")
	)
	(gr_line
		(start 107.103418 -14.55293)
		(end 107.119166 -14.530324)
		(stroke
			(width 0.0635)
			(type default)
		)
		(layer "In2.Cu")
	)
	(gr_line
		(start 107.119166 -14.530324)
		(end 107.123992 -14.503146)
		(stroke
			(width 0.0635)
			(type default)
		)
		(layer "In2.Cu")
	)
	(gr_line
		(start 107.13212 -5.4864)
		(end 107.136946 -5.459222)
		(stroke
			(width 0.0635)
			(type default)
		)
		(layer "In2.Cu")
	)
	(gr_line
		(start 107.136946 -5.459222)
		(end 107.152694 -5.436616)
		(stroke
			(width 0.0635)
			(type default)
		)
		(layer "In2.Cu")
	)
	(gr_line
		(start 107.2261 -26.382472)
		(end 107.437682 -26.301446)
		(stroke
			(width 0.0635)
			(type default)
		)
		(layer "In2.Cu")
	)
	(gr_line
		(start 107.277154 -27.849322)
		(end 107.288076 -27.825446)
		(stroke
			(width 0.0635)
			(type default)
		)
		(layer "In2.Cu")
	)
	(gr_line
		(start 107.288076 -27.799792)
		(end 107.288076 -27.825446)
		(stroke
			(width 0.0635)
			(type default)
		)
		(layer "In2.Cu")
	)
	(gr_line
		(start 107.435396 -27.02941)
		(end 107.692952 -26.45283)
		(stroke
			(width 0.0635)
			(type default)
		)
		(layer "In2.Cu")
	)
	(gr_line
		(start 107.514136 -25.73782)
		(end 107.594908 -25.949656)
		(stroke
			(width 0.0635)
			(type default)
		)
		(layer "In2.Cu")
	)
	(gr_line
		(start 107.514136 -25.73782)
		(end 107.669584 -25.390094)
		(stroke
			(width 0.0635)
			(type default)
		)
		(layer "In2.Cu")
	)
	(gr_line
		(start 107.669584 -25.390094)
		(end 107.881166 -25.309068)
		(stroke
			(width 0.0635)
			(type default)
		)
		(layer "In2.Cu")
	)
	(gr_line
		(start 107.727496 -30.20822)
		(end 107.72775 -30.20822)
		(stroke
			(width 0.0635)
			(type default)
		)
		(layer "In2.Cu")
	)
	(gr_line
		(start 107.868212 4.506722)
		(end 107.89539 4.511548)
		(stroke
			(width 0.0635)
			(type default)
		)
		(layer "In2.Cu")
	)
	(gr_line
		(start 107.878626 -26.037032)
		(end 108.135928 -25.46096)
		(stroke
			(width 0.0635)
			(type default)
		)
		(layer "In2.Cu")
	)
	(gr_line
		(start 107.89539 4.511548)
		(end 107.917996 4.527296)
		(stroke
			(width 0.0635)
			(type default)
		)
		(layer "In2.Cu")
	)
	(gr_line
		(start 107.986322 -4.246372)
		(end 107.994196 -4.235196)
		(stroke
			(width 0.0635)
			(type default)
		)
		(layer "In2.Cu")
	)
	(gr_line
		(start 107.994196 -4.235196)
		(end 108.005372 -4.227322)
		(stroke
			(width 0.0635)
			(type default)
		)
		(layer "In2.Cu")
	)
	(gr_line
		(start 108.080302 -34.070036)
		(end 108.457746 -33.314132)
		(stroke
			(width 0.0635)
			(type default)
		)
		(layer "In2.Cu")
	)
	(gr_arc
		(start 108.457746 -33.314132)
		(mid 108.464536 -33.217263)
		(end 108.40085 -33.143952)
		(stroke
			(width 0.0635)
			(type default)
		)
		(layer "In2.Cu")
	)
	(gr_line
		(start 108.51007 -3.873754)
		(end 108.532676 -3.858006)
		(stroke
			(width 0.0635)
			(type default)
		)
		(layer "In2.Cu")
	)
	(gr_arc
		(start 108.531914 -32.882586)
		(mid 108.62897 -32.889527)
		(end 108.702348 -32.82569)
		(stroke
			(width 0.0635)
			(type default)
		)
		(layer "In2.Cu")
	)
	(gr_line
		(start 108.532676 -3.858006)
		(end 108.559854 -3.85318)
		(stroke
			(width 0.0635)
			(type default)
		)
		(layer "In2.Cu")
	)
	(gr_line
		(start 108.702348 -32.82569)
		(end 109.079792 -32.069786)
		(stroke
			(width 0.0635)
			(type default)
		)
		(layer "In2.Cu")
	)
	(gr_line
		(start 108.940092 -27.25928)
		(end 108.942632 -27.228038)
		(stroke
			(width 0.0635)
			(type default)
		)
		(layer "In2.Cu")
	)
	(gr_line
		(start 108.943394 -27.21864)
		(end 108.943648 -27.218386)
		(stroke
			(width 0.0635)
			(type default)
		)
		(layer "In2.Cu")
	)
	(gr_line
		(start 108.943648 -27.218386)
		(end 108.943902 -27.218386)
		(stroke
			(width 0.0635)
			(type default)
		)
		(layer "In2.Cu")
	)
	(gr_line
		(start 108.943902 -27.218386)
		(end 108.944156 -27.218132)
		(stroke
			(width 0.0635)
			(type default)
		)
		(layer "In2.Cu")
	)
	(gr_line
		(start 108.944156 -27.218132)
		(end 108.944918 -27.21356)
		(stroke
			(width 0.0635)
			(type default)
		)
		(layer "In2.Cu")
	)
	(gr_line
		(start 108.989368 -15.489682)
		(end 109.0041 -15.4686)
		(stroke
			(width 0.0635)
			(type default)
		)
		(layer "In2.Cu")
	)
	(gr_line
		(start 109.0041 -15.4686)
		(end 109.008672 -15.443962)
		(stroke
			(width 0.0635)
			(type default)
		)
		(layer "In2.Cu")
	)
	(gr_line
		(start 109.15904 -26.608786)
		(end 109.40415 -26.025094)
		(stroke
			(width 0.0635)
			(type default)
		)
		(layer "In2.Cu")
	)
	(gr_line
		(start 109.187996 -27.784044)
		(end 109.192568 -27.773376)
		(stroke
			(width 0.0635)
			(type default)
		)
		(layer "In2.Cu")
	)
	(gr_line
		(start 109.192568 -27.773376)
		(end 109.193584 -27.761946)
		(stroke
			(width 0.0635)
			(type default)
		)
		(layer "In2.Cu")
	)
	(gr_line
		(start 109.201204 -5.609844)
		(end 109.20603 -5.582666)
		(stroke
			(width 0.0635)
			(type default)
		)
		(layer "In2.Cu")
	)
	(gr_line
		(start 109.20603 -5.582666)
		(end 109.221524 -5.561076)
		(stroke
			(width 0.0635)
			(type default)
		)
		(layer "In2.Cu")
	)
	(gr_line
		(start 109.232192 -27.266646)
		(end 109.232446 -27.266392)
		(stroke
			(width 0.0635)
			(type default)
		)
		(layer "In2.Cu")
	)
	(gr_line
		(start 109.232192 -27.266646)
		(end 109.232954 -27.266646)
		(stroke
			(width 0.0635)
			(type default)
		)
		(layer "In2.Cu")
	)
	(gr_line
		(start 109.232446 -27.266392)
		(end 109.2327 -27.264106)
		(stroke
			(width 0.0635)
			(type default)
		)
		(layer "In2.Cu")
	)
	(gr_line
		(start 109.2327 -27.2669)
		(end 109.232954 -27.266646)
		(stroke
			(width 0.0635)
			(type default)
		)
		(layer "In2.Cu")
	)
	(gr_line
		(start 109.417358 -26.754836)
		(end 109.627162 -26.669238)
		(stroke
			(width 0.0635)
			(type default)
		)
		(layer "In2.Cu")
	)
	(gr_line
		(start 109.497114 -5.166868)
		(end 109.504988 -5.155692)
		(stroke
			(width 0.0635)
			(type default)
		)
		(layer "In2.Cu")
	)
	(gr_line
		(start 109.504988 -5.155692)
		(end 109.516164 -5.147818)
		(stroke
			(width 0.0635)
			(type default)
		)
		(layer "In2.Cu")
	)
	(gr_line
		(start 109.548422 6.189472)
		(end 109.55147 6.196838)
		(stroke
			(width 0.0635)
			(type default)
		)
		(layer "In2.Cu")
	)
	(gr_line
		(start 109.551216 6.204712)
		(end 109.552994 6.20014)
		(stroke
			(width 0.0635)
			(type default)
		)
		(layer "In2.Cu")
	)
	(gr_line
		(start 109.55147 6.196838)
		(end 109.552994 6.20014)
		(stroke
			(width 0.0635)
			(type default)
		)
		(layer "In2.Cu")
	)
	(gr_line
		(start 109.580426 -25.605486)
		(end 109.824012 -25.024842)
		(stroke
			(width 0.0635)
			(type default)
		)
		(layer "In2.Cu")
	)
	(gr_arc
		(start 109.621066 7.291578)
		(mid 109.517786 7.589232)
		(end 109.242606 7.742682)
		(stroke
			(width 0.0635)
			(type default)
		)
		(layer "In2.Cu")
	)
	(gr_line
		(start 109.627162 -26.669238)
		(end 109.774482 -26.317956)
		(stroke
			(width 0.0635)
			(type default)
		)
		(layer "In2.Cu")
	)
	(gr_line
		(start 109.65053 5.740908)
		(end 109.6899 5.768594)
		(stroke
			(width 0.0635)
			(type default)
		)
		(layer "In2.Cu")
	)
	(gr_line
		(start 109.688884 -26.108152)
		(end 109.774482 -26.317956)
		(stroke
			(width 0.0635)
			(type default)
		)
		(layer "In2.Cu")
	)
	(gr_line
		(start 109.6899 5.768594)
		(end 109.708442 5.813044)
		(stroke
			(width 0.0635)
			(type default)
		)
		(layer "In2.Cu")
	)
	(gr_line
		(start 109.826044 6.08965)
		(end 109.827568 6.090412)
		(stroke
			(width 0.0635)
			(type default)
		)
		(layer "In2.Cu")
	)
	(gr_line
		(start 109.827568 6.090412)
		(end 109.828584 6.095746)
		(stroke
			(width 0.0635)
			(type default)
		)
		(layer "In2.Cu")
	)
	(gr_line
		(start 109.831124 6.110732)
		(end 109.84484 6.18744)
		(stroke
			(width 0.0635)
			(type default)
		)
		(layer "In2.Cu")
	)
	(gr_line
		(start 109.837982 -25.752552)
		(end 110.047786 -25.6667)
		(stroke
			(width 0.0635)
			(type default)
		)
		(layer "In2.Cu")
	)
	(gr_line
		(start 110.001812 -24.601424)
		(end 110.244636 -24.022558)
		(stroke
			(width 0.0635)
			(type default)
		)
		(layer "In2.Cu")
	)
	(gr_line
		(start 110.047786 -25.6667)
		(end 110.195106 -25.315418)
		(stroke
			(width 0.0635)
			(type default)
		)
		(layer "In2.Cu")
	)
	(gr_line
		(start 110.079282 -27.570176)
		(end 110.457488 -28.325826)
		(stroke
			(width 0.0635)
			(type default)
		)
		(layer "In2.Cu")
	)
	(gr_line
		(start 110.109508 -25.105614)
		(end 110.195106 -25.315418)
		(stroke
			(width 0.0635)
			(type default)
		)
		(layer "In2.Cu")
	)
	(gr_line
		(start 110.153196 1.1176)
		(end 110.180374 1.122426)
		(stroke
			(width 0.0635)
			(type default)
		)
		(layer "In2.Cu")
	)
	(gr_line
		(start 110.180374 1.122426)
		(end 110.20298 1.138174)
		(stroke
			(width 0.0635)
			(type default)
		)
		(layer "In2.Cu")
	)
	(gr_arc
		(start 110.258606 7.742682)
		(mid 110.013092 7.567354)
		(end 109.913166 7.282688)
		(stroke
			(width 0.0635)
			(type default)
		)
		(layer "In2.Cu")
	)
	(gr_line
		(start 110.25886 -24.750014)
		(end 110.46841 -24.664416)
		(stroke
			(width 0.0635)
			(type default)
		)
		(layer "In2.Cu")
	)
	(gr_line
		(start 110.264194 -4.623816)
		(end 110.2868 -4.608068)
		(stroke
			(width 0.0635)
			(type default)
		)
		(layer "In2.Cu")
	)
	(gr_line
		(start 110.2868 -4.608068)
		(end 110.313978 -4.603242)
		(stroke
			(width 0.0635)
			(type default)
		)
		(layer "In2.Cu")
	)
	(gr_line
		(start 110.423452 3.767328)
		(end 110.45063 3.772154)
		(stroke
			(width 0.0635)
			(type default)
		)
		(layer "In2.Cu")
	)
	(gr_line
		(start 110.45063 3.772154)
		(end 110.473236 3.787902)
		(stroke
			(width 0.0635)
			(type default)
		)
		(layer "In2.Cu")
	)
	(gr_arc
		(start 110.457488 -28.325826)
		(mid 110.530974 -28.389413)
		(end 110.627922 -28.382468)
		(stroke
			(width 0.0635)
			(type default)
		)
		(layer "In2.Cu")
	)
	(gr_line
		(start 110.46841 -24.664416)
		(end 110.61573 -24.31288)
		(stroke
			(width 0.0635)
			(type default)
		)
		(layer "In2.Cu")
	)
	(gr_line
		(start 110.530132 -24.10333)
		(end 110.61573 -24.31288)
		(stroke
			(width 0.0635)
			(type default)
		)
		(layer "In2.Cu")
	)
	(gr_line
		(start 110.56874 5.206492)
		(end 110.656116 5.206492)
		(stroke
			(width 0.0635)
			(type default)
		)
		(layer "In2.Cu")
	)
	(gr_line
		(start 110.627922 -28.382468)
		(end 110.628176 -28.382468)
		(stroke
			(width 0.0635)
			(type default)
		)
		(layer "In2.Cu")
	)
	(gr_line
		(start 110.701836 -28.814522)
		(end 111.080042 -29.570426)
		(stroke
			(width 0.0635)
			(type default)
		)
		(layer "In2.Cu")
	)
	(gr_arc
		(start 110.758478 -28.644088)
		(mid 110.694859 -28.717574)
		(end 110.701836 -28.814522)
		(stroke
			(width 0.0635)
			(type default)
		)
		(layer "In2.Cu")
	)
	(gr_line
		(start 110.758478 -28.644088)
		(end 110.758732 -28.644088)
		(stroke
			(width 0.0635)
			(type default)
		)
		(layer "In2.Cu")
	)
	(gr_line
		(start 110.798102 2.859024)
		(end 110.82528 2.86385)
		(stroke
			(width 0.0635)
			(type default)
		)
		(layer "In2.Cu")
	)
	(gr_line
		(start 110.82528 2.86385)
		(end 110.847886 2.879598)
		(stroke
			(width 0.0635)
			(type default)
		)
		(layer "In2.Cu")
	)
	(gr_arc
		(start 110.850172 5.126228)
		(mid 110.761118 5.185633)
		(end 110.656116 5.206492)
		(stroke
			(width 0.0635)
			(type default)
		)
		(layer "In2.Cu")
	)
	(gr_line
		(start 110.869476 -14.590268)
		(end 110.870238 -14.587474)
		(stroke
			(width 0.0635)
			(type default)
		)
		(layer "In2.Cu")
	)
	(gr_line
		(start 110.869984 -14.585696)
		(end 110.870746 -14.58595)
		(stroke
			(width 0.0635)
			(type default)
		)
		(layer "In2.Cu")
	)
	(gr_line
		(start 110.870238 -14.587474)
		(end 110.870492 -14.586712)
		(stroke
			(width 0.0635)
			(type default)
		)
		(layer "In2.Cu")
	)
	(gr_line
		(start 110.870492 -14.586712)
		(end 110.870746 -14.586204)
		(stroke
			(width 0.0635)
			(type default)
		)
		(layer "In2.Cu")
	)
	(gr_line
		(start 110.870746 -14.58595)
		(end 110.870746 -14.586204)
		(stroke
			(width 0.0635)
			(type default)
		)
		(layer "In2.Cu")
	)
	(gr_line
		(start 110.90402 4.524756)
		(end 110.907068 4.532122)
		(stroke
			(width 0.0635)
			(type default)
		)
		(layer "In2.Cu")
	)
	(gr_line
		(start 110.90656 4.54025)
		(end 110.908592 4.535424)
		(stroke
			(width 0.0635)
			(type default)
		)
		(layer "In2.Cu")
	)
	(gr_line
		(start 110.907068 4.532122)
		(end 110.908592 4.535424)
		(stroke
			(width 0.0635)
			(type default)
		)
		(layer "In2.Cu")
	)
	(gr_line
		(start 110.92688 -13.932408)
		(end 110.927642 -13.93317)
		(stroke
			(width 0.0635)
			(type default)
		)
		(layer "In2.Cu")
	)
	(gr_line
		(start 110.927134 -13.93952)
		(end 110.927642 -13.933932)
		(stroke
			(width 0.0635)
			(type default)
		)
		(layer "In2.Cu")
	)
	(gr_line
		(start 110.927642 -13.93317)
		(end 110.927642 -13.933932)
		(stroke
			(width 0.0635)
			(type default)
		)
		(layer "In2.Cu")
	)
	(gr_line
		(start 110.930436 4.711954)
		(end 110.930436 4.675378)
		(stroke
			(width 0.0635)
			(type default)
		)
		(layer "In2.Cu")
	)
	(gr_arc
		(start 110.930436 4.93395)
		(mid 110.909261 5.038)
		(end 110.850172 5.126228)
		(stroke
			(width 0.0635)
			(type default)
		)
		(layer "In2.Cu")
	)
	(gr_line
		(start 110.955836 -27.318208)
		(end 110.957614 -27.338274)
		(stroke
			(width 0.0635)
			(type default)
		)
		(layer "In2.Cu")
	)
	(gr_line
		(start 110.955836 -27.318208)
		(end 110.961932 -27.298904)
		(stroke
			(width 0.0635)
			(type default)
		)
		(layer "In2.Cu")
	)
	(gr_line
		(start 110.96244 -26.751026)
		(end 111.06785 -26.951432)
		(stroke
			(width 0.0635)
			(type default)
		)
		(layer "In2.Cu")
	)
	(gr_line
		(start 110.96244 -26.751026)
		(end 111.075978 -26.387298)
		(stroke
			(width 0.0635)
			(type default)
		)
		(layer "In2.Cu")
	)
	(gr_line
		(start 111.051086 -15.075662)
		(end 111.060484 -15.0622)
		(stroke
			(width 0.0635)
			(type default)
		)
		(layer "In2.Cu")
	)
	(gr_line
		(start 111.057182 4.19735)
		(end 111.095536 4.224274)
		(stroke
			(width 0.0635)
			(type default)
		)
		(layer "In2.Cu")
	)
	(gr_line
		(start 111.060484 -15.0622)
		(end 111.064294 -15.04569)
		(stroke
			(width 0.0635)
			(type default)
		)
		(layer "In2.Cu")
	)
	(gr_line
		(start 111.075978 -26.387298)
		(end 111.276384 -26.281888)
		(stroke
			(width 0.0635)
			(type default)
		)
		(layer "In2.Cu")
	)
	(gr_line
		(start 111.095536 4.224274)
		(end 111.11357 4.267454)
		(stroke
			(width 0.0635)
			(type default)
		)
		(layer "In2.Cu")
	)
	(gr_line
		(start 111.154718 -14.654784)
		(end 111.154972 -14.65326)
		(stroke
			(width 0.0635)
			(type default)
		)
		(layer "In2.Cu")
	)
	(gr_line
		(start 111.154972 -14.65326)
		(end 111.15548 -14.651736)
		(stroke
			(width 0.0635)
			(type default)
		)
		(layer "In2.Cu")
	)
	(gr_line
		(start 111.15929 -14.63167)
		(end 111.162846 -14.589506)
		(stroke
			(width 0.0635)
			(type default)
		)
		(layer "In2.Cu")
	)
	(gr_line
		(start 111.169196 0.289052)
		(end 111.196374 0.293878)
		(stroke
			(width 0.0635)
			(type default)
		)
		(layer "In2.Cu")
	)
	(gr_line
		(start 111.176054 4.417822)
		(end 111.176816 4.419854)
		(stroke
			(width 0.0635)
			(type default)
		)
		(layer "In2.Cu")
	)
	(gr_line
		(start 111.176816 4.419854)
		(end 111.176816 4.4196)
		(stroke
			(width 0.0635)
			(type default)
		)
		(layer "In2.Cu")
	)
	(gr_line
		(start 111.17707 4.420362)
		(end 111.178594 4.423664)
		(stroke
			(width 0.0635)
			(type default)
		)
		(layer "In2.Cu")
	)
	(gr_line
		(start 111.181642 4.424934)
		(end 111.183166 4.425696)
		(stroke
			(width 0.0635)
			(type default)
		)
		(layer "In2.Cu")
	)
	(gr_line
		(start 111.183166 4.425696)
		(end 111.184182 4.43103)
		(stroke
			(width 0.0635)
			(type default)
		)
		(layer "In2.Cu")
	)
	(gr_line
		(start 111.186722 4.44627)
		(end 111.186722 4.446016)
		(stroke
			(width 0.0635)
			(type default)
		)
		(layer "In2.Cu")
	)
	(gr_line
		(start 111.186722 4.44627)
		(end 111.200438 4.523486)
		(stroke
			(width 0.0635)
			(type default)
		)
		(layer "In2.Cu")
	)
	(gr_line
		(start 111.196374 0.293878)
		(end 111.21898 0.309626)
		(stroke
			(width 0.0635)
			(type default)
		)
		(layer "In2.Cu")
	)
	(gr_line
		(start 111.218726 -13.958824)
		(end 111.218726 -13.959586)
		(stroke
			(width 0.0635)
			(type default)
		)
		(layer "In2.Cu")
	)
	(gr_line
		(start 111.218726 -13.958824)
		(end 111.219234 -13.958316)
		(stroke
			(width 0.0635)
			(type default)
		)
		(layer "In2.Cu")
	)
	(gr_line
		(start 111.219234 -13.932408)
		(end 111.219234 -13.958316)
		(stroke
			(width 0.0635)
			(type default)
		)
		(layer "In2.Cu")
	)
	(gr_line
		(start 111.286036 -25.713182)
		(end 111.391446 -25.913588)
		(stroke
			(width 0.0635)
			(type default)
		)
		(layer "In2.Cu")
	)
	(gr_line
		(start 111.286036 -25.713182)
		(end 111.399574 -25.349454)
		(stroke
			(width 0.0635)
			(type default)
		)
		(layer "In2.Cu")
	)
	(gr_arc
		(start 111.300768 5.128514)
		(mid 111.243141 5.042409)
		(end 111.22279 4.940808)
		(stroke
			(width 0.0635)
			(type default)
		)
		(layer "In2.Cu")
	)
	(gr_line
		(start 111.300768 5.128514)
		(end 111.305594 5.13334)
		(stroke
			(width 0.0635)
			(type default)
		)
		(layer "In2.Cu")
	)
	(gr_line
		(start 111.359696 -27.004264)
		(end 111.546894 -26.404062)
		(stroke
			(width 0.0635)
			(type default)
		)
		(layer "In2.Cu")
	)
	(gr_line
		(start 111.399574 -25.349454)
		(end 111.59998 -25.244044)
		(stroke
			(width 0.0635)
			(type default)
		)
		(layer "In2.Cu")
	)
	(gr_arc
		(start 111.48187 5.206492)
		(mid 111.386447 5.187475)
		(end 111.305594 5.13334)
		(stroke
			(width 0.0635)
			(type default)
		)
		(layer "In2.Cu")
	)
	(gr_line
		(start 111.48187 5.206492)
		(end 111.58474 5.206492)
		(stroke
			(width 0.0635)
			(type default)
		)
		(layer "In2.Cu")
	)
	(gr_line
		(start 111.683546 -25.965404)
		(end 111.869982 -25.36698)
		(stroke
			(width 0.0635)
			(type default)
		)
		(layer "In2.Cu")
	)
	(gr_line
		(start 111.726726 -30.20822)
		(end 111.72698 -30.20822)
		(stroke
			(width 0.0635)
			(type default)
		)
		(layer "In2.Cu")
	)
	(gr_line
		(start 111.778796 -0.564642)
		(end 111.805974 -0.559816)
		(stroke
			(width 0.0635)
			(type default)
		)
		(layer "In2.Cu")
	)
	(gr_line
		(start 111.805974 -0.559816)
		(end 111.82858 -0.544068)
		(stroke
			(width 0.0635)
			(type default)
		)
		(layer "In2.Cu")
	)
	(gr_line
		(start 111.81969 3.560064)
		(end 111.830866 3.567938)
		(stroke
			(width 0.0635)
			(type default)
		)
		(layer "In2.Cu")
	)
	(gr_line
		(start 111.830866 3.567938)
		(end 111.83874 3.579114)
		(stroke
			(width 0.0635)
			(type default)
		)
		(layer "In2.Cu")
	)
	(gr_line
		(start 112.024922 -1.546098)
		(end 112.0521 -1.541272)
		(stroke
			(width 0.0635)
			(type default)
		)
		(layer "In2.Cu")
	)
	(gr_line
		(start 112.0521 -1.541272)
		(end 112.074706 -1.525524)
		(stroke
			(width 0.0635)
			(type default)
		)
		(layer "In2.Cu")
	)
	(gr_line
		(start 112.079532 -34.070036)
		(end 112.456976 -33.314132)
		(stroke
			(width 0.0635)
			(type default)
		)
		(layer "In2.Cu")
	)
	(gr_line
		(start 112.140238 6.081522)
		(end 112.141254 6.088888)
		(stroke
			(width 0.0635)
			(type default)
		)
		(layer "In2.Cu")
	)
	(gr_line
		(start 112.140238 6.081522)
		(end 112.141508 6.074156)
		(stroke
			(width 0.0635)
			(type default)
		)
		(layer "In2.Cu")
	)
	(gr_line
		(start 112.141254 6.089396)
		(end 112.141254 6.089142)
		(stroke
			(width 0.0635)
			(type default)
		)
		(layer "In2.Cu")
	)
	(gr_arc
		(start 112.211866 7.269988)
		(mid 112.10559 7.572743)
		(end 111.833406 7.742682)
		(stroke
			(width 0.0635)
			(type default)
		)
		(layer "In2.Cu")
	)
	(gr_line
		(start 112.227868 4.966716)
		(end 112.2299 4.9784)
		(stroke
			(width 0.0635)
			(type default)
		)
		(layer "In2.Cu")
	)
	(gr_line
		(start 112.2299 4.990846)
		(end 112.2299 4.9784)
		(stroke
			(width 0.0635)
			(type default)
		)
		(layer "In2.Cu")
	)
	(gr_line
		(start 112.366806 -2.4638)
		(end 112.393984 -2.458974)
		(stroke
			(width 0.0635)
			(type default)
		)
		(layer "In2.Cu")
	)
	(gr_line
		(start 112.393984 -2.458974)
		(end 112.41659 -2.443226)
		(stroke
			(width 0.0635)
			(type default)
		)
		(layer "In2.Cu")
	)
	(gr_line
		(start 112.41278 4.398518)
		(end 112.428528 4.421124)
		(stroke
			(width 0.0635)
			(type default)
		)
		(layer "In2.Cu")
	)
	(gr_line
		(start 112.428528 4.421124)
		(end 112.433354 4.448302)
		(stroke
			(width 0.0635)
			(type default)
		)
		(layer "In2.Cu")
	)
	(gr_arc
		(start 112.456976 -33.314132)
		(mid 112.463773 -33.217258)
		(end 112.40008 -33.143952)
		(stroke
			(width 0.0635)
			(type default)
		)
		(layer "In2.Cu")
	)
	(gr_line
		(start 112.522 4.9784)
		(end 112.517682 4.927854)
		(stroke
			(width 0.0635)
			(type default)
		)
		(layer "In2.Cu")
	)
	(gr_arc
		(start 112.531144 -32.882586)
		(mid 112.6282 -32.889527)
		(end 112.701578 -32.82569)
		(stroke
			(width 0.0635)
			(type default)
		)
		(layer "In2.Cu")
	)
	(gr_line
		(start 112.66678 2.86385)
		(end 112.677956 2.871724)
		(stroke
			(width 0.0635)
			(type default)
		)
		(layer "In2.Cu")
	)
	(gr_line
		(start 112.677956 2.871724)
		(end 112.68583 2.8829)
		(stroke
			(width 0.0635)
			(type default)
		)
		(layer "In2.Cu")
	)
	(gr_line
		(start 112.701578 -32.82569)
		(end 113.080292 -32.069786)
		(stroke
			(width 0.0635)
			(type default)
		)
		(layer "In2.Cu")
	)
	(gr_line
		(start 112.751616 -21.559012)
		(end 112.753902 -21.5519)
		(stroke
			(width 0.0635)
			(type default)
		)
		(layer "In2.Cu")
	)
	(gr_line
		(start 112.753902 -21.5519)
		(end 112.757966 -21.546058)
		(stroke
			(width 0.0635)
			(type default)
		)
		(layer "In2.Cu")
	)
	(gr_arc
		(start 112.849406 7.742682)
		(mid 112.603882 7.567358)
		(end 112.503966 7.282688)
		(stroke
			(width 0.0635)
			(type default)
		)
		(layer "In2.Cu")
	)
	(gr_line
		(start 113.001298 -26.743152)
		(end 113.138712 -26.126948)
		(stroke
			(width 0.0635)
			(type default)
		)
		(layer "In2.Cu")
	)
	(gr_line
		(start 113.183416 -27.792426)
		(end 113.192052 -27.772614)
		(stroke
			(width 0.0635)
			(type default)
		)
		(layer "In2.Cu")
	)
	(gr_line
		(start 113.205006 -14.379956)
		(end 113.219484 -14.351254)
		(stroke
			(width 0.0635)
			(type default)
		)
		(layer "In2.Cu")
	)
	(gr_line
		(start 113.238788 -25.680162)
		(end 113.37544 -25.067514)
		(stroke
			(width 0.0635)
			(type default)
		)
		(layer "In2.Cu")
	)
	(gr_line
		(start 113.280952 -26.841958)
		(end 113.472214 -26.720546)
		(stroke
			(width 0.0635)
			(type default)
		)
		(layer "In2.Cu")
	)
	(gr_line
		(start 113.43386 -26.157428)
		(end 113.555272 -26.34869)
		(stroke
			(width 0.0635)
			(type default)
		)
		(layer "In2.Cu")
	)
	(gr_line
		(start 113.472214 -26.720546)
		(end 113.555272 -26.34869)
		(stroke
			(width 0.0635)
			(type default)
		)
		(layer "In2.Cu")
	)
	(gr_line
		(start 113.517934 -25.781)
		(end 113.708942 -25.659588)
		(stroke
			(width 0.0635)
			(type default)
		)
		(layer "In2.Cu")
	)
	(gr_arc
		(start 113.538 4.755642)
		(mid 113.43467 5.053196)
		(end 113.15954 5.206492)
		(stroke
			(width 0.0635)
			(type default)
		)
		(layer "In2.Cu")
	)
	(gr_line
		(start 113.670588 -25.09647)
		(end 113.792 -25.287732)
		(stroke
			(width 0.0635)
			(type default)
		)
		(layer "In2.Cu")
	)
	(gr_line
		(start 113.708942 -25.659588)
		(end 113.792 -25.287732)
		(stroke
			(width 0.0635)
			(type default)
		)
		(layer "In2.Cu")
	)
	(gr_line
		(start 113.764314 4.422902)
		(end 113.780062 4.445508)
		(stroke
			(width 0.0635)
			(type default)
		)
		(layer "In2.Cu")
	)
	(gr_line
		(start 113.780062 4.445508)
		(end 113.784888 4.472686)
		(stroke
			(width 0.0635)
			(type default)
		)
		(layer "In2.Cu")
	)
	(gr_line
		(start 113.832386 4.741672)
		(end 113.849404 4.8387)
		(stroke
			(width 0.0635)
			(type default)
		)
		(layer "In2.Cu")
	)
	(gr_line
		(start 113.849404 4.85267)
		(end 113.849404 4.8387)
		(stroke
			(width 0.0635)
			(type default)
		)
		(layer "In2.Cu")
	)
	(gr_line
		(start 113.849404 4.85267)
		(end 114.17554 5.206492)
		(stroke
			(width 0.0635)
			(type default)
		)
		(layer "In2.Cu")
	)
	(gr_line
		(start 113.90757 -10.29589)
		(end 113.909094 -10.291318)
		(stroke
			(width 0.0635)
			(type default)
		)
		(layer "In2.Cu")
	)
	(gr_line
		(start 114.268758 -21.06549)
		(end 114.273076 -21.046186)
		(stroke
			(width 0.0635)
			(type default)
		)
		(layer "In2.Cu")
	)
	(gr_line
		(start 114.273076 -21.046186)
		(end 114.284252 -21.030184)
		(stroke
			(width 0.0635)
			(type default)
		)
		(layer "In2.Cu")
	)
	(gr_line
		(start 114.378486 -3.123692)
		(end 114.405664 -3.118866)
		(stroke
			(width 0.0635)
			(type default)
		)
		(layer "In2.Cu")
	)
	(gr_line
		(start 114.405664 -3.118866)
		(end 114.42827 -3.103118)
		(stroke
			(width 0.0635)
			(type default)
		)
		(layer "In2.Cu")
	)
	(gr_line
		(start 114.424206 7.742682)
		(end 114.751358 7.41553)
		(stroke
			(width 0.0635)
			(type default)
		)
		(layer "In2.Cu")
	)
	(gr_line
		(start 114.437922 -8.580374)
		(end 114.442748 -8.565134)
		(stroke
			(width 0.0635)
			(type default)
		)
		(layer "In2.Cu")
	)
	(gr_line
		(start 114.442748 -8.565134)
		(end 114.4524 -8.552942)
		(stroke
			(width 0.0635)
			(type default)
		)
		(layer "In2.Cu")
	)
	(gr_line
		(start 114.522504 2.623058)
		(end 114.53368 2.630932)
		(stroke
			(width 0.0635)
			(type default)
		)
		(layer "In2.Cu")
	)
	(gr_line
		(start 114.53368 2.630932)
		(end 114.541554 2.642108)
		(stroke
			(width 0.0635)
			(type default)
		)
		(layer "In2.Cu")
	)
	(gr_line
		(start 114.572288 -4.149344)
		(end 114.599466 -4.144518)
		(stroke
			(width 0.0635)
			(type default)
		)
		(layer "In2.Cu")
	)
	(gr_line
		(start 114.599466 -4.144518)
		(end 114.622072 -4.12877)
		(stroke
			(width 0.0635)
			(type default)
		)
		(layer "In2.Cu")
	)
	(gr_arc
		(start 114.802666 7.291578)
		(mid 114.789354 7.358662)
		(end 114.751358 7.41553)
		(stroke
			(width 0.0635)
			(type default)
		)
		(layer "In2.Cu")
	)
	(gr_line
		(start 114.84737 3.07848)
		(end 114.863118 3.101086)
		(stroke
			(width 0.0635)
			(type default)
		)
		(layer "In2.Cu")
	)
	(gr_line
		(start 114.863118 3.101086)
		(end 114.867944 3.128264)
		(stroke
			(width 0.0635)
			(type default)
		)
		(layer "In2.Cu")
	)
	(gr_line
		(start 115.050824 1.712214)
		(end 115.062 1.720088)
		(stroke
			(width 0.0635)
			(type default)
		)
		(layer "In2.Cu")
	)
	(gr_line
		(start 115.062 1.720088)
		(end 115.069874 1.731264)
		(stroke
			(width 0.0635)
			(type default)
		)
		(layer "In2.Cu")
	)
	(gr_line
		(start 115.187222 -7.600442)
		(end 115.189 -7.59968)
		(stroke
			(width 0.0635)
			(type default)
		)
		(layer "In2.Cu")
	)
	(gr_line
		(start 115.189 -7.59968)
		(end 115.189762 -7.598156)
		(stroke
			(width 0.0635)
			(type default)
		)
		(layer "In2.Cu")
	)
	(gr_line
		(start 115.189762 -7.598156)
		(end 115.192302 -7.593838)
		(stroke
			(width 0.0635)
			(type default)
		)
		(layer "In2.Cu")
	)
	(gr_line
		(start 115.404392 -7.797038)
		(end 115.434364 -7.758176)
		(stroke
			(width 0.0635)
			(type default)
		)
		(layer "In2.Cu")
	)
	(gr_arc
		(start 115.440206 7.742682)
		(mid 115.194682 7.567358)
		(end 115.094766 7.282688)
		(stroke
			(width 0.0635)
			(type default)
		)
		(layer "In2.Cu")
	)
	(gr_line
		(start 115.442746 -7.744968)
		(end 115.443508 -7.743444)
		(stroke
			(width 0.0635)
			(type default)
		)
		(layer "In2.Cu")
	)
	(gr_line
		(start 115.908074 -6.348476)
		(end 115.922298 -6.323838)
		(stroke
			(width 0.0635)
			(type default)
		)
		(layer "In2.Cu")
	)
	(gr_line
		(start 115.922298 -6.323838)
		(end 115.945158 -6.307836)
		(stroke
			(width 0.0635)
			(type default)
		)
		(layer "In2.Cu")
	)
	(gr_line
		(start 116.120418 4.484878)
		(end 116.123974 4.50469)
		(stroke
			(width 0.0635)
			(type default)
		)
		(layer "In2.Cu")
	)
	(gr_line
		(start 116.123974 4.50469)
		(end 116.128546 4.744212)
		(stroke
			(width 0.0635)
			(type default)
		)
		(layer "In2.Cu")
	)
	(gr_arc
		(start 116.1288 4.755388)
		(mid 116.025518 5.053046)
		(end 115.75034 5.206492)
		(stroke
			(width 0.0635)
			(type default)
		)
		(layer "In2.Cu")
	)
	(gr_line
		(start 116.197634 1.36144)
		(end 116.20881 1.369314)
		(stroke
			(width 0.0635)
			(type default)
		)
		(layer "In2.Cu")
	)
	(gr_line
		(start 116.206016 3.35407)
		(end 116.221764 3.376676)
		(stroke
			(width 0.0635)
			(type default)
		)
		(layer "In2.Cu")
	)
	(gr_line
		(start 116.20881 1.369314)
		(end 116.216684 1.38049)
		(stroke
			(width 0.0635)
			(type default)
		)
		(layer "In2.Cu")
	)
	(gr_line
		(start 116.221764 3.376676)
		(end 116.22659 3.403854)
		(stroke
			(width 0.0635)
			(type default)
		)
		(layer "In2.Cu")
	)
	(gr_line
		(start 116.411756 4.454652)
		(end 116.420646 4.736846)
		(stroke
			(width 0.0635)
			(type default)
		)
		(layer "In2.Cu")
	)
	(gr_arc
		(start 116.76634 5.206492)
		(mid 116.520816 5.031168)
		(end 116.4209 4.746498)
		(stroke
			(width 0.0635)
			(type default)
		)
		(layer "In2.Cu")
	)
	(gr_line
		(start 117.132608 -1.209802)
		(end 117.143784 -1.201928)
		(stroke
			(width 0.0635)
			(type default)
		)
		(layer "In2.Cu")
	)
	(gr_line
		(start 117.143784 -1.201928)
		(end 117.151658 -1.190752)
		(stroke
			(width 0.0635)
			(type default)
		)
		(layer "In2.Cu")
	)
	(gr_line
		(start 117.31498 0.98679)
		(end 117.326156 0.994664)
		(stroke
			(width 0.0635)
			(type default)
		)
		(layer "In2.Cu")
	)
	(gr_line
		(start 117.326156 0.994664)
		(end 117.33403 1.00584)
		(stroke
			(width 0.0635)
			(type default)
		)
		(layer "In2.Cu")
	)
	(gr_arc
		(start 117.393466 7.291578)
		(mid 117.290186 7.589232)
		(end 117.015006 7.742682)
		(stroke
			(width 0.0635)
			(type default)
		)
		(layer "In2.Cu")
	)
	(gr_line
		(start 117.571012 3.313684)
		(end 117.58676 3.33629)
		(stroke
			(width 0.0635)
			(type default)
		)
		(layer "In2.Cu")
	)
	(gr_line
		(start 117.58676 3.33629)
		(end 117.591586 3.363468)
		(stroke
			(width 0.0635)
			(type default)
		)
		(layer "In2.Cu")
	)
	(gr_line
		(start 117.648736 -10.882122)
		(end 117.650006 -10.874756)
		(stroke
			(width 0.0635)
			(type default)
		)
		(layer "In2.Cu")
	)
	(gr_line
		(start 117.731794 -1.594358)
		(end 117.734334 -1.594358)
		(stroke
			(width 0.0635)
			(type default)
		)
		(layer "In2.Cu")
	)
	(gr_line
		(start 117.734334 -1.594358)
		(end 117.735604 -1.593088)
		(stroke
			(width 0.0635)
			(type default)
		)
		(layer "In2.Cu")
	)
	(gr_line
		(start 117.735604 -1.593088)
		(end 117.740938 -1.588262)
		(stroke
			(width 0.0635)
			(type default)
		)
		(layer "In2.Cu")
	)
	(gr_line
		(start 117.877336 -1.84912)
		(end 117.925088 -1.815592)
		(stroke
			(width 0.0635)
			(type default)
		)
		(layer "In2.Cu")
	)
	(gr_line
		(start 117.90934 -11.023346)
		(end 117.924072 -11.002518)
		(stroke
			(width 0.0635)
			(type default)
		)
		(layer "In2.Cu")
	)
	(gr_line
		(start 117.924072 -11.002518)
		(end 117.944392 -10.973308)
		(stroke
			(width 0.0635)
			(type default)
		)
		(layer "In2.Cu")
	)
	(gr_line
		(start 117.93347 -1.808226)
		(end 117.93347 -1.80975)
		(stroke
			(width 0.0635)
			(type default)
		)
		(layer "In2.Cu")
	)
	(gr_line
		(start 117.93347 -1.808226)
		(end 117.93474 -1.806956)
		(stroke
			(width 0.0635)
			(type default)
		)
		(layer "In2.Cu")
	)
	(gr_line
		(start 117.944392 -10.90168)
		(end 117.944392 -10.973308)
		(stroke
			(width 0.0635)
			(type default)
		)
		(layer "In2.Cu")
	)
	(gr_arc
		(start 118.031006 7.742682)
		(mid 117.785482 7.567358)
		(end 117.685566 7.282688)
		(stroke
			(width 0.0635)
			(type default)
		)
		(layer "In2.Cu")
	)
	(gr_line
		(start 118.245382 -7.493508)
		(end 118.250208 -7.46633)
		(stroke
			(width 0.0635)
			(type default)
		)
		(layer "In2.Cu")
	)
	(gr_line
		(start 118.250208 -7.46633)
		(end 118.265956 -7.443724)
		(stroke
			(width 0.0635)
			(type default)
		)
		(layer "In2.Cu")
	)
	(gr_line
		(start 118.355364 -4.97713)
		(end 118.36654 -4.969256)
		(stroke
			(width 0.0635)
			(type default)
		)
		(layer "In2.Cu")
	)
	(gr_line
		(start 118.36654 -4.969256)
		(end 118.374414 -4.95808)
		(stroke
			(width 0.0635)
			(type default)
		)
		(layer "In2.Cu")
	)
	(gr_line
		(start 118.707408 4.444492)
		(end 118.71071 4.46278)
		(stroke
			(width 0.0635)
			(type default)
		)
		(layer "In2.Cu")
	)
	(gr_line
		(start 118.71071 4.46278)
		(end 118.717822 4.692396)
		(stroke
			(width 0.0635)
			(type default)
		)
		(layer "In2.Cu")
	)
	(gr_line
		(start 118.740174 3.012948)
		(end 118.755922 3.035554)
		(stroke
			(width 0.0635)
			(type default)
		)
		(layer "In2.Cu")
	)
	(gr_line
		(start 118.755922 3.035554)
		(end 118.760748 3.062732)
		(stroke
			(width 0.0635)
			(type default)
		)
		(layer "In2.Cu")
	)
	(gr_line
		(start 118.812564 -11.641328)
		(end 118.828312 -11.618722)
		(stroke
			(width 0.0635)
			(type default)
		)
		(layer "In2.Cu")
	)
	(gr_line
		(start 118.828312 -11.618722)
		(end 118.833138 -11.591544)
		(stroke
			(width 0.0635)
			(type default)
		)
		(layer "In2.Cu")
	)
	(gr_line
		(start 118.860316 -2.51206)
		(end 118.871492 -2.504186)
		(stroke
			(width 0.0635)
			(type default)
		)
		(layer "In2.Cu")
	)
	(gr_line
		(start 118.871492 -2.504186)
		(end 118.879366 -2.49301)
		(stroke
			(width 0.0635)
			(type default)
		)
		(layer "In2.Cu")
	)
	(gr_line
		(start 118.998492 4.412996)
		(end 118.998492 4.412742)
		(stroke
			(width 0.0635)
			(type default)
		)
		(layer "In2.Cu")
	)
	(gr_line
		(start 118.998492 4.412996)
		(end 119.009668 4.680458)
		(stroke
			(width 0.0635)
			(type default)
		)
		(layer "In2.Cu")
	)
	(gr_line
		(start 119.18315 -7.923276)
		(end 119.187976 -7.896098)
		(stroke
			(width 0.0635)
			(type default)
		)
		(layer "In2.Cu")
	)
	(gr_line
		(start 119.187976 -7.896098)
		(end 119.203724 -7.873492)
		(stroke
			(width 0.0635)
			(type default)
		)
		(layer "In2.Cu")
	)
	(gr_arc
		(start 119.35714 5.206492)
		(mid 119.111616 5.031168)
		(end 119.0117 4.746498)
		(stroke
			(width 0.0635)
			(type default)
		)
		(layer "In2.Cu")
	)
	(gr_line
		(start 119.67972 -11.006074)
		(end 119.686832 -10.966196)
		(stroke
			(width 0.0635)
			(type default)
		)
		(layer "In2.Cu")
	)
	(gr_line
		(start 119.686832 -10.966196)
		(end 119.695722 -10.91565)
		(stroke
			(width 0.0635)
			(type default)
		)
		(layer "In2.Cu")
	)
	(gr_line
		(start 119.786146 -12.018264)
		(end 119.801894 -11.995658)
		(stroke
			(width 0.0635)
			(type default)
		)
		(layer "In2.Cu")
	)
	(gr_line
		(start 119.801894 -11.995658)
		(end 119.80672 -11.96848)
		(stroke
			(width 0.0635)
			(type default)
		)
		(layer "In2.Cu")
	)
	(gr_line
		(start 119.811038 2.60731)
		(end 119.825008 2.627376)
		(stroke
			(width 0.0635)
			(type default)
		)
		(layer "In2.Cu")
	)
	(gr_line
		(start 119.825008 2.627376)
		(end 119.829326 2.650744)
		(stroke
			(width 0.0635)
			(type default)
		)
		(layer "In2.Cu")
	)
	(gr_line
		(start 119.967502 -11.056874)
		(end 119.989854 -10.930382)
		(stroke
			(width 0.0635)
			(type default)
		)
		(layer "In2.Cu")
	)
	(gr_arc
		(start 119.984266 7.291578)
		(mid 119.880986 7.589232)
		(end 119.605806 7.742682)
		(stroke
			(width 0.0635)
			(type default)
		)
		(layer "In2.Cu")
	)
	(gr_line
		(start 120.187974 -8.12292)
		(end 120.1928 -8.095742)
		(stroke
			(width 0.0635)
			(type default)
		)
		(layer "In2.Cu")
	)
	(gr_line
		(start 120.1928 -8.095742)
		(end 120.208548 -8.073136)
		(stroke
			(width 0.0635)
			(type default)
		)
		(layer "In2.Cu")
	)
	(gr_arc
		(start 120.621806 7.742682)
		(mid 120.36129 7.554674)
		(end 120.285256 7.242556)
		(stroke
			(width 0.0635)
			(type default)
		)
		(layer "In2.Cu")
	)
	(gr_line
		(start 120.856248 -12.153392)
		(end 120.871996 -12.130786)
		(stroke
			(width 0.0635)
			(type default)
		)
		(layer "In2.Cu")
	)
	(gr_line
		(start 120.871996 -12.130786)
		(end 120.876822 -12.103608)
		(stroke
			(width 0.0635)
			(type default)
		)
		(layer "In2.Cu")
	)
	(gr_line
		(start 121.255028 -8.274304)
		(end 121.259854 -8.247126)
		(stroke
			(width 0.0635)
			(type default)
		)
		(layer "In2.Cu")
	)
	(gr_line
		(start 121.259854 -8.247126)
		(end 121.275602 -8.22452)
		(stroke
			(width 0.0635)
			(type default)
		)
		(layer "In2.Cu")
	)
	(gr_arc
		(start 121.3104 4.75742)
		(mid 121.20656 5.053955)
		(end 120.93194 5.206492)
		(stroke
			(width 0.0635)
			(type default)
		)
		(layer "In2.Cu")
	)
	(gr_line
		(start 121.310654 4.572762)
		(end 121.311162 4.572254)
		(stroke
			(width 0.0635)
			(type default)
		)
		(layer "In2.Cu")
	)
	(gr_line
		(start 121.310654 4.573016)
		(end 121.310654 4.572762)
		(stroke
			(width 0.0635)
			(type default)
		)
		(layer "In2.Cu")
	)
	(gr_line
		(start 121.310908 4.567936)
		(end 121.311162 4.571492)
		(stroke
			(width 0.0635)
			(type default)
		)
		(layer "In2.Cu")
	)
	(gr_line
		(start 121.311162 4.572254)
		(end 121.311162 4.571492)
		(stroke
			(width 0.0635)
			(type default)
		)
		(layer "In2.Cu")
	)
	(gr_line
		(start 121.451116 3.06324)
		(end 121.474484 3.096768)
		(stroke
			(width 0.0635)
			(type default)
		)
		(layer "In2.Cu")
	)
	(gr_line
		(start 121.474484 3.096768)
		(end 121.47804 3.137154)
		(stroke
			(width 0.0635)
			(type default)
		)
		(layer "In2.Cu")
	)
	(gr_line
		(start 121.602246 4.546854)
		(end 121.602246 4.546092)
		(stroke
			(width 0.0635)
			(type default)
		)
		(layer "In2.Cu")
	)
	(gr_line
		(start 121.602246 4.546854)
		(end 121.603008 4.547616)
		(stroke
			(width 0.0635)
			(type default)
		)
		(layer "In2.Cu")
	)
	(gr_line
		(start 121.602754 4.747006)
		(end 121.602754 4.651756)
		(stroke
			(width 0.0635)
			(type default)
		)
		(layer "In2.Cu")
	)
	(gr_line
		(start 121.603008 4.586478)
		(end 121.603008 4.547616)
		(stroke
			(width 0.0635)
			(type default)
		)
		(layer "In2.Cu")
	)
	(gr_line
		(start 122.403616 2.539746)
		(end 122.41784 2.560066)
		(stroke
			(width 0.0635)
			(type default)
		)
		(layer "In2.Cu")
	)
	(gr_line
		(start 122.41784 2.560066)
		(end 122.422412 2.584196)
		(stroke
			(width 0.0635)
			(type default)
		)
		(layer "In2.Cu")
	)
	(gr_arc
		(start 122.575066 7.291578)
		(mid 122.471924 7.589405)
		(end 122.196606 7.742682)
		(stroke
			(width 0.0635)
			(type default)
		)
		(layer "In2.Cu")
	)
	(gr_line
		(start 122.868436 5.60324)
		(end 122.868436 5.602986)
		(stroke
			(width 0.0635)
			(type default)
		)
		(layer "In2.Cu")
	)
	(gr_arc
		(start 122.868436 6.251194)
		(mid 122.870151 6.267919)
		(end 122.870722 6.284722)
		(stroke
			(width 0.0635)
			(type default)
		)
		(layer "In2.Cu")
	)
	(gr_arc
		(start 123.212606 7.742682)
		(mid 122.967092 7.567354)
		(end 122.867166 7.282688)
		(stroke
			(width 0.0635)
			(type default)
		)
		(layer "In2.Cu")
	)
	(gr_line
		(start 123.917964 2.958846)
		(end 123.933712 2.981452)
		(stroke
			(width 0.0635)
			(type default)
		)
		(layer "In2.Cu")
	)
	(gr_line
		(start 123.933712 2.981452)
		(end 123.938538 3.00863)
		(stroke
			(width 0.0635)
			(type default)
		)
		(layer "In2.Cu")
	)
	(gr_arc
		(start 124.1933 4.746244)
		(mid 124.193428 4.747387)
		(end 124.193554 4.74853)
		(stroke
			(width 0.0635)
			(type default)
		)
		(layer "In2.Cu")
	)
	(gr_arc
		(start 124.53874 5.206492)
		(mid 124.293884 5.031979)
		(end 124.193554 4.74853)
		(stroke
			(width 0.0635)
			(type default)
		)
		(layer "In2.Cu")
	)
	(gr_line
		(start 124.556012 1.85166)
		(end 124.562108 1.885696)
		(stroke
			(width 0.0635)
			(type default)
		)
		(layer "In2.Cu")
	)
	(gr_line
		(start 124.562108 1.885696)
		(end 124.56287 1.886712)
		(stroke
			(width 0.0635)
			(type default)
		)
		(layer "In2.Cu")
	)
	(gr_line
		(start 124.742956 1.296416)
		(end 124.758704 1.319022)
		(stroke
			(width 0.0635)
			(type default)
		)
		(layer "In2.Cu")
	)
	(gr_line
		(start 124.758704 1.319022)
		(end 124.76353 1.3462)
		(stroke
			(width 0.0635)
			(type default)
		)
		(layer "In2.Cu")
	)
	(gr_line
		(start 124.84608 1.79959)
		(end 124.84608 1.799336)
		(stroke
			(width 0.0635)
			(type default)
		)
		(layer "In2.Cu")
	)
	(gr_arc
		(start 125.165866 7.291578)
		(mid 125.062586 7.589232)
		(end 124.787406 7.742682)
		(stroke
			(width 0.0635)
			(type default)
		)
		(layer "In2.Cu")
	)
	(gr_arc
		(start 125.165866 7.291578)
		(mid 125.166184 6.991984)
		(end 125.167136 6.692392)
		(stroke
			(width 0.0635)
			(type default)
		)
		(layer "In2.Cu")
	)
	(gr_line
		(start 125.459236 7.07263)
		(end 125.459236 6.987032)
		(stroke
			(width 0.0635)
			(type default)
		)
		(layer "In2.Cu")
	)
	(gr_arc
		(start 125.58649 7.453884)
		(mid 125.491889 7.273595)
		(end 125.459236 7.07263)
		(stroke
			(width 0.0635)
			(type default)
		)
		(layer "In2.Cu")
	)
	(gr_line
		(start 125.58649 7.453884)
		(end 125.803406 7.742682)
		(stroke
			(width 0.0635)
			(type default)
		)
		(layer "In2.Cu")
	)
	(gr_line
		(start 126.28245 1.725676)
		(end 126.297944 1.747266)
		(stroke
			(width 0.0635)
			(type default)
		)
		(layer "In2.Cu")
	)
	(gr_line
		(start 126.297944 1.747266)
		(end 126.30277 1.774444)
		(stroke
			(width 0.0635)
			(type default)
		)
		(layer "In2.Cu")
	)
	(gr_line
		(start 126.483618 4.484878)
		(end 126.487174 4.50469)
		(stroke
			(width 0.0635)
			(type default)
		)
		(layer "In2.Cu")
	)
	(gr_line
		(start 126.487174 4.50469)
		(end 126.491746 4.744212)
		(stroke
			(width 0.0635)
			(type default)
		)
		(layer "In2.Cu")
	)
	(gr_arc
		(start 126.492 4.755388)
		(mid 126.388718 5.053046)
		(end 126.11354 5.206492)
		(stroke
			(width 0.0635)
			(type default)
		)
		(layer "In2.Cu")
	)
	(gr_line
		(start 126.774956 4.454652)
		(end 126.783846 4.736846)
		(stroke
			(width 0.0635)
			(type default)
		)
		(layer "In2.Cu")
	)
	(gr_arc
		(start 127.12954 5.206492)
		(mid 126.884016 5.031168)
		(end 126.7841 4.746498)
		(stroke
			(width 0.0635)
			(type default)
		)
		(layer "In2.Cu")
	)
	(gr_line
		(start 127.424688 1.722882)
		(end 127.440436 1.745488)
		(stroke
			(width 0.0635)
			(type default)
		)
		(layer "In2.Cu")
	)
	(gr_line
		(start 127.440436 1.745488)
		(end 127.446278 1.775714)
		(stroke
			(width 0.0635)
			(type default)
		)
		(layer "In2.Cu")
	)
	(gr_arc
		(start 127.756666 7.291578)
		(mid 127.653386 7.589232)
		(end 127.378206 7.742682)
		(stroke
			(width 0.0635)
			(type default)
		)
		(layer "In2.Cu")
	)
	(gr_arc
		(start 127.756666 7.291578)
		(mid 127.756984 6.991984)
		(end 127.757936 6.692392)
		(stroke
			(width 0.0635)
			(type default)
		)
		(layer "In2.Cu")
	)
	(gr_line
		(start 128.050036 7.07263)
		(end 128.050036 6.987032)
		(stroke
			(width 0.0635)
			(type default)
		)
		(layer "In2.Cu")
	)
	(gr_arc
		(start 128.17729 7.453884)
		(mid 128.082689 7.273595)
		(end 128.050036 7.07263)
		(stroke
			(width 0.0635)
			(type default)
		)
		(layer "In2.Cu")
	)
	(gr_line
		(start 128.17729 7.453884)
		(end 128.394206 7.742682)
		(stroke
			(width 0.0635)
			(type default)
		)
		(layer "In2.Cu")
	)
	(gr_line
		(start 128.42113 3.073146)
		(end 128.425956 3.100324)
		(stroke
			(width 0.0635)
			(type default)
		)
		(layer "In2.Cu")
	)
	(gr_line
		(start 128.423924 1.471168)
		(end 128.439672 1.493774)
		(stroke
			(width 0.0635)
			(type default)
		)
		(layer "In2.Cu")
	)
	(gr_line
		(start 128.425956 3.100324)
		(end 128.441704 3.12293)
		(stroke
			(width 0.0635)
			(type default)
		)
		(layer "In2.Cu")
	)
	(gr_line
		(start 128.439672 1.493774)
		(end 128.444498 1.520952)
		(stroke
			(width 0.0635)
			(type default)
		)
		(layer "In2.Cu")
	)
	(gr_line
		(start 128.70434 5.206492)
		(end 129.035302 4.87553)
		(stroke
			(width 0.0635)
			(type default)
		)
		(layer "In2.Cu")
	)
	(gr_arc
		(start 129.0828 4.755642)
		(mid 129.071472 4.82051)
		(end 129.035302 4.87553)
		(stroke
			(width 0.0635)
			(type default)
		)
		(layer "In2.Cu")
	)
	(gr_line
		(start 129.25171 3.769868)
		(end 129.267458 3.792474)
		(stroke
			(width 0.0635)
			(type default)
		)
		(layer "In2.Cu")
	)
	(gr_line
		(start 129.267458 3.792474)
		(end 129.272284 3.819652)
		(stroke
			(width 0.0635)
			(type default)
		)
		(layer "In2.Cu")
	)
	(gr_arc
		(start 129.72034 5.206492)
		(mid 129.474839 5.031139)
		(end 129.3749 4.746498)
		(stroke
			(width 0.0635)
			(type default)
		)
		(layer "In2.Cu")
	)
	(gr_line
		(start 0 -31.785814)
		(end 0 -0.999998)
		(stroke
			(width 1.524)
			(type default)
		)
		(layer "In4.Cu")
	)
	(gr_arc
		(start 0 -31.785814)
		(mid 0.076081 -32.168518)
		(end 0.292862 -32.49295)
		(stroke
			(width 1.524)
			(type default)
		)
		(layer "In4.Cu")
	)
	(gr_arc
		(start 0.999998 0)
		(mid 0.292893 -0.292893)
		(end 0 -0.999998)
		(stroke
			(width 1.524)
			(type default)
		)
		(layer "In4.Cu")
	)
	(gr_line
		(start 0.999998 0)
		(end 3.885692 0)
		(stroke
			(width 1.524)
			(type default)
		)
		(layer "In4.Cu")
	)
	(gr_line
		(start 2.707132 -34.90722)
		(end 0.292862 -32.49295)
		(stroke
			(width 1.524)
			(type default)
		)
		(layer "In4.Cu")
	)
	(gr_arc
		(start 2.707132 -34.90722)
		(mid 3.031582 -35.123959)
		(end 3.414268 -35.200082)
		(stroke
			(width 1.524)
			(type default)
		)
		(layer "In4.Cu")
	)
	(gr_arc
		(start 4.592828 -0.292862)
		(mid 4.268379 -0.076123)
		(end 3.885692 0)
		(stroke
			(width 1.524)
			(type default)
		)
		(layer "In4.Cu")
	)
	(gr_line
		(start 4.592828 -0.292862)
		(end 5.007102 -0.707136)
		(stroke
			(width 1.524)
			(type default)
		)
		(layer "In4.Cu")
	)
	(gr_arc
		(start 5.299964 -7.590028)
		(mid 6.999986 -9.29005)
		(end 8.700008 -7.590028)
		(stroke
			(width 1.524)
			(type default)
		)
		(layer "In4.Cu")
	)
	(gr_arc
		(start 5.299964 -1.414272)
		(mid 5.223886 -1.031566)
		(end 5.007102 -0.707136)
		(stroke
			(width 1.524)
			(type default)
		)
		(layer "In4.Cu")
	)
	(gr_line
		(start 5.299964 -1.414272)
		(end 5.299964 -7.590028)
		(stroke
			(width 1.524)
			(type default)
		)
		(layer "In4.Cu")
	)
	(gr_line
		(start 8.700008 -7.590028)
		(end 8.700008 -1.414272)
		(stroke
			(width 1.524)
			(type default)
		)
		(layer "In4.Cu")
	)
	(gr_arc
		(start 8.99287 -0.707136)
		(mid 8.776129 -1.031585)
		(end 8.700008 -1.414272)
		(stroke
			(width 1.524)
			(type default)
		)
		(layer "In4.Cu")
	)
	(gr_line
		(start 8.99287 -0.707136)
		(end 9.407144 -0.292862)
		(stroke
			(width 1.524)
			(type default)
		)
		(layer "In4.Cu")
	)
	(gr_arc
		(start 10.11428 0)
		(mid 9.73157 -0.076073)
		(end 9.407144 -0.292862)
		(stroke
			(width 1.524)
			(type default)
		)
		(layer "In4.Cu")
	)
	(gr_line
		(start 10.11428 0)
		(end 14.349984 0)
		(stroke
			(width 1.524)
			(type default)
		)
		(layer "In4.Cu")
	)
	(gr_arc
		(start 14.349984 0)
		(mid 14.491333 0.058549)
		(end 14.549882 0.199898)
		(stroke
			(width 1.524)
			(type default)
		)
		(layer "In4.Cu")
	)
	(gr_line
		(start 14.549882 0.199898)
		(end 14.549882 14.029944)
		(stroke
			(width 1.524)
			(type default)
		)
		(layer "In4.Cu")
	)
	(gr_line
		(start 14.549882 14.029944)
		(end 15.050008 14.53007)
		(stroke
			(width 1.524)
			(type default)
		)
		(layer "In4.Cu")
	)
	(gr_line
		(start 15.050008 14.53007)
		(end 40.679878 14.53007)
		(stroke
			(width 7.5946)
			(type default)
		)
		(layer "In4.Cu")
	)
	(gr_line
		(start 40.679878 14.53007)
		(end 41.180004 14.029944)
		(stroke
			(width 1.524)
			(type default)
		)
		(layer "In4.Cu")
	)
	(gr_arc
		(start 41.180004 9.329928)
		(mid 42.380154 8.129778)
		(end 43.58005 9.329928)
		(stroke
			(width 1.524)
			(type default)
		)
		(layer "In4.Cu")
	)
	(gr_line
		(start 41.180004 14.029944)
		(end 41.180004 9.329928)
		(stroke
			(width 1.524)
			(type default)
		)
		(layer "In4.Cu")
	)
	(gr_line
		(start 43.58005 9.329928)
		(end 43.58005 14.029944)
		(stroke
			(width 1.524)
			(type default)
		)
		(layer "In4.Cu")
	)
	(gr_line
		(start 43.58005 14.029944)
		(end 44.079922 14.53007)
		(stroke
			(width 1.524)
			(type default)
		)
		(layer "In4.Cu")
	)
	(gr_line
		(start 44.079922 14.53007)
		(end 98.49993 14.53007)
		(stroke
			(width 7.5946)
			(type default)
		)
		(layer "In4.Cu")
	)
	(gr_line
		(start 44.6024 -32.308546)
		(end 45.602906 -34.308542)
		(stroke
			(width 0.2)
			(type default)
		)
		(layer "In4.Cu")
	)
	(gr_line
		(start 44.6024 -11.988546)
		(end 45.602906 -13.988542)
		(stroke
			(width 0.2)
			(type default)
		)
		(layer "In4.Cu")
	)
	(gr_arc
		(start 45.556424 -31.831026)
		(mid 44.840652 -31.592774)
		(end 44.6024 -32.308546)
		(stroke
			(width 0.2)
			(type default)
		)
		(layer "In4.Cu")
	)
	(gr_arc
		(start 45.556424 -11.511026)
		(mid 44.840652 -11.272774)
		(end 44.6024 -11.988546)
		(stroke
			(width 0.2)
			(type default)
		)
		(layer "In4.Cu")
	)
	(gr_line
		(start 45.602906 -34.308542)
		(end 45.60316 -34.308542)
		(stroke
			(width 0.2)
			(type default)
		)
		(layer "In4.Cu")
	)
	(gr_line
		(start 45.602906 -27.808682)
		(end 46.602396 -29.808678)
		(stroke
			(width 0.2)
			(type default)
		)
		(layer "In4.Cu")
	)
	(gr_line
		(start 45.602906 -13.988542)
		(end 45.60316 -13.988542)
		(stroke
			(width 0.2)
			(type default)
		)
		(layer "In4.Cu")
	)
	(gr_line
		(start 45.602906 -7.488682)
		(end 46.602396 -9.488678)
		(stroke
			(width 0.2)
			(type default)
		)
		(layer "In4.Cu")
	)
	(gr_arc
		(start 45.60316 -34.308542)
		(mid 46.31878 -34.546997)
		(end 46.557184 -33.831276)
		(stroke
			(width 0.2)
			(type default)
		)
		(layer "In4.Cu")
	)
	(gr_line
		(start 45.60316 -27.808682)
		(end 45.602906 -27.808682)
		(stroke
			(width 0.2)
			(type default)
		)
		(layer "In4.Cu")
	)
	(gr_arc
		(start 45.60316 -13.988542)
		(mid 46.31878 -14.226997)
		(end 46.557184 -13.511276)
		(stroke
			(width 0.2)
			(type default)
		)
		(layer "In4.Cu")
	)
	(gr_line
		(start 45.60316 -7.488682)
		(end 45.602906 -7.488682)
		(stroke
			(width 0.2)
			(type default)
		)
		(layer "In4.Cu")
	)
	(gr_line
		(start 46.557184 -33.831276)
		(end 45.556424 -31.831026)
		(stroke
			(width 0.2)
			(type default)
		)
		(layer "In4.Cu")
	)
	(gr_arc
		(start 46.557184 -27.33167)
		(mid 45.841666 -27.093164)
		(end 45.60316 -27.808682)
		(stroke
			(width 0.2)
			(type default)
		)
		(layer "In4.Cu")
	)
	(gr_line
		(start 46.557184 -13.511276)
		(end 45.556424 -11.511026)
		(stroke
			(width 0.2)
			(type default)
		)
		(layer "In4.Cu")
	)
	(gr_arc
		(start 46.557184 -7.01167)
		(mid 45.841666 -6.773164)
		(end 45.60316 -7.488682)
		(stroke
			(width 0.2)
			(type default)
		)
		(layer "In4.Cu")
	)
	(gr_line
		(start 46.557438 -27.33167)
		(end 46.557184 -27.33167)
		(stroke
			(width 0.2)
			(type default)
		)
		(layer "In4.Cu")
	)
	(gr_line
		(start 46.557438 -7.01167)
		(end 46.557184 -7.01167)
		(stroke
			(width 0.2)
			(type default)
		)
		(layer "In4.Cu")
	)
	(gr_arc
		(start 46.602396 -29.808678)
		(mid 47.318066 -30.047616)
		(end 47.556674 -29.33192)
		(stroke
			(width 0.2)
			(type default)
		)
		(layer "In4.Cu")
	)
	(gr_arc
		(start 46.602396 -9.488678)
		(mid 47.318066 -9.727616)
		(end 47.556674 -9.01192)
		(stroke
			(width 0.2)
			(type default)
		)
		(layer "In4.Cu")
	)
	(gr_line
		(start 47.556674 -29.33192)
		(end 47.556928 -29.33192)
		(stroke
			(width 0.2)
			(type default)
		)
		(layer "In4.Cu")
	)
	(gr_line
		(start 47.556674 -9.01192)
		(end 47.556928 -9.01192)
		(stroke
			(width 0.2)
			(type default)
		)
		(layer "In4.Cu")
	)
	(gr_line
		(start 47.556928 -29.33192)
		(end 46.557438 -27.33167)
		(stroke
			(width 0.2)
			(type default)
		)
		(layer "In4.Cu")
	)
	(gr_line
		(start 47.556928 -9.01192)
		(end 46.557438 -7.01167)
		(stroke
			(width 0.2)
			(type default)
		)
		(layer "In4.Cu")
	)
	(gr_line
		(start 47.603156 -33.83153)
		(end 47.60341 -33.83153)
		(stroke
			(width 0.2)
			(type default)
		)
		(layer "In4.Cu")
	)
	(gr_line
		(start 47.603156 -13.51153)
		(end 47.60341 -13.51153)
		(stroke
			(width 0.2)
			(type default)
		)
		(layer "In4.Cu")
	)
	(gr_arc
		(start 47.60341 -33.83153)
		(mid 47.841916 -34.547048)
		(end 48.557434 -34.308542)
		(stroke
			(width 0.2)
			(type default)
		)
		(layer "In4.Cu")
	)
	(gr_arc
		(start 47.60341 -13.51153)
		(mid 47.841916 -14.227048)
		(end 48.557434 -13.988542)
		(stroke
			(width 0.2)
			(type default)
		)
		(layer "In4.Cu")
	)
	(gr_line
		(start 48.557434 -34.308542)
		(end 48.557688 -34.308542)
		(stroke
			(width 0.2)
			(type default)
		)
		(layer "In4.Cu")
	)
	(gr_line
		(start 48.557434 -13.988542)
		(end 48.557688 -13.988542)
		(stroke
			(width 0.2)
			(type default)
		)
		(layer "In4.Cu")
	)
	(gr_line
		(start 48.557688 -34.308542)
		(end 49.556924 -32.308546)
		(stroke
			(width 0.2)
			(type default)
		)
		(layer "In4.Cu")
	)
	(gr_line
		(start 48.557688 -13.988542)
		(end 49.556924 -11.988546)
		(stroke
			(width 0.2)
			(type default)
		)
		(layer "In4.Cu")
	)
	(gr_line
		(start 48.602646 -31.83128)
		(end 47.603156 -33.83153)
		(stroke
			(width 0.2)
			(type default)
		)
		(layer "In4.Cu")
	)
	(gr_line
		(start 48.602646 -11.51128)
		(end 47.603156 -13.51153)
		(stroke
			(width 0.2)
			(type default)
		)
		(layer "In4.Cu")
	)
	(gr_line
		(start 48.6029 -31.83128)
		(end 48.602646 -31.83128)
		(stroke
			(width 0.2)
			(type default)
		)
		(layer "In4.Cu")
	)
	(gr_line
		(start 48.6029 -11.51128)
		(end 48.602646 -11.51128)
		(stroke
			(width 0.2)
			(type default)
		)
		(layer "In4.Cu")
	)
	(gr_arc
		(start 49.556924 -32.308546)
		(mid 49.31857 -31.592723)
		(end 48.6029 -31.83128)
		(stroke
			(width 0.2)
			(type default)
		)
		(layer "In4.Cu")
	)
	(gr_arc
		(start 49.556924 -11.988546)
		(mid 49.31857 -11.272723)
		(end 48.6029 -11.51128)
		(stroke
			(width 0.2)
			(type default)
		)
		(layer "In4.Cu")
	)
	(gr_line
		(start 50.602896 -29.33192)
		(end 50.60315 -29.33192)
		(stroke
			(width 0.2)
			(type default)
		)
		(layer "In4.Cu")
	)
	(gr_line
		(start 50.602896 -9.01192)
		(end 50.60315 -9.01192)
		(stroke
			(width 0.2)
			(type default)
		)
		(layer "In4.Cu")
	)
	(gr_arc
		(start 50.60315 -29.33192)
		(mid 50.841656 -30.047438)
		(end 51.557174 -29.808932)
		(stroke
			(width 0.2)
			(type default)
		)
		(layer "In4.Cu")
	)
	(gr_arc
		(start 50.60315 -9.01192)
		(mid 50.841656 -9.727438)
		(end 51.557174 -9.488932)
		(stroke
			(width 0.2)
			(type default)
		)
		(layer "In4.Cu")
	)
	(gr_line
		(start 51.557174 -29.808932)
		(end 51.557428 -29.808932)
		(stroke
			(width 0.2)
			(type default)
		)
		(layer "In4.Cu")
	)
	(gr_line
		(start 51.557174 -9.488932)
		(end 51.557428 -9.488932)
		(stroke
			(width 0.2)
			(type default)
		)
		(layer "In4.Cu")
	)
	(gr_line
		(start 51.557428 -29.808932)
		(end 52.556664 -27.808936)
		(stroke
			(width 0.2)
			(type default)
		)
		(layer "In4.Cu")
	)
	(gr_line
		(start 51.557428 -9.488932)
		(end 52.556664 -7.488936)
		(stroke
			(width 0.2)
			(type default)
		)
		(layer "In4.Cu")
	)
	(gr_line
		(start 51.602386 -27.33167)
		(end 50.602896 -29.33192)
		(stroke
			(width 0.2)
			(type default)
		)
		(layer "In4.Cu")
	)
	(gr_line
		(start 51.602386 -7.01167)
		(end 50.602896 -9.01192)
		(stroke
			(width 0.2)
			(type default)
		)
		(layer "In4.Cu")
	)
	(gr_line
		(start 51.60264 -27.33167)
		(end 51.602386 -27.33167)
		(stroke
			(width 0.2)
			(type default)
		)
		(layer "In4.Cu")
	)
	(gr_line
		(start 51.60264 -7.01167)
		(end 51.602386 -7.01167)
		(stroke
			(width 0.2)
			(type default)
		)
		(layer "In4.Cu")
	)
	(gr_arc
		(start 52.556664 -27.808936)
		(mid 52.31831 -27.093113)
		(end 51.60264 -27.33167)
		(stroke
			(width 0.2)
			(type default)
		)
		(layer "In4.Cu")
	)
	(gr_arc
		(start 52.556664 -7.488936)
		(mid 52.31831 -6.773113)
		(end 51.60264 -7.01167)
		(stroke
			(width 0.2)
			(type default)
		)
		(layer "In4.Cu")
	)
	(gr_line
		(start 52.603146 -32.308292)
		(end 53.602636 -34.308288)
		(stroke
			(width 0.2)
			(type default)
		)
		(layer "In4.Cu")
	)
	(gr_line
		(start 52.603146 -11.988292)
		(end 53.602636 -13.988288)
		(stroke
			(width 0.2)
			(type default)
		)
		(layer "In4.Cu")
	)
	(gr_line
		(start 52.6034 -32.308292)
		(end 52.603146 -32.308292)
		(stroke
			(width 0.2)
			(type default)
		)
		(layer "In4.Cu")
	)
	(gr_line
		(start 52.6034 -11.988292)
		(end 52.603146 -11.988292)
		(stroke
			(width 0.2)
			(type default)
		)
		(layer "In4.Cu")
	)
	(gr_arc
		(start 53.557424 -31.83128)
		(mid 52.841906 -31.592774)
		(end 52.6034 -32.308292)
		(stroke
			(width 0.2)
			(type default)
		)
		(layer "In4.Cu")
	)
	(gr_arc
		(start 53.557424 -11.51128)
		(mid 52.841906 -11.272774)
		(end 52.6034 -11.988292)
		(stroke
			(width 0.2)
			(type default)
		)
		(layer "In4.Cu")
	)
	(gr_line
		(start 53.557678 -31.83128)
		(end 53.557424 -31.83128)
		(stroke
			(width 0.2)
			(type default)
		)
		(layer "In4.Cu")
	)
	(gr_line
		(start 53.557678 -11.51128)
		(end 53.557424 -11.51128)
		(stroke
			(width 0.2)
			(type default)
		)
		(layer "In4.Cu")
	)
	(gr_arc
		(start 53.602636 -34.308288)
		(mid 54.318306 -34.547226)
		(end 54.556914 -33.83153)
		(stroke
			(width 0.2)
			(type default)
		)
		(layer "In4.Cu")
	)
	(gr_arc
		(start 53.602636 -13.988288)
		(mid 54.318306 -14.227226)
		(end 54.556914 -13.51153)
		(stroke
			(width 0.2)
			(type default)
		)
		(layer "In4.Cu")
	)
	(gr_line
		(start 54.556914 -33.83153)
		(end 54.557168 -33.83153)
		(stroke
			(width 0.2)
			(type default)
		)
		(layer "In4.Cu")
	)
	(gr_line
		(start 54.556914 -13.51153)
		(end 54.557168 -13.51153)
		(stroke
			(width 0.2)
			(type default)
		)
		(layer "In4.Cu")
	)
	(gr_line
		(start 54.557168 -33.83153)
		(end 53.557678 -31.83128)
		(stroke
			(width 0.2)
			(type default)
		)
		(layer "In4.Cu")
	)
	(gr_line
		(start 54.557168 -13.51153)
		(end 53.557678 -11.51128)
		(stroke
			(width 0.2)
			(type default)
		)
		(layer "In4.Cu")
	)
	(gr_arc
		(start 54.60238 -29.331666)
		(mid 54.840632 -30.047438)
		(end 55.556404 -29.809186)
		(stroke
			(width 0.2)
			(type default)
		)
		(layer "In4.Cu")
	)
	(gr_arc
		(start 54.60238 -9.011666)
		(mid 54.840632 -9.727438)
		(end 55.556404 -9.489186)
		(stroke
			(width 0.2)
			(type default)
		)
		(layer "In4.Cu")
	)
	(gr_line
		(start 55.556404 -29.809186)
		(end 56.557164 -27.80919)
		(stroke
			(width 0.2)
			(type default)
		)
		(layer "In4.Cu")
	)
	(gr_line
		(start 55.556404 -9.489186)
		(end 56.557164 -7.48919)
		(stroke
			(width 0.2)
			(type default)
		)
		(layer "In4.Cu")
	)
	(gr_line
		(start 55.60314 -27.331416)
		(end 54.60238 -29.331666)
		(stroke
			(width 0.2)
			(type default)
		)
		(layer "In4.Cu")
	)
	(gr_line
		(start 55.60314 -7.011416)
		(end 54.60238 -9.011666)
		(stroke
			(width 0.2)
			(type default)
		)
		(layer "In4.Cu")
	)
	(gr_line
		(start 56.557164 -27.80919)
		(end 56.557164 -27.808936)
		(stroke
			(width 0.2)
			(type default)
		)
		(layer "In4.Cu")
	)
	(gr_arc
		(start 56.557164 -27.808936)
		(mid 56.318912 -27.093164)
		(end 55.60314 -27.331416)
		(stroke
			(width 0.2)
			(type default)
		)
		(layer "In4.Cu")
	)
	(gr_line
		(start 56.557164 -7.48919)
		(end 56.557164 -7.488936)
		(stroke
			(width 0.2)
			(type default)
		)
		(layer "In4.Cu")
	)
	(gr_arc
		(start 56.557164 -7.488936)
		(mid 56.318912 -6.773164)
		(end 55.60314 -7.011416)
		(stroke
			(width 0.2)
			(type default)
		)
		(layer "In4.Cu")
	)
	(gr_line
		(start 56.60263 -32.308546)
		(end 57.603136 -34.308542)
		(stroke
			(width 0.2)
			(type default)
		)
		(layer "In4.Cu")
	)
	(gr_line
		(start 56.60263 -11.988546)
		(end 57.603136 -13.988542)
		(stroke
			(width 0.2)
			(type default)
		)
		(layer "In4.Cu")
	)
	(gr_arc
		(start 57.556654 -31.831026)
		(mid 56.840882 -31.592774)
		(end 56.60263 -32.308546)
		(stroke
			(width 0.2)
			(type default)
		)
		(layer "In4.Cu")
	)
	(gr_arc
		(start 57.556654 -11.511026)
		(mid 56.840882 -11.272774)
		(end 56.60263 -11.988546)
		(stroke
			(width 0.2)
			(type default)
		)
		(layer "In4.Cu")
	)
	(gr_line
		(start 57.603136 -34.308542)
		(end 57.60339 -34.308542)
		(stroke
			(width 0.2)
			(type default)
		)
		(layer "In4.Cu")
	)
	(gr_line
		(start 57.603136 -13.988542)
		(end 57.60339 -13.988542)
		(stroke
			(width 0.2)
			(type default)
		)
		(layer "In4.Cu")
	)
	(gr_arc
		(start 57.60339 -34.308542)
		(mid 58.31901 -34.546997)
		(end 58.557414 -33.831276)
		(stroke
			(width 0.2)
			(type default)
		)
		(layer "In4.Cu")
	)
	(gr_arc
		(start 57.60339 -13.988542)
		(mid 58.31901 -14.226997)
		(end 58.557414 -13.511276)
		(stroke
			(width 0.2)
			(type default)
		)
		(layer "In4.Cu")
	)
	(gr_line
		(start 58.557414 -33.831276)
		(end 57.556654 -31.831026)
		(stroke
			(width 0.2)
			(type default)
		)
		(layer "In4.Cu")
	)
	(gr_line
		(start 58.557414 -13.511276)
		(end 57.556654 -11.511026)
		(stroke
			(width 0.2)
			(type default)
		)
		(layer "In4.Cu")
	)
	(gr_line
		(start 58.602626 -29.33192)
		(end 58.60288 -29.33192)
		(stroke
			(width 0.2)
			(type default)
		)
		(layer "In4.Cu")
	)
	(gr_line
		(start 58.602626 -9.01192)
		(end 58.60288 -9.01192)
		(stroke
			(width 0.2)
			(type default)
		)
		(layer "In4.Cu")
	)
	(gr_arc
		(start 58.60288 -29.33192)
		(mid 58.841386 -30.047438)
		(end 59.556904 -29.808932)
		(stroke
			(width 0.2)
			(type default)
		)
		(layer "In4.Cu")
	)
	(gr_arc
		(start 58.60288 -9.01192)
		(mid 58.841386 -9.727438)
		(end 59.556904 -9.488932)
		(stroke
			(width 0.2)
			(type default)
		)
		(layer "In4.Cu")
	)
	(gr_line
		(start 59.556904 -29.808932)
		(end 59.557158 -29.808932)
		(stroke
			(width 0.2)
			(type default)
		)
		(layer "In4.Cu")
	)
	(gr_line
		(start 59.556904 -9.488932)
		(end 59.557158 -9.488932)
		(stroke
			(width 0.2)
			(type default)
		)
		(layer "In4.Cu")
	)
	(gr_line
		(start 59.557158 -29.808932)
		(end 60.556394 -27.808936)
		(stroke
			(width 0.2)
			(type default)
		)
		(layer "In4.Cu")
	)
	(gr_line
		(start 59.557158 -9.488932)
		(end 60.556394 -7.488936)
		(stroke
			(width 0.2)
			(type default)
		)
		(layer "In4.Cu")
	)
	(gr_line
		(start 59.602116 -27.33167)
		(end 58.602626 -29.33192)
		(stroke
			(width 0.2)
			(type default)
		)
		(layer "In4.Cu")
	)
	(gr_line
		(start 59.602116 -7.01167)
		(end 58.602626 -9.01192)
		(stroke
			(width 0.2)
			(type default)
		)
		(layer "In4.Cu")
	)
	(gr_line
		(start 59.60237 -27.33167)
		(end 59.602116 -27.33167)
		(stroke
			(width 0.2)
			(type default)
		)
		(layer "In4.Cu")
	)
	(gr_line
		(start 59.60237 -7.01167)
		(end 59.602116 -7.01167)
		(stroke
			(width 0.2)
			(type default)
		)
		(layer "In4.Cu")
	)
	(gr_arc
		(start 60.556394 -27.808936)
		(mid 60.31804 -27.093113)
		(end 59.60237 -27.33167)
		(stroke
			(width 0.2)
			(type default)
		)
		(layer "In4.Cu")
	)
	(gr_arc
		(start 60.556394 -7.488936)
		(mid 60.31804 -6.773113)
		(end 59.60237 -7.01167)
		(stroke
			(width 0.2)
			(type default)
		)
		(layer "In4.Cu")
	)
	(gr_line
		(start 60.602876 -32.308292)
		(end 61.602366 -34.308288)
		(stroke
			(width 0.2)
			(type default)
		)
		(layer "In4.Cu")
	)
	(gr_line
		(start 60.602876 -11.988292)
		(end 61.602366 -13.988288)
		(stroke
			(width 0.2)
			(type default)
		)
		(layer "In4.Cu")
	)
	(gr_line
		(start 60.60313 -32.308292)
		(end 60.602876 -32.308292)
		(stroke
			(width 0.2)
			(type default)
		)
		(layer "In4.Cu")
	)
	(gr_line
		(start 60.60313 -11.988292)
		(end 60.602876 -11.988292)
		(stroke
			(width 0.2)
			(type default)
		)
		(layer "In4.Cu")
	)
	(gr_arc
		(start 61.557154 -31.83128)
		(mid 60.841636 -31.592774)
		(end 60.60313 -32.308292)
		(stroke
			(width 0.2)
			(type default)
		)
		(layer "In4.Cu")
	)
	(gr_arc
		(start 61.557154 -11.51128)
		(mid 60.841636 -11.272774)
		(end 60.60313 -11.988292)
		(stroke
			(width 0.2)
			(type default)
		)
		(layer "In4.Cu")
	)
	(gr_line
		(start 61.557408 -31.83128)
		(end 61.557154 -31.83128)
		(stroke
			(width 0.2)
			(type default)
		)
		(layer "In4.Cu")
	)
	(gr_line
		(start 61.557408 -11.51128)
		(end 61.557154 -11.51128)
		(stroke
			(width 0.2)
			(type default)
		)
		(layer "In4.Cu")
	)
	(gr_arc
		(start 61.602366 -34.308288)
		(mid 62.318036 -34.547226)
		(end 62.556644 -33.83153)
		(stroke
			(width 0.2)
			(type default)
		)
		(layer "In4.Cu")
	)
	(gr_arc
		(start 61.602366 -13.988288)
		(mid 62.318036 -14.227226)
		(end 62.556644 -13.51153)
		(stroke
			(width 0.2)
			(type default)
		)
		(layer "In4.Cu")
	)
	(gr_line
		(start 62.556644 -33.83153)
		(end 62.556898 -33.83153)
		(stroke
			(width 0.2)
			(type default)
		)
		(layer "In4.Cu")
	)
	(gr_line
		(start 62.556644 -13.51153)
		(end 62.556898 -13.51153)
		(stroke
			(width 0.2)
			(type default)
		)
		(layer "In4.Cu")
	)
	(gr_line
		(start 62.556898 -33.83153)
		(end 61.557408 -31.83128)
		(stroke
			(width 0.2)
			(type default)
		)
		(layer "In4.Cu")
	)
	(gr_line
		(start 62.556898 -13.51153)
		(end 61.557408 -11.51128)
		(stroke
			(width 0.2)
			(type default)
		)
		(layer "In4.Cu")
	)
	(gr_line
		(start 63.602616 -33.83153)
		(end 63.60287 -33.83153)
		(stroke
			(width 0.2)
			(type default)
		)
		(layer "In4.Cu")
	)
	(gr_line
		(start 63.602616 -13.51153)
		(end 63.60287 -13.51153)
		(stroke
			(width 0.2)
			(type default)
		)
		(layer "In4.Cu")
	)
	(gr_arc
		(start 63.60287 -33.83153)
		(mid 63.841376 -34.547048)
		(end 64.556894 -34.308542)
		(stroke
			(width 0.2)
			(type default)
		)
		(layer "In4.Cu")
	)
	(gr_arc
		(start 63.60287 -13.51153)
		(mid 63.841376 -14.227048)
		(end 64.556894 -13.988542)
		(stroke
			(width 0.2)
			(type default)
		)
		(layer "In4.Cu")
	)
	(gr_line
		(start 64.556894 -34.308542)
		(end 64.557148 -34.308542)
		(stroke
			(width 0.2)
			(type default)
		)
		(layer "In4.Cu")
	)
	(gr_line
		(start 64.556894 -13.988542)
		(end 64.557148 -13.988542)
		(stroke
			(width 0.2)
			(type default)
		)
		(layer "In4.Cu")
	)
	(gr_line
		(start 64.557148 -34.308542)
		(end 65.556384 -32.308546)
		(stroke
			(width 0.2)
			(type default)
		)
		(layer "In4.Cu")
	)
	(gr_line
		(start 64.557148 -13.988542)
		(end 65.556384 -11.988546)
		(stroke
			(width 0.2)
			(type default)
		)
		(layer "In4.Cu")
	)
	(gr_line
		(start 64.602106 -31.83128)
		(end 63.602616 -33.83153)
		(stroke
			(width 0.2)
			(type default)
		)
		(layer "In4.Cu")
	)
	(gr_line
		(start 64.602106 -11.51128)
		(end 63.602616 -13.51153)
		(stroke
			(width 0.2)
			(type default)
		)
		(layer "In4.Cu")
	)
	(gr_line
		(start 64.60236 -31.83128)
		(end 64.602106 -31.83128)
		(stroke
			(width 0.2)
			(type default)
		)
		(layer "In4.Cu")
	)
	(gr_arc
		(start 64.60236 -29.331666)
		(mid 64.840612 -30.047438)
		(end 65.556384 -29.809186)
		(stroke
			(width 0.2)
			(type default)
		)
		(layer "In4.Cu")
	)
	(gr_line
		(start 64.60236 -11.51128)
		(end 64.602106 -11.51128)
		(stroke
			(width 0.2)
			(type default)
		)
		(layer "In4.Cu")
	)
	(gr_arc
		(start 64.60236 -9.011666)
		(mid 64.840612 -9.727438)
		(end 65.556384 -9.489186)
		(stroke
			(width 0.2)
			(type default)
		)
		(layer "In4.Cu")
	)
	(gr_arc
		(start 65.556384 -32.308546)
		(mid 65.31803 -31.592723)
		(end 64.60236 -31.83128)
		(stroke
			(width 0.2)
			(type default)
		)
		(layer "In4.Cu")
	)
	(gr_line
		(start 65.556384 -29.809186)
		(end 66.557144 -27.80919)
		(stroke
			(width 0.2)
			(type default)
		)
		(layer "In4.Cu")
	)
	(gr_arc
		(start 65.556384 -11.988546)
		(mid 65.31803 -11.272723)
		(end 64.60236 -11.51128)
		(stroke
			(width 0.2)
			(type default)
		)
		(layer "In4.Cu")
	)
	(gr_line
		(start 65.556384 -9.489186)
		(end 66.557144 -7.48919)
		(stroke
			(width 0.2)
			(type default)
		)
		(layer "In4.Cu")
	)
	(gr_line
		(start 65.60312 -27.331416)
		(end 64.60236 -29.331666)
		(stroke
			(width 0.2)
			(type default)
		)
		(layer "In4.Cu")
	)
	(gr_line
		(start 65.60312 -7.011416)
		(end 64.60236 -9.011666)
		(stroke
			(width 0.2)
			(type default)
		)
		(layer "In4.Cu")
	)
	(gr_line
		(start 66.557144 -27.80919)
		(end 66.557144 -27.808936)
		(stroke
			(width 0.2)
			(type default)
		)
		(layer "In4.Cu")
	)
	(gr_arc
		(start 66.557144 -27.808936)
		(mid 66.318892 -27.093164)
		(end 65.60312 -27.331416)
		(stroke
			(width 0.2)
			(type default)
		)
		(layer "In4.Cu")
	)
	(gr_line
		(start 66.557144 -7.48919)
		(end 66.557144 -7.488936)
		(stroke
			(width 0.2)
			(type default)
		)
		(layer "In4.Cu")
	)
	(gr_arc
		(start 66.557144 -7.488936)
		(mid 66.318892 -6.773164)
		(end 65.60312 -7.011416)
		(stroke
			(width 0.2)
			(type default)
		)
		(layer "In4.Cu")
	)
	(gr_line
		(start 66.60261 -32.308546)
		(end 67.603116 -34.308542)
		(stroke
			(width 0.2)
			(type default)
		)
		(layer "In4.Cu")
	)
	(gr_line
		(start 66.60261 -11.988546)
		(end 67.603116 -13.988542)
		(stroke
			(width 0.2)
			(type default)
		)
		(layer "In4.Cu")
	)
	(gr_arc
		(start 67.556634 -31.831026)
		(mid 66.840862 -31.592774)
		(end 66.60261 -32.308546)
		(stroke
			(width 0.2)
			(type default)
		)
		(layer "In4.Cu")
	)
	(gr_arc
		(start 67.556634 -11.511026)
		(mid 66.840862 -11.272774)
		(end 66.60261 -11.988546)
		(stroke
			(width 0.2)
			(type default)
		)
		(layer "In4.Cu")
	)
	(gr_line
		(start 67.603116 -34.308542)
		(end 67.60337 -34.308542)
		(stroke
			(width 0.2)
			(type default)
		)
		(layer "In4.Cu")
	)
	(gr_line
		(start 67.603116 -13.988542)
		(end 67.60337 -13.988542)
		(stroke
			(width 0.2)
			(type default)
		)
		(layer "In4.Cu")
	)
	(gr_arc
		(start 67.60337 -34.308542)
		(mid 68.31899 -34.546997)
		(end 68.557394 -33.831276)
		(stroke
			(width 0.2)
			(type default)
		)
		(layer "In4.Cu")
	)
	(gr_arc
		(start 67.60337 -13.988542)
		(mid 68.31899 -14.226997)
		(end 68.557394 -13.511276)
		(stroke
			(width 0.2)
			(type default)
		)
		(layer "In4.Cu")
	)
	(gr_line
		(start 68.557394 -33.831276)
		(end 67.556634 -31.831026)
		(stroke
			(width 0.2)
			(type default)
		)
		(layer "In4.Cu")
	)
	(gr_line
		(start 68.557394 -13.511276)
		(end 67.556634 -11.511026)
		(stroke
			(width 0.2)
			(type default)
		)
		(layer "In4.Cu")
	)
	(gr_line
		(start 68.602606 -29.33192)
		(end 68.60286 -29.33192)
		(stroke
			(width 0.2)
			(type default)
		)
		(layer "In4.Cu")
	)
	(gr_line
		(start 68.602606 -9.01192)
		(end 68.60286 -9.01192)
		(stroke
			(width 0.2)
			(type default)
		)
		(layer "In4.Cu")
	)
	(gr_arc
		(start 68.60286 -29.33192)
		(mid 68.841366 -30.047438)
		(end 69.556884 -29.808932)
		(stroke
			(width 0.2)
			(type default)
		)
		(layer "In4.Cu")
	)
	(gr_arc
		(start 68.60286 -9.01192)
		(mid 68.841366 -9.727438)
		(end 69.556884 -9.488932)
		(stroke
			(width 0.2)
			(type default)
		)
		(layer "In4.Cu")
	)
	(gr_line
		(start 69.556884 -29.808932)
		(end 69.557138 -29.808932)
		(stroke
			(width 0.2)
			(type default)
		)
		(layer "In4.Cu")
	)
	(gr_line
		(start 69.556884 -9.488932)
		(end 69.557138 -9.488932)
		(stroke
			(width 0.2)
			(type default)
		)
		(layer "In4.Cu")
	)
	(gr_line
		(start 69.557138 -29.808932)
		(end 70.556374 -27.808936)
		(stroke
			(width 0.2)
			(type default)
		)
		(layer "In4.Cu")
	)
	(gr_line
		(start 69.557138 -9.488932)
		(end 70.556374 -7.488936)
		(stroke
			(width 0.2)
			(type default)
		)
		(layer "In4.Cu")
	)
	(gr_line
		(start 69.602096 -27.33167)
		(end 68.602606 -29.33192)
		(stroke
			(width 0.2)
			(type default)
		)
		(layer "In4.Cu")
	)
	(gr_line
		(start 69.602096 -7.01167)
		(end 68.602606 -9.01192)
		(stroke
			(width 0.2)
			(type default)
		)
		(layer "In4.Cu")
	)
	(gr_line
		(start 69.60235 -27.33167)
		(end 69.602096 -27.33167)
		(stroke
			(width 0.2)
			(type default)
		)
		(layer "In4.Cu")
	)
	(gr_line
		(start 69.60235 -7.01167)
		(end 69.602096 -7.01167)
		(stroke
			(width 0.2)
			(type default)
		)
		(layer "In4.Cu")
	)
	(gr_arc
		(start 70.556374 -27.808936)
		(mid 70.31802 -27.093113)
		(end 69.60235 -27.33167)
		(stroke
			(width 0.2)
			(type default)
		)
		(layer "In4.Cu")
	)
	(gr_arc
		(start 70.556374 -7.488936)
		(mid 70.31802 -6.773113)
		(end 69.60235 -7.01167)
		(stroke
			(width 0.2)
			(type default)
		)
		(layer "In4.Cu")
	)
	(gr_line
		(start 70.602856 -32.308292)
		(end 71.602346 -34.308288)
		(stroke
			(width 0.2)
			(type default)
		)
		(layer "In4.Cu")
	)
	(gr_line
		(start 70.602856 -11.988292)
		(end 71.602346 -13.988288)
		(stroke
			(width 0.2)
			(type default)
		)
		(layer "In4.Cu")
	)
	(gr_line
		(start 70.60311 -32.308292)
		(end 70.602856 -32.308292)
		(stroke
			(width 0.2)
			(type default)
		)
		(layer "In4.Cu")
	)
	(gr_line
		(start 70.60311 -11.988292)
		(end 70.602856 -11.988292)
		(stroke
			(width 0.2)
			(type default)
		)
		(layer "In4.Cu")
	)
	(gr_arc
		(start 71.557134 -31.83128)
		(mid 70.841616 -31.592774)
		(end 70.60311 -32.308292)
		(stroke
			(width 0.2)
			(type default)
		)
		(layer "In4.Cu")
	)
	(gr_arc
		(start 71.557134 -11.51128)
		(mid 70.841616 -11.272774)
		(end 70.60311 -11.988292)
		(stroke
			(width 0.2)
			(type default)
		)
		(layer "In4.Cu")
	)
	(gr_line
		(start 71.557388 -31.83128)
		(end 71.557134 -31.83128)
		(stroke
			(width 0.2)
			(type default)
		)
		(layer "In4.Cu")
	)
	(gr_line
		(start 71.557388 -11.51128)
		(end 71.557134 -11.51128)
		(stroke
			(width 0.2)
			(type default)
		)
		(layer "In4.Cu")
	)
	(gr_arc
		(start 71.602346 -34.308288)
		(mid 72.318016 -34.547226)
		(end 72.556624 -33.83153)
		(stroke
			(width 0.2)
			(type default)
		)
		(layer "In4.Cu")
	)
	(gr_arc
		(start 71.602346 -13.988288)
		(mid 72.318016 -14.227226)
		(end 72.556624 -13.51153)
		(stroke
			(width 0.2)
			(type default)
		)
		(layer "In4.Cu")
	)
	(gr_line
		(start 72.556624 -33.83153)
		(end 72.556878 -33.83153)
		(stroke
			(width 0.2)
			(type default)
		)
		(layer "In4.Cu")
	)
	(gr_line
		(start 72.556624 -13.51153)
		(end 72.556878 -13.51153)
		(stroke
			(width 0.2)
			(type default)
		)
		(layer "In4.Cu")
	)
	(gr_line
		(start 72.556878 -33.83153)
		(end 71.557388 -31.83128)
		(stroke
			(width 0.2)
			(type default)
		)
		(layer "In4.Cu")
	)
	(gr_line
		(start 72.556878 -13.51153)
		(end 71.557388 -11.51128)
		(stroke
			(width 0.2)
			(type default)
		)
		(layer "In4.Cu")
	)
	(gr_line
		(start 72.603106 -29.33192)
		(end 72.60336 -29.33192)
		(stroke
			(width 0.2)
			(type default)
		)
		(layer "In4.Cu")
	)
	(gr_line
		(start 72.603106 -9.01192)
		(end 72.60336 -9.01192)
		(stroke
			(width 0.2)
			(type default)
		)
		(layer "In4.Cu")
	)
	(gr_arc
		(start 72.60336 -29.33192)
		(mid 72.841866 -30.047438)
		(end 73.557384 -29.808932)
		(stroke
			(width 0.2)
			(type default)
		)
		(layer "In4.Cu")
	)
	(gr_arc
		(start 72.60336 -9.01192)
		(mid 72.841866 -9.727438)
		(end 73.557384 -9.488932)
		(stroke
			(width 0.2)
			(type default)
		)
		(layer "In4.Cu")
	)
	(gr_line
		(start 73.557384 -29.808932)
		(end 73.557638 -29.808932)
		(stroke
			(width 0.2)
			(type default)
		)
		(layer "In4.Cu")
	)
	(gr_line
		(start 73.557384 -9.488932)
		(end 73.557638 -9.488932)
		(stroke
			(width 0.2)
			(type default)
		)
		(layer "In4.Cu")
	)
	(gr_line
		(start 73.557638 -29.808932)
		(end 74.556874 -27.808936)
		(stroke
			(width 0.2)
			(type default)
		)
		(layer "In4.Cu")
	)
	(gr_line
		(start 73.557638 -9.488932)
		(end 74.556874 -7.488936)
		(stroke
			(width 0.2)
			(type default)
		)
		(layer "In4.Cu")
	)
	(gr_line
		(start 73.602596 -27.33167)
		(end 72.603106 -29.33192)
		(stroke
			(width 0.2)
			(type default)
		)
		(layer "In4.Cu")
	)
	(gr_line
		(start 73.602596 -7.01167)
		(end 72.603106 -9.01192)
		(stroke
			(width 0.2)
			(type default)
		)
		(layer "In4.Cu")
	)
	(gr_line
		(start 73.60285 -27.33167)
		(end 73.602596 -27.33167)
		(stroke
			(width 0.2)
			(type default)
		)
		(layer "In4.Cu")
	)
	(gr_line
		(start 73.60285 -7.01167)
		(end 73.602596 -7.01167)
		(stroke
			(width 0.2)
			(type default)
		)
		(layer "In4.Cu")
	)
	(gr_arc
		(start 74.556874 -27.808936)
		(mid 74.31852 -27.093113)
		(end 73.60285 -27.33167)
		(stroke
			(width 0.2)
			(type default)
		)
		(layer "In4.Cu")
	)
	(gr_arc
		(start 74.556874 -7.488936)
		(mid 74.31852 -6.773113)
		(end 73.60285 -7.01167)
		(stroke
			(width 0.2)
			(type default)
		)
		(layer "In4.Cu")
	)
	(gr_line
		(start 74.60234 -32.308546)
		(end 75.602846 -34.308542)
		(stroke
			(width 0.2)
			(type default)
		)
		(layer "In4.Cu")
	)
	(gr_line
		(start 74.60234 -11.988546)
		(end 75.602846 -13.988542)
		(stroke
			(width 0.2)
			(type default)
		)
		(layer "In4.Cu")
	)
	(gr_arc
		(start 75.556364 -31.831026)
		(mid 74.840592 -31.592774)
		(end 74.60234 -32.308546)
		(stroke
			(width 0.2)
			(type default)
		)
		(layer "In4.Cu")
	)
	(gr_arc
		(start 75.556364 -11.511026)
		(mid 74.840592 -11.272774)
		(end 74.60234 -11.988546)
		(stroke
			(width 0.2)
			(type default)
		)
		(layer "In4.Cu")
	)
	(gr_line
		(start 75.602846 -34.308542)
		(end 75.6031 -34.308542)
		(stroke
			(width 0.2)
			(type default)
		)
		(layer "In4.Cu")
	)
	(gr_line
		(start 75.602846 -13.988542)
		(end 75.6031 -13.988542)
		(stroke
			(width 0.2)
			(type default)
		)
		(layer "In4.Cu")
	)
	(gr_arc
		(start 75.6031 -34.308542)
		(mid 76.31872 -34.546997)
		(end 76.557124 -33.831276)
		(stroke
			(width 0.2)
			(type default)
		)
		(layer "In4.Cu")
	)
	(gr_arc
		(start 75.6031 -13.988542)
		(mid 76.31872 -14.226997)
		(end 76.557124 -13.511276)
		(stroke
			(width 0.2)
			(type default)
		)
		(layer "In4.Cu")
	)
	(gr_line
		(start 76.557124 -33.831276)
		(end 75.556364 -31.831026)
		(stroke
			(width 0.2)
			(type default)
		)
		(layer "In4.Cu")
	)
	(gr_line
		(start 76.557124 -13.511276)
		(end 75.556364 -11.511026)
		(stroke
			(width 0.2)
			(type default)
		)
		(layer "In4.Cu")
	)
	(gr_arc
		(start 76.60259 -29.331666)
		(mid 76.840842 -30.047438)
		(end 77.556614 -29.809186)
		(stroke
			(width 0.2)
			(type default)
		)
		(layer "In4.Cu")
	)
	(gr_arc
		(start 76.60259 -9.011666)
		(mid 76.840842 -9.727438)
		(end 77.556614 -9.489186)
		(stroke
			(width 0.2)
			(type default)
		)
		(layer "In4.Cu")
	)
	(gr_line
		(start 77.305154 7.343902)
		(end 78.3209 7.343902)
		(stroke
			(width 0.2)
			(type default)
		)
		(layer "In4.Cu")
	)
	(gr_arc
		(start 77.305154 8.060182)
		(mid 76.947014 7.702042)
		(end 77.305154 7.343902)
		(stroke
			(width 0.2)
			(type default)
		)
		(layer "In4.Cu")
	)
	(gr_line
		(start 77.556614 -29.809186)
		(end 78.557374 -27.80919)
		(stroke
			(width 0.2)
			(type default)
		)
		(layer "In4.Cu")
	)
	(gr_line
		(start 77.556614 -9.489186)
		(end 78.557374 -7.48919)
		(stroke
			(width 0.2)
			(type default)
		)
		(layer "In4.Cu")
	)
	(gr_line
		(start 77.60335 -27.331416)
		(end 76.60259 -29.331666)
		(stroke
			(width 0.2)
			(type default)
		)
		(layer "In4.Cu")
	)
	(gr_line
		(start 77.60335 -7.011416)
		(end 76.60259 -9.011666)
		(stroke
			(width 0.2)
			(type default)
		)
		(layer "In4.Cu")
	)
	(gr_arc
		(start 78.3209 7.343902)
		(mid 78.679294 7.701915)
		(end 78.321154 8.060182)
		(stroke
			(width 0.2)
			(type default)
		)
		(layer "In4.Cu")
	)
	(gr_line
		(start 78.321154 8.060182)
		(end 77.305154 8.060182)
		(stroke
			(width 0.2)
			(type default)
		)
		(layer "In4.Cu")
	)
	(gr_line
		(start 78.557374 -27.80919)
		(end 78.557374 -27.808936)
		(stroke
			(width 0.2)
			(type default)
		)
		(layer "In4.Cu")
	)
	(gr_arc
		(start 78.557374 -27.808936)
		(mid 78.319122 -27.093164)
		(end 77.60335 -27.331416)
		(stroke
			(width 0.2)
			(type default)
		)
		(layer "In4.Cu")
	)
	(gr_line
		(start 78.557374 -7.48919)
		(end 78.557374 -7.488936)
		(stroke
			(width 0.2)
			(type default)
		)
		(layer "In4.Cu")
	)
	(gr_arc
		(start 78.557374 -7.488936)
		(mid 78.319122 -6.773164)
		(end 77.60335 -7.011416)
		(stroke
			(width 0.2)
			(type default)
		)
		(layer "In4.Cu")
	)
	(gr_line
		(start 78.602586 -32.308292)
		(end 79.602076 -34.308288)
		(stroke
			(width 0.2)
			(type default)
		)
		(layer "In4.Cu")
	)
	(gr_line
		(start 78.602586 -11.988292)
		(end 79.602076 -13.988288)
		(stroke
			(width 0.2)
			(type default)
		)
		(layer "In4.Cu")
	)
	(gr_line
		(start 78.60284 -32.308292)
		(end 78.602586 -32.308292)
		(stroke
			(width 0.2)
			(type default)
		)
		(layer "In4.Cu")
	)
	(gr_line
		(start 78.60284 -11.988292)
		(end 78.602586 -11.988292)
		(stroke
			(width 0.2)
			(type default)
		)
		(layer "In4.Cu")
	)
	(gr_line
		(start 78.631288 4.807712)
		(end 79.647034 4.807712)
		(stroke
			(width 0.2)
			(type default)
		)
		(layer "In4.Cu")
	)
	(gr_arc
		(start 78.631288 5.523992)
		(mid 78.273148 5.165852)
		(end 78.631288 4.807712)
		(stroke
			(width 0.2)
			(type default)
		)
		(layer "In4.Cu")
	)
	(gr_arc
		(start 79.556864 -31.83128)
		(mid 78.841346 -31.592774)
		(end 78.60284 -32.308292)
		(stroke
			(width 0.2)
			(type default)
		)
		(layer "In4.Cu")
	)
	(gr_arc
		(start 79.556864 -11.51128)
		(mid 78.841346 -11.272774)
		(end 78.60284 -11.988292)
		(stroke
			(width 0.2)
			(type default)
		)
		(layer "In4.Cu")
	)
	(gr_line
		(start 79.557118 -31.83128)
		(end 79.556864 -31.83128)
		(stroke
			(width 0.2)
			(type default)
		)
		(layer "In4.Cu")
	)
	(gr_line
		(start 79.557118 -11.51128)
		(end 79.556864 -11.51128)
		(stroke
			(width 0.2)
			(type default)
		)
		(layer "In4.Cu")
	)
	(gr_arc
		(start 79.602076 -34.308288)
		(mid 80.317746 -34.547226)
		(end 80.556354 -33.83153)
		(stroke
			(width 0.2)
			(type default)
		)
		(layer "In4.Cu")
	)
	(gr_arc
		(start 79.602076 -13.988288)
		(mid 80.317746 -14.227226)
		(end 80.556354 -13.51153)
		(stroke
			(width 0.2)
			(type default)
		)
		(layer "In4.Cu")
	)
	(gr_arc
		(start 79.647034 4.807712)
		(mid 80.005428 5.165725)
		(end 79.647288 5.523992)
		(stroke
			(width 0.2)
			(type default)
		)
		(layer "In4.Cu")
	)
	(gr_line
		(start 79.647288 5.523992)
		(end 78.631288 5.523992)
		(stroke
			(width 0.2)
			(type default)
		)
		(layer "In4.Cu")
	)
	(gr_line
		(start 79.895954 7.343902)
		(end 80.9117 7.343902)
		(stroke
			(width 0.2)
			(type default)
		)
		(layer "In4.Cu")
	)
	(gr_arc
		(start 79.895954 8.060182)
		(mid 79.537814 7.702042)
		(end 79.895954 7.343902)
		(stroke
			(width 0.2)
			(type default)
		)
		(layer "In4.Cu")
	)
	(gr_line
		(start 80.556354 -33.83153)
		(end 80.556608 -33.83153)
		(stroke
			(width 0.2)
			(type default)
		)
		(layer "In4.Cu")
	)
	(gr_line
		(start 80.556354 -13.51153)
		(end 80.556608 -13.51153)
		(stroke
			(width 0.2)
			(type default)
		)
		(layer "In4.Cu")
	)
	(gr_line
		(start 80.556608 -33.83153)
		(end 79.557118 -31.83128)
		(stroke
			(width 0.2)
			(type default)
		)
		(layer "In4.Cu")
	)
	(gr_line
		(start 80.556608 -13.51153)
		(end 79.557118 -11.51128)
		(stroke
			(width 0.2)
			(type default)
		)
		(layer "In4.Cu")
	)
	(gr_arc
		(start 80.9117 7.343902)
		(mid 81.270094 7.701915)
		(end 80.911954 8.060182)
		(stroke
			(width 0.2)
			(type default)
		)
		(layer "In4.Cu")
	)
	(gr_line
		(start 80.911954 8.060182)
		(end 79.895954 8.060182)
		(stroke
			(width 0.2)
			(type default)
		)
		(layer "In4.Cu")
	)
	(gr_line
		(start 81.222088 4.807712)
		(end 82.237834 4.807712)
		(stroke
			(width 0.2)
			(type default)
		)
		(layer "In4.Cu")
	)
	(gr_arc
		(start 81.222088 5.523992)
		(mid 80.863948 5.165852)
		(end 81.222088 4.807712)
		(stroke
			(width 0.2)
			(type default)
		)
		(layer "In4.Cu")
	)
	(gr_line
		(start 81.60258 -27.808936)
		(end 82.603086 -29.808932)
		(stroke
			(width 0.2)
			(type default)
		)
		(layer "In4.Cu")
	)
	(gr_line
		(start 81.60258 -7.488936)
		(end 82.603086 -9.488932)
		(stroke
			(width 0.2)
			(type default)
		)
		(layer "In4.Cu")
	)
	(gr_arc
		(start 82.237834 4.807712)
		(mid 82.596228 5.165725)
		(end 82.238088 5.523992)
		(stroke
			(width 0.2)
			(type default)
		)
		(layer "In4.Cu")
	)
	(gr_line
		(start 82.238088 5.523992)
		(end 81.222088 5.523992)
		(stroke
			(width 0.2)
			(type default)
		)
		(layer "In4.Cu")
	)
	(gr_line
		(start 82.486754 7.343902)
		(end 83.5025 7.343902)
		(stroke
			(width 0.2)
			(type default)
		)
		(layer "In4.Cu")
	)
	(gr_arc
		(start 82.486754 8.060182)
		(mid 82.128614 7.702042)
		(end 82.486754 7.343902)
		(stroke
			(width 0.2)
			(type default)
		)
		(layer "In4.Cu")
	)
	(gr_arc
		(start 82.556604 -27.331416)
		(mid 81.840832 -27.093164)
		(end 81.60258 -27.808936)
		(stroke
			(width 0.2)
			(type default)
		)
		(layer "In4.Cu")
	)
	(gr_arc
		(start 82.556604 -7.011416)
		(mid 81.840832 -6.773164)
		(end 81.60258 -7.488936)
		(stroke
			(width 0.2)
			(type default)
		)
		(layer "In4.Cu")
	)
	(gr_line
		(start 82.603086 -29.808932)
		(end 82.60334 -29.808932)
		(stroke
			(width 0.2)
			(type default)
		)
		(layer "In4.Cu")
	)
	(gr_line
		(start 82.603086 -9.488932)
		(end 82.60334 -9.488932)
		(stroke
			(width 0.2)
			(type default)
		)
		(layer "In4.Cu")
	)
	(gr_arc
		(start 82.60334 -29.808932)
		(mid 83.31896 -30.047387)
		(end 83.557364 -29.331666)
		(stroke
			(width 0.2)
			(type default)
		)
		(layer "In4.Cu")
	)
	(gr_arc
		(start 82.60334 -9.488932)
		(mid 83.31896 -9.727387)
		(end 83.557364 -9.011666)
		(stroke
			(width 0.2)
			(type default)
		)
		(layer "In4.Cu")
	)
	(gr_arc
		(start 83.5025 7.343902)
		(mid 83.860894 7.701915)
		(end 83.502754 8.060182)
		(stroke
			(width 0.2)
			(type default)
		)
		(layer "In4.Cu")
	)
	(gr_line
		(start 83.502754 8.060182)
		(end 82.486754 8.060182)
		(stroke
			(width 0.2)
			(type default)
		)
		(layer "In4.Cu")
	)
	(gr_line
		(start 83.557364 -29.331666)
		(end 82.556604 -27.331416)
		(stroke
			(width 0.2)
			(type default)
		)
		(layer "In4.Cu")
	)
	(gr_line
		(start 83.557364 -9.011666)
		(end 82.556604 -7.011416)
		(stroke
			(width 0.2)
			(type default)
		)
		(layer "In4.Cu")
	)
	(gr_line
		(start 83.602576 -33.83153)
		(end 83.60283 -33.83153)
		(stroke
			(width 0.2)
			(type default)
		)
		(layer "In4.Cu")
	)
	(gr_line
		(start 83.602576 -13.51153)
		(end 83.60283 -13.51153)
		(stroke
			(width 0.2)
			(type default)
		)
		(layer "In4.Cu")
	)
	(gr_arc
		(start 83.60283 -33.83153)
		(mid 83.841336 -34.547048)
		(end 84.556854 -34.308542)
		(stroke
			(width 0.2)
			(type default)
		)
		(layer "In4.Cu")
	)
	(gr_arc
		(start 83.60283 -13.51153)
		(mid 83.841336 -14.227048)
		(end 84.556854 -13.988542)
		(stroke
			(width 0.2)
			(type default)
		)
		(layer "In4.Cu")
	)
	(gr_line
		(start 83.812888 4.807712)
		(end 84.828634 4.807712)
		(stroke
			(width 0.2)
			(type default)
		)
		(layer "In4.Cu")
	)
	(gr_arc
		(start 83.812888 5.523992)
		(mid 83.454748 5.165852)
		(end 83.812888 4.807712)
		(stroke
			(width 0.2)
			(type default)
		)
		(layer "In4.Cu")
	)
	(gr_line
		(start 84.556854 -34.308542)
		(end 84.557108 -34.308542)
		(stroke
			(width 0.2)
			(type default)
		)
		(layer "In4.Cu")
	)
	(gr_line
		(start 84.556854 -13.988542)
		(end 84.557108 -13.988542)
		(stroke
			(width 0.2)
			(type default)
		)
		(layer "In4.Cu")
	)
	(gr_line
		(start 84.557108 -34.308542)
		(end 85.556344 -32.308546)
		(stroke
			(width 0.2)
			(type default)
		)
		(layer "In4.Cu")
	)
	(gr_line
		(start 84.557108 -13.988542)
		(end 85.556344 -11.988546)
		(stroke
			(width 0.2)
			(type default)
		)
		(layer "In4.Cu")
	)
	(gr_line
		(start 84.602066 -31.83128)
		(end 83.602576 -33.83153)
		(stroke
			(width 0.2)
			(type default)
		)
		(layer "In4.Cu")
	)
	(gr_line
		(start 84.602066 -11.51128)
		(end 83.602576 -13.51153)
		(stroke
			(width 0.2)
			(type default)
		)
		(layer "In4.Cu")
	)
	(gr_line
		(start 84.60232 -31.83128)
		(end 84.602066 -31.83128)
		(stroke
			(width 0.2)
			(type default)
		)
		(layer "In4.Cu")
	)
	(gr_line
		(start 84.60232 -11.51128)
		(end 84.602066 -11.51128)
		(stroke
			(width 0.2)
			(type default)
		)
		(layer "In4.Cu")
	)
	(gr_arc
		(start 84.828634 4.807712)
		(mid 85.187028 5.165725)
		(end 84.828888 5.523992)
		(stroke
			(width 0.2)
			(type default)
		)
		(layer "In4.Cu")
	)
	(gr_line
		(start 84.828888 5.523992)
		(end 83.812888 5.523992)
		(stroke
			(width 0.2)
			(type default)
		)
		(layer "In4.Cu")
	)
	(gr_line
		(start 85.077554 7.343902)
		(end 86.0933 7.343902)
		(stroke
			(width 0.2)
			(type default)
		)
		(layer "In4.Cu")
	)
	(gr_arc
		(start 85.077554 8.060182)
		(mid 84.719414 7.702042)
		(end 85.077554 7.343902)
		(stroke
			(width 0.2)
			(type default)
		)
		(layer "In4.Cu")
	)
	(gr_arc
		(start 85.556344 -32.308546)
		(mid 85.31799 -31.592723)
		(end 84.60232 -31.83128)
		(stroke
			(width 0.2)
			(type default)
		)
		(layer "In4.Cu")
	)
	(gr_arc
		(start 85.556344 -11.988546)
		(mid 85.31799 -11.272723)
		(end 84.60232 -11.51128)
		(stroke
			(width 0.2)
			(type default)
		)
		(layer "In4.Cu")
	)
	(gr_line
		(start 85.602826 -27.808682)
		(end 86.602316 -29.808678)
		(stroke
			(width 0.2)
			(type default)
		)
		(layer "In4.Cu")
	)
	(gr_line
		(start 85.602826 -7.488682)
		(end 86.602316 -9.488678)
		(stroke
			(width 0.2)
			(type default)
		)
		(layer "In4.Cu")
	)
	(gr_line
		(start 85.60308 -27.808682)
		(end 85.602826 -27.808682)
		(stroke
			(width 0.2)
			(type default)
		)
		(layer "In4.Cu")
	)
	(gr_line
		(start 85.60308 -7.488682)
		(end 85.602826 -7.488682)
		(stroke
			(width 0.2)
			(type default)
		)
		(layer "In4.Cu")
	)
	(gr_arc
		(start 86.0933 7.343902)
		(mid 86.451694 7.701915)
		(end 86.093554 8.060182)
		(stroke
			(width 0.2)
			(type default)
		)
		(layer "In4.Cu")
	)
	(gr_line
		(start 86.093554 8.060182)
		(end 85.077554 8.060182)
		(stroke
			(width 0.2)
			(type default)
		)
		(layer "In4.Cu")
	)
	(gr_line
		(start 86.403688 4.807712)
		(end 87.419434 4.807712)
		(stroke
			(width 0.2)
			(type default)
		)
		(layer "In4.Cu")
	)
	(gr_arc
		(start 86.403688 5.523992)
		(mid 86.045548 5.165852)
		(end 86.403688 4.807712)
		(stroke
			(width 0.2)
			(type default)
		)
		(layer "In4.Cu")
	)
	(gr_arc
		(start 86.557104 -27.33167)
		(mid 85.841586 -27.093164)
		(end 85.60308 -27.808682)
		(stroke
			(width 0.2)
			(type default)
		)
		(layer "In4.Cu")
	)
	(gr_arc
		(start 86.557104 -7.01167)
		(mid 85.841586 -6.773164)
		(end 85.60308 -7.488682)
		(stroke
			(width 0.2)
			(type default)
		)
		(layer "In4.Cu")
	)
	(gr_line
		(start 86.557358 -27.33167)
		(end 86.557104 -27.33167)
		(stroke
			(width 0.2)
			(type default)
		)
		(layer "In4.Cu")
	)
	(gr_line
		(start 86.557358 -7.01167)
		(end 86.557104 -7.01167)
		(stroke
			(width 0.2)
			(type default)
		)
		(layer "In4.Cu")
	)
	(gr_arc
		(start 86.602316 -29.808678)
		(mid 87.317986 -30.047616)
		(end 87.556594 -29.33192)
		(stroke
			(width 0.2)
			(type default)
		)
		(layer "In4.Cu")
	)
	(gr_arc
		(start 86.602316 -9.488678)
		(mid 87.317986 -9.727616)
		(end 87.556594 -9.01192)
		(stroke
			(width 0.2)
			(type default)
		)
		(layer "In4.Cu")
	)
	(gr_arc
		(start 87.419434 4.807712)
		(mid 87.777828 5.165725)
		(end 87.419688 5.523992)
		(stroke
			(width 0.2)
			(type default)
		)
		(layer "In4.Cu")
	)
	(gr_line
		(start 87.419688 5.523992)
		(end 86.403688 5.523992)
		(stroke
			(width 0.2)
			(type default)
		)
		(layer "In4.Cu")
	)
	(gr_line
		(start 87.556594 -29.33192)
		(end 87.556848 -29.33192)
		(stroke
			(width 0.2)
			(type default)
		)
		(layer "In4.Cu")
	)
	(gr_line
		(start 87.556594 -9.01192)
		(end 87.556848 -9.01192)
		(stroke
			(width 0.2)
			(type default)
		)
		(layer "In4.Cu")
	)
	(gr_line
		(start 87.556848 -29.33192)
		(end 86.557358 -27.33167)
		(stroke
			(width 0.2)
			(type default)
		)
		(layer "In4.Cu")
	)
	(gr_line
		(start 87.556848 -9.01192)
		(end 86.557358 -7.01167)
		(stroke
			(width 0.2)
			(type default)
		)
		(layer "In4.Cu")
	)
	(gr_line
		(start 87.603076 -33.83153)
		(end 87.60333 -33.83153)
		(stroke
			(width 0.2)
			(type default)
		)
		(layer "In4.Cu")
	)
	(gr_line
		(start 87.603076 -13.51153)
		(end 87.60333 -13.51153)
		(stroke
			(width 0.2)
			(type default)
		)
		(layer "In4.Cu")
	)
	(gr_arc
		(start 87.60333 -33.83153)
		(mid 87.841836 -34.547048)
		(end 88.557354 -34.308542)
		(stroke
			(width 0.2)
			(type default)
		)
		(layer "In4.Cu")
	)
	(gr_arc
		(start 87.60333 -13.51153)
		(mid 87.841836 -14.227048)
		(end 88.557354 -13.988542)
		(stroke
			(width 0.2)
			(type default)
		)
		(layer "In4.Cu")
	)
	(gr_line
		(start 87.668354 7.343902)
		(end 88.6841 7.343902)
		(stroke
			(width 0.2)
			(type default)
		)
		(layer "In4.Cu")
	)
	(gr_arc
		(start 87.668354 8.060182)
		(mid 87.310214 7.702042)
		(end 87.668354 7.343902)
		(stroke
			(width 0.2)
			(type default)
		)
		(layer "In4.Cu")
	)
	(gr_line
		(start 88.557354 -34.308542)
		(end 88.557608 -34.308542)
		(stroke
			(width 0.2)
			(type default)
		)
		(layer "In4.Cu")
	)
	(gr_line
		(start 88.557354 -13.988542)
		(end 88.557608 -13.988542)
		(stroke
			(width 0.2)
			(type default)
		)
		(layer "In4.Cu")
	)
	(gr_line
		(start 88.557608 -34.308542)
		(end 89.556844 -32.308546)
		(stroke
			(width 0.2)
			(type default)
		)
		(layer "In4.Cu")
	)
	(gr_line
		(start 88.557608 -13.988542)
		(end 89.556844 -11.988546)
		(stroke
			(width 0.2)
			(type default)
		)
		(layer "In4.Cu")
	)
	(gr_line
		(start 88.602566 -31.83128)
		(end 87.603076 -33.83153)
		(stroke
			(width 0.2)
			(type default)
		)
		(layer "In4.Cu")
	)
	(gr_line
		(start 88.602566 -11.51128)
		(end 87.603076 -13.51153)
		(stroke
			(width 0.2)
			(type default)
		)
		(layer "In4.Cu")
	)
	(gr_line
		(start 88.60282 -31.83128)
		(end 88.602566 -31.83128)
		(stroke
			(width 0.2)
			(type default)
		)
		(layer "In4.Cu")
	)
	(gr_line
		(start 88.60282 -11.51128)
		(end 88.602566 -11.51128)
		(stroke
			(width 0.2)
			(type default)
		)
		(layer "In4.Cu")
	)
	(gr_arc
		(start 88.6841 7.343902)
		(mid 89.042494 7.701915)
		(end 88.684354 8.060182)
		(stroke
			(width 0.2)
			(type default)
		)
		(layer "In4.Cu")
	)
	(gr_line
		(start 88.684354 8.060182)
		(end 87.668354 8.060182)
		(stroke
			(width 0.2)
			(type default)
		)
		(layer "In4.Cu")
	)
	(gr_line
		(start 88.994488 4.807712)
		(end 90.010234 4.807712)
		(stroke
			(width 0.2)
			(type default)
		)
		(layer "In4.Cu")
	)
	(gr_arc
		(start 88.994488 5.523992)
		(mid 88.636348 5.165852)
		(end 88.994488 4.807712)
		(stroke
			(width 0.2)
			(type default)
		)
		(layer "In4.Cu")
	)
	(gr_arc
		(start 89.556844 -32.308546)
		(mid 89.31849 -31.592723)
		(end 88.60282 -31.83128)
		(stroke
			(width 0.2)
			(type default)
		)
		(layer "In4.Cu")
	)
	(gr_arc
		(start 89.556844 -11.988546)
		(mid 89.31849 -11.272723)
		(end 88.60282 -11.51128)
		(stroke
			(width 0.2)
			(type default)
		)
		(layer "In4.Cu")
	)
	(gr_line
		(start 89.60231 -27.808936)
		(end 90.602816 -29.808932)
		(stroke
			(width 0.2)
			(type default)
		)
		(layer "In4.Cu")
	)
	(gr_line
		(start 89.60231 -7.488936)
		(end 90.602816 -9.488932)
		(stroke
			(width 0.2)
			(type default)
		)
		(layer "In4.Cu")
	)
	(gr_arc
		(start 90.010234 4.807712)
		(mid 90.368628 5.165725)
		(end 90.010488 5.523992)
		(stroke
			(width 0.2)
			(type default)
		)
		(layer "In4.Cu")
	)
	(gr_line
		(start 90.010488 5.523992)
		(end 88.994488 5.523992)
		(stroke
			(width 0.2)
			(type default)
		)
		(layer "In4.Cu")
	)
	(gr_line
		(start 90.259154 7.343902)
		(end 91.2749 7.343902)
		(stroke
			(width 0.2)
			(type default)
		)
		(layer "In4.Cu")
	)
	(gr_arc
		(start 90.259154 8.060182)
		(mid 89.901014 7.702042)
		(end 90.259154 7.343902)
		(stroke
			(width 0.2)
			(type default)
		)
		(layer "In4.Cu")
	)
	(gr_arc
		(start 90.556334 -27.331416)
		(mid 89.840562 -27.093164)
		(end 89.60231 -27.808936)
		(stroke
			(width 0.2)
			(type default)
		)
		(layer "In4.Cu")
	)
	(gr_arc
		(start 90.556334 -7.011416)
		(mid 89.840562 -6.773164)
		(end 89.60231 -7.488936)
		(stroke
			(width 0.2)
			(type default)
		)
		(layer "In4.Cu")
	)
	(gr_line
		(start 90.602816 -29.808932)
		(end 90.60307 -29.808932)
		(stroke
			(width 0.2)
			(type default)
		)
		(layer "In4.Cu")
	)
	(gr_line
		(start 90.602816 -9.488932)
		(end 90.60307 -9.488932)
		(stroke
			(width 0.2)
			(type default)
		)
		(layer "In4.Cu")
	)
	(gr_arc
		(start 90.60307 -29.808932)
		(mid 91.31869 -30.047387)
		(end 91.557094 -29.331666)
		(stroke
			(width 0.2)
			(type default)
		)
		(layer "In4.Cu")
	)
	(gr_arc
		(start 90.60307 -9.488932)
		(mid 91.31869 -9.727387)
		(end 91.557094 -9.011666)
		(stroke
			(width 0.2)
			(type default)
		)
		(layer "In4.Cu")
	)
	(gr_arc
		(start 91.2749 7.343902)
		(mid 91.633294 7.701915)
		(end 91.275154 8.060182)
		(stroke
			(width 0.2)
			(type default)
		)
		(layer "In4.Cu")
	)
	(gr_line
		(start 91.275154 8.060182)
		(end 90.259154 8.060182)
		(stroke
			(width 0.2)
			(type default)
		)
		(layer "In4.Cu")
	)
	(gr_line
		(start 91.557094 -29.331666)
		(end 90.556334 -27.331416)
		(stroke
			(width 0.2)
			(type default)
		)
		(layer "In4.Cu")
	)
	(gr_line
		(start 91.557094 -9.011666)
		(end 90.556334 -7.011416)
		(stroke
			(width 0.2)
			(type default)
		)
		(layer "In4.Cu")
	)
	(gr_line
		(start 91.585288 4.807712)
		(end 92.601034 4.807712)
		(stroke
			(width 0.2)
			(type default)
		)
		(layer "In4.Cu")
	)
	(gr_arc
		(start 91.585288 5.523992)
		(mid 91.227148 5.165852)
		(end 91.585288 4.807712)
		(stroke
			(width 0.2)
			(type default)
		)
		(layer "In4.Cu")
	)
	(gr_arc
		(start 91.60256 -33.831276)
		(mid 91.840812 -34.547048)
		(end 92.556584 -34.308796)
		(stroke
			(width 0.2)
			(type default)
		)
		(layer "In4.Cu")
	)
	(gr_arc
		(start 91.60256 -13.511276)
		(mid 91.840812 -14.227048)
		(end 92.556584 -13.988796)
		(stroke
			(width 0.2)
			(type default)
		)
		(layer "In4.Cu")
	)
	(gr_line
		(start 92.556584 -34.308796)
		(end 93.557344 -32.3088)
		(stroke
			(width 0.2)
			(type default)
		)
		(layer "In4.Cu")
	)
	(gr_line
		(start 92.556584 -13.988796)
		(end 93.557344 -11.9888)
		(stroke
			(width 0.2)
			(type default)
		)
		(layer "In4.Cu")
	)
	(gr_arc
		(start 92.601034 4.807712)
		(mid 92.959428 5.165725)
		(end 92.601288 5.523992)
		(stroke
			(width 0.2)
			(type default)
		)
		(layer "In4.Cu")
	)
	(gr_line
		(start 92.601288 5.523992)
		(end 91.585288 5.523992)
		(stroke
			(width 0.2)
			(type default)
		)
		(layer "In4.Cu")
	)
	(gr_line
		(start 92.60332 -31.831026)
		(end 91.60256 -33.831276)
		(stroke
			(width 0.2)
			(type default)
		)
		(layer "In4.Cu")
	)
	(gr_line
		(start 92.60332 -11.511026)
		(end 91.60256 -13.511276)
		(stroke
			(width 0.2)
			(type default)
		)
		(layer "In4.Cu")
	)
	(gr_line
		(start 92.849954 7.343902)
		(end 93.8657 7.343902)
		(stroke
			(width 0.2)
			(type default)
		)
		(layer "In4.Cu")
	)
	(gr_arc
		(start 92.849954 8.060182)
		(mid 92.491814 7.702042)
		(end 92.849954 7.343902)
		(stroke
			(width 0.2)
			(type default)
		)
		(layer "In4.Cu")
	)
	(gr_line
		(start 93.557344 -32.3088)
		(end 93.557344 -32.308546)
		(stroke
			(width 0.2)
			(type default)
		)
		(layer "In4.Cu")
	)
	(gr_arc
		(start 93.557344 -32.308546)
		(mid 93.319092 -31.592774)
		(end 92.60332 -31.831026)
		(stroke
			(width 0.2)
			(type default)
		)
		(layer "In4.Cu")
	)
	(gr_line
		(start 93.557344 -11.9888)
		(end 93.557344 -11.988546)
		(stroke
			(width 0.2)
			(type default)
		)
		(layer "In4.Cu")
	)
	(gr_arc
		(start 93.557344 -11.988546)
		(mid 93.319092 -11.272774)
		(end 92.60332 -11.511026)
		(stroke
			(width 0.2)
			(type default)
		)
		(layer "In4.Cu")
	)
	(gr_line
		(start 93.602556 -27.808682)
		(end 94.602046 -29.808678)
		(stroke
			(width 0.2)
			(type default)
		)
		(layer "In4.Cu")
	)
	(gr_line
		(start 93.602556 -7.488682)
		(end 94.602046 -9.488678)
		(stroke
			(width 0.2)
			(type default)
		)
		(layer "In4.Cu")
	)
	(gr_line
		(start 93.60281 -27.808682)
		(end 93.602556 -27.808682)
		(stroke
			(width 0.2)
			(type default)
		)
		(layer "In4.Cu")
	)
	(gr_line
		(start 93.60281 -7.488682)
		(end 93.602556 -7.488682)
		(stroke
			(width 0.2)
			(type default)
		)
		(layer "In4.Cu")
	)
	(gr_arc
		(start 93.8657 7.343902)
		(mid 94.224094 7.701915)
		(end 93.865954 8.060182)
		(stroke
			(width 0.2)
			(type default)
		)
		(layer "In4.Cu")
	)
	(gr_line
		(start 93.865954 8.060182)
		(end 92.849954 8.060182)
		(stroke
			(width 0.2)
			(type default)
		)
		(layer "In4.Cu")
	)
	(gr_line
		(start 94.176088 4.807712)
		(end 95.191834 4.807712)
		(stroke
			(width 0.2)
			(type default)
		)
		(layer "In4.Cu")
	)
	(gr_arc
		(start 94.176088 5.523992)
		(mid 93.817948 5.165852)
		(end 94.176088 4.807712)
		(stroke
			(width 0.2)
			(type default)
		)
		(layer "In4.Cu")
	)
	(gr_arc
		(start 94.556834 -27.33167)
		(mid 93.841316 -27.093164)
		(end 93.60281 -27.808682)
		(stroke
			(width 0.2)
			(type default)
		)
		(layer "In4.Cu")
	)
	(gr_arc
		(start 94.556834 -7.01167)
		(mid 93.841316 -6.773164)
		(end 93.60281 -7.488682)
		(stroke
			(width 0.2)
			(type default)
		)
		(layer "In4.Cu")
	)
	(gr_line
		(start 94.557088 -27.33167)
		(end 94.556834 -27.33167)
		(stroke
			(width 0.2)
			(type default)
		)
		(layer "In4.Cu")
	)
	(gr_line
		(start 94.557088 -7.01167)
		(end 94.556834 -7.01167)
		(stroke
			(width 0.2)
			(type default)
		)
		(layer "In4.Cu")
	)
	(gr_arc
		(start 94.602046 -29.808678)
		(mid 95.317716 -30.047616)
		(end 95.556324 -29.33192)
		(stroke
			(width 0.2)
			(type default)
		)
		(layer "In4.Cu")
	)
	(gr_arc
		(start 94.602046 -9.488678)
		(mid 95.317716 -9.727616)
		(end 95.556324 -9.01192)
		(stroke
			(width 0.2)
			(type default)
		)
		(layer "In4.Cu")
	)
	(gr_arc
		(start 95.191834 4.807712)
		(mid 95.550228 5.165725)
		(end 95.192088 5.523992)
		(stroke
			(width 0.2)
			(type default)
		)
		(layer "In4.Cu")
	)
	(gr_line
		(start 95.192088 5.523992)
		(end 94.176088 5.523992)
		(stroke
			(width 0.2)
			(type default)
		)
		(layer "In4.Cu")
	)
	(gr_line
		(start 95.440754 7.343902)
		(end 96.4565 7.343902)
		(stroke
			(width 0.2)
			(type default)
		)
		(layer "In4.Cu")
	)
	(gr_arc
		(start 95.440754 8.060182)
		(mid 95.082614 7.702042)
		(end 95.440754 7.343902)
		(stroke
			(width 0.2)
			(type default)
		)
		(layer "In4.Cu")
	)
	(gr_line
		(start 95.556324 -29.33192)
		(end 95.556578 -29.33192)
		(stroke
			(width 0.2)
			(type default)
		)
		(layer "In4.Cu")
	)
	(gr_line
		(start 95.556324 -9.01192)
		(end 95.556578 -9.01192)
		(stroke
			(width 0.2)
			(type default)
		)
		(layer "In4.Cu")
	)
	(gr_line
		(start 95.556578 -29.33192)
		(end 94.557088 -27.33167)
		(stroke
			(width 0.2)
			(type default)
		)
		(layer "In4.Cu")
	)
	(gr_line
		(start 95.556578 -9.01192)
		(end 94.557088 -7.01167)
		(stroke
			(width 0.2)
			(type default)
		)
		(layer "In4.Cu")
	)
	(gr_line
		(start 95.602806 -33.83153)
		(end 95.60306 -33.83153)
		(stroke
			(width 0.2)
			(type default)
		)
		(layer "In4.Cu")
	)
	(gr_line
		(start 95.602806 -13.51153)
		(end 95.60306 -13.51153)
		(stroke
			(width 0.2)
			(type default)
		)
		(layer "In4.Cu")
	)
	(gr_arc
		(start 95.60306 -33.83153)
		(mid 95.841566 -34.547048)
		(end 96.557084 -34.308542)
		(stroke
			(width 0.2)
			(type default)
		)
		(layer "In4.Cu")
	)
	(gr_arc
		(start 95.60306 -13.51153)
		(mid 95.841566 -14.227048)
		(end 96.557084 -13.988542)
		(stroke
			(width 0.2)
			(type default)
		)
		(layer "In4.Cu")
	)
	(gr_arc
		(start 96.4565 7.343902)
		(mid 96.814894 7.701915)
		(end 96.456754 8.060182)
		(stroke
			(width 0.2)
			(type default)
		)
		(layer "In4.Cu")
	)
	(gr_line
		(start 96.456754 8.060182)
		(end 95.440754 8.060182)
		(stroke
			(width 0.2)
			(type default)
		)
		(layer "In4.Cu")
	)
	(gr_line
		(start 96.557084 -34.308542)
		(end 96.557338 -34.308542)
		(stroke
			(width 0.2)
			(type default)
		)
		(layer "In4.Cu")
	)
	(gr_line
		(start 96.557084 -13.988542)
		(end 96.557338 -13.988542)
		(stroke
			(width 0.2)
			(type default)
		)
		(layer "In4.Cu")
	)
	(gr_line
		(start 96.557338 -34.308542)
		(end 97.556574 -32.308546)
		(stroke
			(width 0.2)
			(type default)
		)
		(layer "In4.Cu")
	)
	(gr_line
		(start 96.557338 -13.988542)
		(end 97.556574 -11.988546)
		(stroke
			(width 0.2)
			(type default)
		)
		(layer "In4.Cu")
	)
	(gr_line
		(start 96.602296 -31.83128)
		(end 95.602806 -33.83153)
		(stroke
			(width 0.2)
			(type default)
		)
		(layer "In4.Cu")
	)
	(gr_line
		(start 96.602296 -11.51128)
		(end 95.602806 -13.51153)
		(stroke
			(width 0.2)
			(type default)
		)
		(layer "In4.Cu")
	)
	(gr_line
		(start 96.60255 -31.83128)
		(end 96.602296 -31.83128)
		(stroke
			(width 0.2)
			(type default)
		)
		(layer "In4.Cu")
	)
	(gr_line
		(start 96.60255 -11.51128)
		(end 96.602296 -11.51128)
		(stroke
			(width 0.2)
			(type default)
		)
		(layer "In4.Cu")
	)
	(gr_line
		(start 96.766888 4.807712)
		(end 97.782634 4.807712)
		(stroke
			(width 0.2)
			(type default)
		)
		(layer "In4.Cu")
	)
	(gr_arc
		(start 96.766888 5.523992)
		(mid 96.408748 5.165852)
		(end 96.766888 4.807712)
		(stroke
			(width 0.2)
			(type default)
		)
		(layer "In4.Cu")
	)
	(gr_arc
		(start 97.556574 -32.308546)
		(mid 97.31822 -31.592723)
		(end 96.60255 -31.83128)
		(stroke
			(width 0.2)
			(type default)
		)
		(layer "In4.Cu")
	)
	(gr_arc
		(start 97.556574 -11.988546)
		(mid 97.31822 -11.272723)
		(end 96.60255 -11.51128)
		(stroke
			(width 0.2)
			(type default)
		)
		(layer "In4.Cu")
	)
	(gr_line
		(start 97.603056 -27.808682)
		(end 98.602546 -29.808678)
		(stroke
			(width 0.2)
			(type default)
		)
		(layer "In4.Cu")
	)
	(gr_line
		(start 97.603056 -7.488682)
		(end 98.602546 -9.488678)
		(stroke
			(width 0.2)
			(type default)
		)
		(layer "In4.Cu")
	)
	(gr_line
		(start 97.60331 -27.808682)
		(end 97.603056 -27.808682)
		(stroke
			(width 0.2)
			(type default)
		)
		(layer "In4.Cu")
	)
	(gr_line
		(start 97.60331 -7.488682)
		(end 97.603056 -7.488682)
		(stroke
			(width 0.2)
			(type default)
		)
		(layer "In4.Cu")
	)
	(gr_arc
		(start 97.782634 4.807712)
		(mid 98.141028 5.165725)
		(end 97.782888 5.523992)
		(stroke
			(width 0.2)
			(type default)
		)
		(layer "In4.Cu")
	)
	(gr_line
		(start 97.782888 5.523992)
		(end 96.766888 5.523992)
		(stroke
			(width 0.2)
			(type default)
		)
		(layer "In4.Cu")
	)
	(gr_line
		(start 98.49993 14.53007)
		(end 99.000056 14.029944)
		(stroke
			(width 1.524)
			(type default)
		)
		(layer "In4.Cu")
	)
	(gr_arc
		(start 98.557334 -27.33167)
		(mid 97.841816 -27.093164)
		(end 97.60331 -27.808682)
		(stroke
			(width 0.2)
			(type default)
		)
		(layer "In4.Cu")
	)
	(gr_arc
		(start 98.557334 -7.01167)
		(mid 97.841816 -6.773164)
		(end 97.60331 -7.488682)
		(stroke
			(width 0.2)
			(type default)
		)
		(layer "In4.Cu")
	)
	(gr_line
		(start 98.557588 -27.33167)
		(end 98.557334 -27.33167)
		(stroke
			(width 0.2)
			(type default)
		)
		(layer "In4.Cu")
	)
	(gr_line
		(start 98.557588 -7.01167)
		(end 98.557334 -7.01167)
		(stroke
			(width 0.2)
			(type default)
		)
		(layer "In4.Cu")
	)
	(gr_arc
		(start 98.602546 -29.808678)
		(mid 99.318216 -30.047616)
		(end 99.556824 -29.33192)
		(stroke
			(width 0.2)
			(type default)
		)
		(layer "In4.Cu")
	)
	(gr_arc
		(start 98.602546 -9.488678)
		(mid 99.318216 -9.727616)
		(end 99.556824 -9.01192)
		(stroke
			(width 0.2)
			(type default)
		)
		(layer "In4.Cu")
	)
	(gr_arc
		(start 99.000056 6.729984)
		(mid 99.058605 6.588635)
		(end 99.199954 6.530086)
		(stroke
			(width 1.524)
			(type default)
		)
		(layer "In4.Cu")
	)
	(gr_line
		(start 99.000056 14.029944)
		(end 99.000056 6.729984)
		(stroke
			(width 1.524)
			(type default)
		)
		(layer "In4.Cu")
	)
	(gr_line
		(start 99.199954 6.530086)
		(end 107.750102 6.530086)
		(stroke
			(width 1.524)
			(type default)
		)
		(layer "In4.Cu")
	)
	(gr_line
		(start 99.556824 -29.33192)
		(end 99.557078 -29.33192)
		(stroke
			(width 0.2)
			(type default)
		)
		(layer "In4.Cu")
	)
	(gr_line
		(start 99.556824 -9.01192)
		(end 99.557078 -9.01192)
		(stroke
			(width 0.2)
			(type default)
		)
		(layer "In4.Cu")
	)
	(gr_line
		(start 99.557078 -29.33192)
		(end 98.557588 -27.33167)
		(stroke
			(width 0.2)
			(type default)
		)
		(layer "In4.Cu")
	)
	(gr_line
		(start 99.557078 -9.01192)
		(end 98.557588 -7.01167)
		(stroke
			(width 0.2)
			(type default)
		)
		(layer "In4.Cu")
	)
	(gr_arc
		(start 99.60229 -33.831276)
		(mid 99.840542 -34.547048)
		(end 100.556314 -34.308796)
		(stroke
			(width 0.2)
			(type default)
		)
		(layer "In4.Cu")
	)
	(gr_arc
		(start 99.60229 -13.511276)
		(mid 99.840542 -14.227048)
		(end 100.556314 -13.988796)
		(stroke
			(width 0.2)
			(type default)
		)
		(layer "In4.Cu")
	)
	(gr_line
		(start 100.556314 -34.308796)
		(end 101.557074 -32.3088)
		(stroke
			(width 0.2)
			(type default)
		)
		(layer "In4.Cu")
	)
	(gr_line
		(start 100.556314 -13.988796)
		(end 101.557074 -11.9888)
		(stroke
			(width 0.2)
			(type default)
		)
		(layer "In4.Cu")
	)
	(gr_line
		(start 100.60305 -31.831026)
		(end 99.60229 -33.831276)
		(stroke
			(width 0.2)
			(type default)
		)
		(layer "In4.Cu")
	)
	(gr_line
		(start 100.60305 -11.511026)
		(end 99.60229 -13.511276)
		(stroke
			(width 0.2)
			(type default)
		)
		(layer "In4.Cu")
	)
	(gr_line
		(start 101.557074 -32.3088)
		(end 101.557074 -32.308546)
		(stroke
			(width 0.2)
			(type default)
		)
		(layer "In4.Cu")
	)
	(gr_arc
		(start 101.557074 -32.308546)
		(mid 101.318822 -31.592774)
		(end 100.60305 -31.831026)
		(stroke
			(width 0.2)
			(type default)
		)
		(layer "In4.Cu")
	)
	(gr_line
		(start 101.557074 -11.9888)
		(end 101.557074 -11.988546)
		(stroke
			(width 0.2)
			(type default)
		)
		(layer "In4.Cu")
	)
	(gr_arc
		(start 101.557074 -11.988546)
		(mid 101.318822 -11.272774)
		(end 100.60305 -11.511026)
		(stroke
			(width 0.2)
			(type default)
		)
		(layer "In4.Cu")
	)
	(gr_line
		(start 101.60254 -27.808936)
		(end 102.603046 -29.808932)
		(stroke
			(width 0.2)
			(type default)
		)
		(layer "In4.Cu")
	)
	(gr_line
		(start 101.60254 -7.488936)
		(end 102.603046 -9.488932)
		(stroke
			(width 0.2)
			(type default)
		)
		(layer "In4.Cu")
	)
	(gr_arc
		(start 102.556564 -27.331416)
		(mid 101.840792 -27.093164)
		(end 101.60254 -27.808936)
		(stroke
			(width 0.2)
			(type default)
		)
		(layer "In4.Cu")
	)
	(gr_arc
		(start 102.556564 -7.011416)
		(mid 101.840792 -6.773164)
		(end 101.60254 -7.488936)
		(stroke
			(width 0.2)
			(type default)
		)
		(layer "In4.Cu")
	)
	(gr_line
		(start 102.603046 -29.808932)
		(end 102.6033 -29.808932)
		(stroke
			(width 0.2)
			(type default)
		)
		(layer "In4.Cu")
	)
	(gr_line
		(start 102.603046 -9.488932)
		(end 102.6033 -9.488932)
		(stroke
			(width 0.2)
			(type default)
		)
		(layer "In4.Cu")
	)
	(gr_arc
		(start 102.6033 -29.808932)
		(mid 103.31892 -30.047387)
		(end 103.557324 -29.331666)
		(stroke
			(width 0.2)
			(type default)
		)
		(layer "In4.Cu")
	)
	(gr_arc
		(start 102.6033 -9.488932)
		(mid 103.31892 -9.727387)
		(end 103.557324 -9.011666)
		(stroke
			(width 0.2)
			(type default)
		)
		(layer "In4.Cu")
	)
	(gr_line
		(start 103.557324 -29.331666)
		(end 102.556564 -27.331416)
		(stroke
			(width 0.2)
			(type default)
		)
		(layer "In4.Cu")
	)
	(gr_line
		(start 103.557324 -9.011666)
		(end 102.556564 -7.011416)
		(stroke
			(width 0.2)
			(type default)
		)
		(layer "In4.Cu")
	)
	(gr_line
		(start 103.602536 -33.83153)
		(end 103.60279 -33.83153)
		(stroke
			(width 0.2)
			(type default)
		)
		(layer "In4.Cu")
	)
	(gr_line
		(start 103.602536 -13.51153)
		(end 103.60279 -13.51153)
		(stroke
			(width 0.2)
			(type default)
		)
		(layer "In4.Cu")
	)
	(gr_arc
		(start 103.60279 -33.83153)
		(mid 103.841296 -34.547048)
		(end 104.556814 -34.308542)
		(stroke
			(width 0.2)
			(type default)
		)
		(layer "In4.Cu")
	)
	(gr_arc
		(start 103.60279 -13.51153)
		(mid 103.841296 -14.227048)
		(end 104.556814 -13.988542)
		(stroke
			(width 0.2)
			(type default)
		)
		(layer "In4.Cu")
	)
	(gr_line
		(start 104.556814 -34.308542)
		(end 104.557068 -34.308542)
		(stroke
			(width 0.2)
			(type default)
		)
		(layer "In4.Cu")
	)
	(gr_line
		(start 104.556814 -13.988542)
		(end 104.557068 -13.988542)
		(stroke
			(width 0.2)
			(type default)
		)
		(layer "In4.Cu")
	)
	(gr_line
		(start 104.557068 -34.308542)
		(end 105.556304 -32.308546)
		(stroke
			(width 0.2)
			(type default)
		)
		(layer "In4.Cu")
	)
	(gr_line
		(start 104.557068 -13.988542)
		(end 105.556304 -11.988546)
		(stroke
			(width 0.2)
			(type default)
		)
		(layer "In4.Cu")
	)
	(gr_line
		(start 104.602026 -31.83128)
		(end 103.602536 -33.83153)
		(stroke
			(width 0.2)
			(type default)
		)
		(layer "In4.Cu")
	)
	(gr_line
		(start 104.602026 -11.51128)
		(end 103.602536 -13.51153)
		(stroke
			(width 0.2)
			(type default)
		)
		(layer "In4.Cu")
	)
	(gr_line
		(start 104.60228 -31.83128)
		(end 104.602026 -31.83128)
		(stroke
			(width 0.2)
			(type default)
		)
		(layer "In4.Cu")
	)
	(gr_line
		(start 104.60228 -11.51128)
		(end 104.602026 -11.51128)
		(stroke
			(width 0.2)
			(type default)
		)
		(layer "In4.Cu")
	)
	(gr_arc
		(start 105.556304 -32.308546)
		(mid 105.31795 -31.592723)
		(end 104.60228 -31.83128)
		(stroke
			(width 0.2)
			(type default)
		)
		(layer "In4.Cu")
	)
	(gr_arc
		(start 105.556304 -11.988546)
		(mid 105.31795 -11.272723)
		(end 104.60228 -11.51128)
		(stroke
			(width 0.2)
			(type default)
		)
		(layer "In4.Cu")
	)
	(gr_line
		(start 105.602786 -27.808682)
		(end 106.602276 -29.808678)
		(stroke
			(width 0.2)
			(type default)
		)
		(layer "In4.Cu")
	)
	(gr_line
		(start 105.602786 -7.488682)
		(end 106.602276 -9.488678)
		(stroke
			(width 0.2)
			(type default)
		)
		(layer "In4.Cu")
	)
	(gr_line
		(start 105.60304 -27.808682)
		(end 105.602786 -27.808682)
		(stroke
			(width 0.2)
			(type default)
		)
		(layer "In4.Cu")
	)
	(gr_line
		(start 105.60304 -7.488682)
		(end 105.602786 -7.488682)
		(stroke
			(width 0.2)
			(type default)
		)
		(layer "In4.Cu")
	)
	(gr_arc
		(start 106.557064 -27.33167)
		(mid 105.841546 -27.093164)
		(end 105.60304 -27.808682)
		(stroke
			(width 0.2)
			(type default)
		)
		(layer "In4.Cu")
	)
	(gr_arc
		(start 106.557064 -7.01167)
		(mid 105.841546 -6.773164)
		(end 105.60304 -7.488682)
		(stroke
			(width 0.2)
			(type default)
		)
		(layer "In4.Cu")
	)
	(gr_line
		(start 106.557318 -27.33167)
		(end 106.557064 -27.33167)
		(stroke
			(width 0.2)
			(type default)
		)
		(layer "In4.Cu")
	)
	(gr_line
		(start 106.557318 -7.01167)
		(end 106.557064 -7.01167)
		(stroke
			(width 0.2)
			(type default)
		)
		(layer "In4.Cu")
	)
	(gr_arc
		(start 106.602276 -29.808678)
		(mid 107.317946 -30.047616)
		(end 107.556554 -29.33192)
		(stroke
			(width 0.2)
			(type default)
		)
		(layer "In4.Cu")
	)
	(gr_arc
		(start 106.602276 -9.488678)
		(mid 107.317946 -9.727616)
		(end 107.556554 -9.01192)
		(stroke
			(width 0.2)
			(type default)
		)
		(layer "In4.Cu")
	)
	(gr_line
		(start 107.556554 -29.33192)
		(end 107.556808 -29.33192)
		(stroke
			(width 0.2)
			(type default)
		)
		(layer "In4.Cu")
	)
	(gr_line
		(start 107.556554 -9.01192)
		(end 107.556808 -9.01192)
		(stroke
			(width 0.2)
			(type default)
		)
		(layer "In4.Cu")
	)
	(gr_line
		(start 107.556808 -29.33192)
		(end 106.557318 -27.33167)
		(stroke
			(width 0.2)
			(type default)
		)
		(layer "In4.Cu")
	)
	(gr_line
		(start 107.556808 -9.01192)
		(end 106.557318 -7.01167)
		(stroke
			(width 0.2)
			(type default)
		)
		(layer "In4.Cu")
	)
	(gr_line
		(start 107.603036 -33.83153)
		(end 107.60329 -33.83153)
		(stroke
			(width 0.2)
			(type default)
		)
		(layer "In4.Cu")
	)
	(gr_line
		(start 107.603036 -13.51153)
		(end 107.60329 -13.51153)
		(stroke
			(width 0.2)
			(type default)
		)
		(layer "In4.Cu")
	)
	(gr_arc
		(start 107.60329 -33.83153)
		(mid 107.841796 -34.547048)
		(end 108.557314 -34.308542)
		(stroke
			(width 0.2)
			(type default)
		)
		(layer "In4.Cu")
	)
	(gr_arc
		(start 107.60329 -13.51153)
		(mid 107.841796 -14.227048)
		(end 108.557314 -13.988542)
		(stroke
			(width 0.2)
			(type default)
		)
		(layer "In4.Cu")
	)
	(gr_arc
		(start 107.750102 6.530086)
		(mid 107.891451 6.588635)
		(end 107.95 6.729984)
		(stroke
			(width 1.524)
			(type default)
		)
		(layer "In4.Cu")
	)
	(gr_line
		(start 107.95 6.729984)
		(end 107.95 14.029944)
		(stroke
			(width 1.524)
			(type default)
		)
		(layer "In4.Cu")
	)
	(gr_line
		(start 107.95 14.029944)
		(end 108.450126 14.53007)
		(stroke
			(width 1.524)
			(type default)
		)
		(layer "In4.Cu")
	)
	(gr_line
		(start 108.450126 14.53007)
		(end 132.700014 14.53007)
		(stroke
			(width 7.5946)
			(type default)
		)
		(layer "In4.Cu")
	)
	(gr_line
		(start 108.557314 -34.308542)
		(end 108.557568 -34.308542)
		(stroke
			(width 0.2)
			(type default)
		)
		(layer "In4.Cu")
	)
	(gr_line
		(start 108.557314 -13.988542)
		(end 108.557568 -13.988542)
		(stroke
			(width 0.2)
			(type default)
		)
		(layer "In4.Cu")
	)
	(gr_line
		(start 108.557568 -34.308542)
		(end 109.556804 -32.308546)
		(stroke
			(width 0.2)
			(type default)
		)
		(layer "In4.Cu")
	)
	(gr_line
		(start 108.557568 -13.988542)
		(end 109.556804 -11.988546)
		(stroke
			(width 0.2)
			(type default)
		)
		(layer "In4.Cu")
	)
	(gr_line
		(start 108.602526 -31.83128)
		(end 107.603036 -33.83153)
		(stroke
			(width 0.2)
			(type default)
		)
		(layer "In4.Cu")
	)
	(gr_line
		(start 108.602526 -11.51128)
		(end 107.603036 -13.51153)
		(stroke
			(width 0.2)
			(type default)
		)
		(layer "In4.Cu")
	)
	(gr_line
		(start 108.60278 -31.83128)
		(end 108.602526 -31.83128)
		(stroke
			(width 0.2)
			(type default)
		)
		(layer "In4.Cu")
	)
	(gr_line
		(start 108.60278 -11.51128)
		(end 108.602526 -11.51128)
		(stroke
			(width 0.2)
			(type default)
		)
		(layer "In4.Cu")
	)
	(gr_line
		(start 109.242606 7.384542)
		(end 110.258352 7.384542)
		(stroke
			(width 0.2)
			(type default)
		)
		(layer "In4.Cu")
	)
	(gr_arc
		(start 109.242606 8.100822)
		(mid 108.884466 7.742682)
		(end 109.242606 7.384542)
		(stroke
			(width 0.2)
			(type default)
		)
		(layer "In4.Cu")
	)
	(gr_arc
		(start 109.556804 -32.308546)
		(mid 109.31845 -31.592723)
		(end 108.60278 -31.83128)
		(stroke
			(width 0.2)
			(type default)
		)
		(layer "In4.Cu")
	)
	(gr_arc
		(start 109.556804 -11.988546)
		(mid 109.31845 -11.272723)
		(end 108.60278 -11.51128)
		(stroke
			(width 0.2)
			(type default)
		)
		(layer "In4.Cu")
	)
	(gr_line
		(start 109.60227 -27.808936)
		(end 110.602776 -29.808932)
		(stroke
			(width 0.2)
			(type default)
		)
		(layer "In4.Cu")
	)
	(gr_line
		(start 109.60227 -7.488936)
		(end 110.602776 -9.488932)
		(stroke
			(width 0.2)
			(type default)
		)
		(layer "In4.Cu")
	)
	(gr_arc
		(start 110.258352 7.384542)
		(mid 110.616746 7.742555)
		(end 110.258606 8.100822)
		(stroke
			(width 0.2)
			(type default)
		)
		(layer "In4.Cu")
	)
	(gr_line
		(start 110.258606 8.100822)
		(end 109.242606 8.100822)
		(stroke
			(width 0.2)
			(type default)
		)
		(layer "In4.Cu")
	)
	(gr_arc
		(start 110.556294 -27.331416)
		(mid 109.840522 -27.093164)
		(end 109.60227 -27.808936)
		(stroke
			(width 0.2)
			(type default)
		)
		(layer "In4.Cu")
	)
	(gr_arc
		(start 110.556294 -7.011416)
		(mid 109.840522 -6.773164)
		(end 109.60227 -7.488936)
		(stroke
			(width 0.2)
			(type default)
		)
		(layer "In4.Cu")
	)
	(gr_line
		(start 110.56874 4.848352)
		(end 111.584486 4.848352)
		(stroke
			(width 0.2)
			(type default)
		)
		(layer "In4.Cu")
	)
	(gr_arc
		(start 110.56874 5.564632)
		(mid 110.2106 5.206492)
		(end 110.56874 4.848352)
		(stroke
			(width 0.2)
			(type default)
		)
		(layer "In4.Cu")
	)
	(gr_line
		(start 110.602776 -29.808932)
		(end 110.60303 -29.808932)
		(stroke
			(width 0.2)
			(type default)
		)
		(layer "In4.Cu")
	)
	(gr_line
		(start 110.602776 -9.488932)
		(end 110.60303 -9.488932)
		(stroke
			(width 0.2)
			(type default)
		)
		(layer "In4.Cu")
	)
	(gr_arc
		(start 110.60303 -29.808932)
		(mid 111.31865 -30.047387)
		(end 111.557054 -29.331666)
		(stroke
			(width 0.2)
			(type default)
		)
		(layer "In4.Cu")
	)
	(gr_arc
		(start 110.60303 -9.488932)
		(mid 111.31865 -9.727387)
		(end 111.557054 -9.011666)
		(stroke
			(width 0.2)
			(type default)
		)
		(layer "In4.Cu")
	)
	(gr_line
		(start 111.557054 -29.331666)
		(end 110.556294 -27.331416)
		(stroke
			(width 0.2)
			(type default)
		)
		(layer "In4.Cu")
	)
	(gr_line
		(start 111.557054 -9.011666)
		(end 110.556294 -7.011416)
		(stroke
			(width 0.2)
			(type default)
		)
		(layer "In4.Cu")
	)
	(gr_arc
		(start 111.584486 4.848352)
		(mid 111.94288 5.206365)
		(end 111.58474 5.564632)
		(stroke
			(width 0.2)
			(type default)
		)
		(layer "In4.Cu")
	)
	(gr_line
		(start 111.58474 5.564632)
		(end 110.56874 5.564632)
		(stroke
			(width 0.2)
			(type default)
		)
		(layer "In4.Cu")
	)
	(gr_arc
		(start 111.60252 -33.831276)
		(mid 111.840772 -34.547048)
		(end 112.556544 -34.308796)
		(stroke
			(width 0.2)
			(type default)
		)
		(layer "In4.Cu")
	)
	(gr_arc
		(start 111.60252 -13.511276)
		(mid 111.840772 -14.227048)
		(end 112.556544 -13.988796)
		(stroke
			(width 0.2)
			(type default)
		)
		(layer "In4.Cu")
	)
	(gr_line
		(start 111.833406 7.384542)
		(end 112.849152 7.384542)
		(stroke
			(width 0.2)
			(type default)
		)
		(layer "In4.Cu")
	)
	(gr_arc
		(start 111.833406 8.100822)
		(mid 111.475266 7.742682)
		(end 111.833406 7.384542)
		(stroke
			(width 0.2)
			(type default)
		)
		(layer "In4.Cu")
	)
	(gr_line
		(start 112.556544 -34.308796)
		(end 113.557304 -32.3088)
		(stroke
			(width 0.2)
			(type default)
		)
		(layer "In4.Cu")
	)
	(gr_line
		(start 112.556544 -13.988796)
		(end 113.557304 -11.9888)
		(stroke
			(width 0.2)
			(type default)
		)
		(layer "In4.Cu")
	)
	(gr_line
		(start 112.60328 -31.831026)
		(end 111.60252 -33.831276)
		(stroke
			(width 0.2)
			(type default)
		)
		(layer "In4.Cu")
	)
	(gr_line
		(start 112.60328 -11.511026)
		(end 111.60252 -13.511276)
		(stroke
			(width 0.2)
			(type default)
		)
		(layer "In4.Cu")
	)
	(gr_arc
		(start 112.849152 7.384542)
		(mid 113.207546 7.742555)
		(end 112.849406 8.100822)
		(stroke
			(width 0.2)
			(type default)
		)
		(layer "In4.Cu")
	)
	(gr_line
		(start 112.849406 8.100822)
		(end 111.833406 8.100822)
		(stroke
			(width 0.2)
			(type default)
		)
		(layer "In4.Cu")
	)
	(gr_line
		(start 113.15954 4.848352)
		(end 114.175286 4.848352)
		(stroke
			(width 0.2)
			(type default)
		)
		(layer "In4.Cu")
	)
	(gr_arc
		(start 113.15954 5.564632)
		(mid 112.8014 5.206492)
		(end 113.15954 4.848352)
		(stroke
			(width 0.2)
			(type default)
		)
		(layer "In4.Cu")
	)
	(gr_line
		(start 113.557304 -32.3088)
		(end 113.557304 -32.308546)
		(stroke
			(width 0.2)
			(type default)
		)
		(layer "In4.Cu")
	)
	(gr_arc
		(start 113.557304 -32.308546)
		(mid 113.319052 -31.592774)
		(end 112.60328 -31.831026)
		(stroke
			(width 0.2)
			(type default)
		)
		(layer "In4.Cu")
	)
	(gr_line
		(start 113.557304 -11.9888)
		(end 113.557304 -11.988546)
		(stroke
			(width 0.2)
			(type default)
		)
		(layer "In4.Cu")
	)
	(gr_arc
		(start 113.557304 -11.988546)
		(mid 113.319052 -11.272774)
		(end 112.60328 -11.511026)
		(stroke
			(width 0.2)
			(type default)
		)
		(layer "In4.Cu")
	)
	(gr_arc
		(start 114.175286 4.848352)
		(mid 114.53368 5.206365)
		(end 114.17554 5.564632)
		(stroke
			(width 0.2)
			(type default)
		)
		(layer "In4.Cu")
	)
	(gr_line
		(start 114.17554 5.564632)
		(end 113.15954 5.564632)
		(stroke
			(width 0.2)
			(type default)
		)
		(layer "In4.Cu")
	)
	(gr_line
		(start 114.424206 7.384542)
		(end 115.439952 7.384542)
		(stroke
			(width 0.2)
			(type default)
		)
		(layer "In4.Cu")
	)
	(gr_arc
		(start 114.424206 8.100822)
		(mid 114.066066 7.742682)
		(end 114.424206 7.384542)
		(stroke
			(width 0.2)
			(type default)
		)
		(layer "In4.Cu")
	)
	(gr_arc
		(start 115.439952 7.384542)
		(mid 115.798346 7.742555)
		(end 115.440206 8.100822)
		(stroke
			(width 0.2)
			(type default)
		)
		(layer "In4.Cu")
	)
	(gr_line
		(start 115.440206 8.100822)
		(end 114.424206 8.100822)
		(stroke
			(width 0.2)
			(type default)
		)
		(layer "In4.Cu")
	)
	(gr_line
		(start 115.75034 4.848352)
		(end 116.766086 4.848352)
		(stroke
			(width 0.2)
			(type default)
		)
		(layer "In4.Cu")
	)
	(gr_arc
		(start 115.75034 5.564632)
		(mid 115.3922 5.206492)
		(end 115.75034 4.848352)
		(stroke
			(width 0.2)
			(type default)
		)
		(layer "In4.Cu")
	)
	(gr_arc
		(start 115.78463 -32.885888)
		(mid 115.23726 -33.46069)
		(end 115.812062 -34.00806)
		(stroke
			(width 0.2)
			(type default)
		)
		(layer "In4.Cu")
	)
	(gr_line
		(start 115.78463 -32.883602)
		(end 115.78463 -32.885888)
		(stroke
			(width 0.2)
			(type default)
		)
		(layer "In4.Cu")
	)
	(gr_line
		(start 115.784884 -32.883348)
		(end 115.78463 -32.883602)
		(stroke
			(width 0.2)
			(type default)
		)
		(layer "In4.Cu")
	)
	(gr_line
		(start 115.812062 -34.0106)
		(end 116.675408 -33.989518)
		(stroke
			(width 0.2)
			(type default)
		)
		(layer "In4.Cu")
	)
	(gr_line
		(start 115.812062 -34.00806)
		(end 115.812062 -34.0106)
		(stroke
			(width 0.2)
			(type default)
		)
		(layer "In4.Cu")
	)
	(gr_line
		(start 116.647976 -32.864806)
		(end 116.647976 -32.862266)
		(stroke
			(width 0.2)
			(type default)
		)
		(layer "In4.Cu")
	)
	(gr_line
		(start 116.647976 -32.862266)
		(end 115.784884 -32.883348)
		(stroke
			(width 0.2)
			(type default)
		)
		(layer "In4.Cu")
	)
	(gr_line
		(start 116.675408 -33.989518)
		(end 116.675408 -33.987232)
		(stroke
			(width 0.2)
			(type default)
		)
		(layer "In4.Cu")
	)
	(gr_line
		(start 116.675408 -33.987232)
		(end 116.675408 -33.986978)
		(stroke
			(width 0.2)
			(type default)
		)
		(layer "In4.Cu")
	)
	(gr_arc
		(start 116.675408 -33.986978)
		(mid 117.222778 -33.412176)
		(end 116.647976 -32.864806)
		(stroke
			(width 0.2)
			(type default)
		)
		(layer "In4.Cu")
	)
	(gr_arc
		(start 116.766086 4.848352)
		(mid 117.12448 5.206365)
		(end 116.76634 5.564632)
		(stroke
			(width 0.2)
			(type default)
		)
		(layer "In4.Cu")
	)
	(gr_line
		(start 116.76634 5.564632)
		(end 115.75034 5.564632)
		(stroke
			(width 0.2)
			(type default)
		)
		(layer "In4.Cu")
	)
	(gr_line
		(start 117.015006 7.384542)
		(end 118.030752 7.384542)
		(stroke
			(width 0.2)
			(type default)
		)
		(layer "In4.Cu")
	)
	(gr_arc
		(start 117.015006 8.100822)
		(mid 116.656866 7.742682)
		(end 117.015006 7.384542)
		(stroke
			(width 0.2)
			(type default)
		)
		(layer "In4.Cu")
	)
	(gr_arc
		(start 118.030752 7.384542)
		(mid 118.389146 7.742555)
		(end 118.031006 8.100822)
		(stroke
			(width 0.2)
			(type default)
		)
		(layer "In4.Cu")
	)
	(gr_line
		(start 118.031006 8.100822)
		(end 117.015006 8.100822)
		(stroke
			(width 0.2)
			(type default)
		)
		(layer "In4.Cu")
	)
	(gr_line
		(start 118.34114 4.848352)
		(end 119.356886 4.848352)
		(stroke
			(width 0.2)
			(type default)
		)
		(layer "In4.Cu")
	)
	(gr_arc
		(start 118.34114 5.564632)
		(mid 117.983 5.206492)
		(end 118.34114 4.848352)
		(stroke
			(width 0.2)
			(type default)
		)
		(layer "In4.Cu")
	)
	(gr_arc
		(start 119.356886 4.848352)
		(mid 119.71528 5.206365)
		(end 119.35714 5.564632)
		(stroke
			(width 0.2)
			(type default)
		)
		(layer "In4.Cu")
	)
	(gr_line
		(start 119.35714 5.564632)
		(end 118.34114 5.564632)
		(stroke
			(width 0.2)
			(type default)
		)
		(layer "In4.Cu")
	)
	(gr_line
		(start 119.605806 7.384542)
		(end 120.621552 7.384542)
		(stroke
			(width 0.2)
			(type default)
		)
		(layer "In4.Cu")
	)
	(gr_arc
		(start 119.605806 8.100822)
		(mid 119.247666 7.742682)
		(end 119.605806 7.384542)
		(stroke
			(width 0.2)
			(type default)
		)
		(layer "In4.Cu")
	)
	(gr_arc
		(start 120.621552 7.384542)
		(mid 120.979946 7.742555)
		(end 120.621806 8.100822)
		(stroke
			(width 0.2)
			(type default)
		)
		(layer "In4.Cu")
	)
	(gr_line
		(start 120.621806 8.100822)
		(end 119.605806 8.100822)
		(stroke
			(width 0.2)
			(type default)
		)
		(layer "In4.Cu")
	)
	(gr_line
		(start 120.93194 4.848352)
		(end 121.947686 4.848352)
		(stroke
			(width 0.2)
			(type default)
		)
		(layer "In4.Cu")
	)
	(gr_arc
		(start 120.93194 5.564632)
		(mid 120.5738 5.206492)
		(end 120.93194 4.848352)
		(stroke
			(width 0.2)
			(type default)
		)
		(layer "In4.Cu")
	)
	(gr_arc
		(start 121.947686 4.848352)
		(mid 122.30608 5.206365)
		(end 121.94794 5.564632)
		(stroke
			(width 0.2)
			(type default)
		)
		(layer "In4.Cu")
	)
	(gr_line
		(start 121.94794 5.564632)
		(end 120.93194 5.564632)
		(stroke
			(width 0.2)
			(type default)
		)
		(layer "In4.Cu")
	)
	(gr_line
		(start 122.196606 7.384542)
		(end 123.212352 7.384542)
		(stroke
			(width 0.2)
			(type default)
		)
		(layer "In4.Cu")
	)
	(gr_arc
		(start 122.196606 8.100822)
		(mid 121.838466 7.742682)
		(end 122.196606 7.384542)
		(stroke
			(width 0.2)
			(type default)
		)
		(layer "In4.Cu")
	)
	(gr_arc
		(start 123.212352 7.384542)
		(mid 123.570746 7.742555)
		(end 123.212606 8.100822)
		(stroke
			(width 0.2)
			(type default)
		)
		(layer "In4.Cu")
	)
	(gr_line
		(start 123.212606 8.100822)
		(end 122.196606 8.100822)
		(stroke
			(width 0.2)
			(type default)
		)
		(layer "In4.Cu")
	)
	(gr_line
		(start 123.52274 4.848352)
		(end 124.538486 4.848352)
		(stroke
			(width 0.2)
			(type default)
		)
		(layer "In4.Cu")
	)
	(gr_arc
		(start 123.52274 5.564632)
		(mid 123.1646 5.206492)
		(end 123.52274 4.848352)
		(stroke
			(width 0.2)
			(type default)
		)
		(layer "In4.Cu")
	)
	(gr_arc
		(start 124.538486 4.848352)
		(mid 124.89688 5.206365)
		(end 124.53874 5.564632)
		(stroke
			(width 0.2)
			(type default)
		)
		(layer "In4.Cu")
	)
	(gr_line
		(start 124.53874 5.564632)
		(end 123.52274 5.564632)
		(stroke
			(width 0.2)
			(type default)
		)
		(layer "In4.Cu")
	)
	(gr_line
		(start 124.787406 7.384542)
		(end 125.803406 7.384542)
		(stroke
			(width 0.2)
			(type default)
		)
		(layer "In4.Cu")
	)
	(gr_arc
		(start 124.78766 8.100822)
		(mid 124.429266 7.742809)
		(end 124.787406 7.384542)
		(stroke
			(width 0.2)
			(type default)
		)
		(layer "In4.Cu")
	)
	(gr_line
		(start 125.639576 -34.426906)
		(end 126.51105 -34.426906)
		(stroke
			(width 0.2)
			(type default)
		)
		(layer "In4.Cu")
	)
	(gr_arc
		(start 125.639576 -33.304226)
		(mid 125.078236 -33.865566)
		(end 125.639576 -34.426906)
		(stroke
			(width 0.2)
			(type default)
		)
		(layer "In4.Cu")
	)
	(gr_arc
		(start 125.803406 7.384542)
		(mid 126.161546 7.742682)
		(end 125.803406 8.100822)
		(stroke
			(width 0.2)
			(type default)
		)
		(layer "In4.Cu")
	)
	(gr_line
		(start 125.803406 8.100822)
		(end 124.78766 8.100822)
		(stroke
			(width 0.2)
			(type default)
		)
		(layer "In4.Cu")
	)
	(gr_line
		(start 126.11354 4.848352)
		(end 127.129286 4.848352)
		(stroke
			(width 0.2)
			(type default)
		)
		(layer "In4.Cu")
	)
	(gr_arc
		(start 126.11354 5.564632)
		(mid 125.7554 5.206492)
		(end 126.11354 4.848352)
		(stroke
			(width 0.2)
			(type default)
		)
		(layer "In4.Cu")
	)
	(gr_arc
		(start 126.51105 -34.426906)
		(mid 127.072644 -33.865693)
		(end 126.511304 -33.304226)
		(stroke
			(width 0.2)
			(type default)
		)
		(layer "In4.Cu")
	)
	(gr_line
		(start 126.511304 -33.304226)
		(end 125.639576 -33.304226)
		(stroke
			(width 0.2)
			(type default)
		)
		(layer "In4.Cu")
	)
	(gr_arc
		(start 127.129286 4.848352)
		(mid 127.48768 5.206365)
		(end 127.12954 5.564632)
		(stroke
			(width 0.2)
			(type default)
		)
		(layer "In4.Cu")
	)
	(gr_line
		(start 127.12954 5.564632)
		(end 126.11354 5.564632)
		(stroke
			(width 0.2)
			(type default)
		)
		(layer "In4.Cu")
	)
	(gr_line
		(start 127.378206 7.384542)
		(end 128.393952 7.384542)
		(stroke
			(width 0.2)
			(type default)
		)
		(layer "In4.Cu")
	)
	(gr_arc
		(start 127.378206 8.100822)
		(mid 127.020066 7.742682)
		(end 127.378206 7.384542)
		(stroke
			(width 0.2)
			(type default)
		)
		(layer "In4.Cu")
	)
	(gr_arc
		(start 128.393952 7.384542)
		(mid 128.752346 7.742555)
		(end 128.394206 8.100822)
		(stroke
			(width 0.2)
			(type default)
		)
		(layer "In4.Cu")
	)
	(gr_line
		(start 128.394206 8.100822)
		(end 127.378206 8.100822)
		(stroke
			(width 0.2)
			(type default)
		)
		(layer "In4.Cu")
	)
	(gr_line
		(start 128.70434 4.848352)
		(end 129.720086 4.848352)
		(stroke
			(width 0.2)
			(type default)
		)
		(layer "In4.Cu")
	)
	(gr_arc
		(start 128.70434 5.564632)
		(mid 128.3462 5.206492)
		(end 128.70434 4.848352)
		(stroke
			(width 0.2)
			(type default)
		)
		(layer "In4.Cu")
	)
	(gr_arc
		(start 129.720086 4.848352)
		(mid 130.07848 5.206365)
		(end 129.72034 5.564632)
		(stroke
			(width 0.2)
			(type default)
		)
		(layer "In4.Cu")
	)
	(gr_line
		(start 129.72034 5.564632)
		(end 128.70434 5.564632)
		(stroke
			(width 0.2)
			(type default)
		)
		(layer "In4.Cu")
	)
	(gr_line
		(start 132.700014 14.53007)
		(end 133.199886 14.029944)
		(stroke
			(width 1.524)
			(type default)
		)
		(layer "In4.Cu")
	)
	(gr_arc
		(start 133.199886 0.199898)
		(mid 133.258599 0.058533)
		(end 133.400038 0)
		(stroke
			(width 1.524)
			(type default)
		)
		(layer "In4.Cu")
	)
	(gr_line
		(start 133.199886 14.029944)
		(end 133.199886 0.199898)
		(stroke
			(width 1.524)
			(type default)
		)
		(layer "In4.Cu")
	)
	(gr_line
		(start 133.400038 0)
		(end 137.385806 0)
		(stroke
			(width 1.524)
			(type default)
		)
		(layer "In4.Cu")
	)
	(gr_arc
		(start 138.092942 -0.292862)
		(mid 137.768489 -0.076142)
		(end 137.385806 0)
		(stroke
			(width 1.524)
			(type default)
		)
		(layer "In4.Cu")
	)
	(gr_line
		(start 138.092942 -0.292862)
		(end 138.507216 -0.707136)
		(stroke
			(width 1.524)
			(type default)
		)
		(layer "In4.Cu")
	)
	(gr_arc
		(start 138.800078 -7.590028)
		(mid 140.5001 -9.29005)
		(end 142.200122 -7.590028)
		(stroke
			(width 1.524)
			(type default)
		)
		(layer "In4.Cu")
	)
	(gr_arc
		(start 138.800078 -1.414272)
		(mid 138.724001 -1.031565)
		(end 138.507216 -0.707136)
		(stroke
			(width 1.524)
			(type default)
		)
		(layer "In4.Cu")
	)
	(gr_line
		(start 138.800078 -1.414272)
		(end 138.800078 -7.590028)
		(stroke
			(width 1.524)
			(type default)
		)
		(layer "In4.Cu")
	)
	(gr_line
		(start 142.200122 -7.590028)
		(end 142.200122 -1.414272)
		(stroke
			(width 1.524)
			(type default)
		)
		(layer "In4.Cu")
	)
	(gr_arc
		(start 142.492984 -0.707136)
		(mid 142.276252 -1.031587)
		(end 142.200122 -1.414272)
		(stroke
			(width 1.524)
			(type default)
		)
		(layer "In4.Cu")
	)
	(gr_line
		(start 142.492984 -0.707136)
		(end 142.907004 -0.292862)
		(stroke
			(width 1.524)
			(type default)
		)
		(layer "In4.Cu")
	)
	(gr_arc
		(start 143.61414 0)
		(mid 143.231439 -0.076086)
		(end 142.907004 -0.292862)
		(stroke
			(width 1.524)
			(type default)
		)
		(layer "In4.Cu")
	)
	(gr_line
		(start 143.61414 0)
		(end 146.500088 0)
		(stroke
			(width 1.524)
			(type default)
		)
		(layer "In4.Cu")
	)
	(gr_line
		(start 144.085818 -35.200082)
		(end 3.414268 -35.200082)
		(stroke
			(width 1.524)
			(type default)
		)
		(layer "In4.Cu")
	)
	(gr_arc
		(start 144.085818 -35.200082)
		(mid 144.468527 -35.124008)
		(end 144.792954 -34.90722)
		(stroke
			(width 1.524)
			(type default)
		)
		(layer "In4.Cu")
	)
	(gr_line
		(start 147.207224 -32.49295)
		(end 144.792954 -34.90722)
		(stroke
			(width 1.524)
			(type default)
		)
		(layer "In4.Cu")
	)
	(gr_arc
		(start 147.207224 -32.49295)
		(mid 147.423949 -32.168498)
		(end 147.500086 -31.785814)
		(stroke
			(width 1.524)
			(type default)
		)
		(layer "In4.Cu")
	)
	(gr_arc
		(start 147.500086 -0.999998)
		(mid 147.207192 -0.292898)
		(end 146.500088 0)
		(stroke
			(width 1.524)
			(type default)
		)
		(layer "In4.Cu")
	)
	(gr_line
		(start 147.500086 -0.999998)
		(end 147.500086 -31.785814)
		(stroke
			(width 1.524)
			(type default)
		)
		(layer "In4.Cu")
	)
	(gr_line
		(start 0 -31.785814)
		(end 0 -0.999998)
		(stroke
			(width 0.05)
			(type default)
		)
		(layer "Edge.Cuts")
	)
	(gr_arc
		(start 0 -31.785814)
		(mid 0.076081 -32.168518)
		(end 0.292862 -32.49295)
		(stroke
			(width 0.05)
			(type default)
		)
		(layer "Edge.Cuts")
	)
	(gr_arc
		(start 0.999998 0)
		(mid 0.292893 -0.292893)
		(end 0 -0.999998)
		(stroke
			(width 0.05)
			(type default)
		)
		(layer "Edge.Cuts")
	)
	(gr_line
		(start 0.999998 0)
		(end 3.885692 0)
		(stroke
			(width 0.05)
			(type default)
		)
		(layer "Edge.Cuts")
	)
	(gr_line
		(start 2.707132 -34.90722)
		(end 0.292862 -32.49295)
		(stroke
			(width 0.05)
			(type default)
		)
		(layer "Edge.Cuts")
	)
	(gr_arc
		(start 2.707132 -34.90722)
		(mid 3.031582 -35.123959)
		(end 3.414268 -35.200082)
		(stroke
			(width 0.05)
			(type default)
		)
		(layer "Edge.Cuts")
	)
	(gr_arc
		(start 4.19989 -25.584912)
		(mid 6.999986 -28.385008)
		(end 9.800082 -25.584912)
		(stroke
			(width 0.05)
			(type default)
		)
		(layer "Edge.Cuts")
	)
	(gr_arc
		(start 4.592828 -0.292862)
		(mid 4.268379 -0.076123)
		(end 3.885692 0)
		(stroke
			(width 0.05)
			(type default)
		)
		(layer "Edge.Cuts")
	)
	(gr_line
		(start 4.592828 -0.292862)
		(end 5.007102 -0.707136)
		(stroke
			(width 0.05)
			(type default)
		)
		(layer "Edge.Cuts")
	)
	(gr_arc
		(start 5.299964 -7.590028)
		(mid 6.999986 -9.29005)
		(end 8.700008 -7.590028)
		(stroke
			(width 0.05)
			(type default)
		)
		(layer "Edge.Cuts")
	)
	(gr_arc
		(start 5.299964 -1.414272)
		(mid 5.223886 -1.031566)
		(end 5.007102 -0.707136)
		(stroke
			(width 0.05)
			(type default)
		)
		(layer "Edge.Cuts")
	)
	(gr_line
		(start 5.299964 -1.414272)
		(end 5.299964 -7.590028)
		(stroke
			(width 0.05)
			(type default)
		)
		(layer "Edge.Cuts")
	)
	(gr_line
		(start 8.700008 -7.590028)
		(end 8.700008 -1.414272)
		(stroke
			(width 0.05)
			(type default)
		)
		(layer "Edge.Cuts")
	)
	(gr_arc
		(start 8.99287 -0.707136)
		(mid 8.776129 -1.031585)
		(end 8.700008 -1.414272)
		(stroke
			(width 0.05)
			(type default)
		)
		(layer "Edge.Cuts")
	)
	(gr_line
		(start 8.99287 -0.707136)
		(end 9.407144 -0.292862)
		(stroke
			(width 0.05)
			(type default)
		)
		(layer "Edge.Cuts")
	)
	(gr_arc
		(start 9.800082 -25.584912)
		(mid 6.999986 -22.784816)
		(end 4.19989 -25.584912)
		(stroke
			(width 0.05)
			(type default)
		)
		(layer "Edge.Cuts")
	)
	(gr_arc
		(start 10.11428 0)
		(mid 9.73157 -0.076073)
		(end 9.407144 -0.292862)
		(stroke
			(width 0.05)
			(type default)
		)
		(layer "Edge.Cuts")
	)
	(gr_line
		(start 10.11428 0)
		(end 14.349984 0)
		(stroke
			(width 0.05)
			(type default)
		)
		(layer "Edge.Cuts")
	)
	(gr_arc
		(start 14.349984 0)
		(mid 14.491333 0.058549)
		(end 14.549882 0.199898)
		(stroke
			(width 0.05)
			(type default)
		)
		(layer "Edge.Cuts")
	)
	(gr_line
		(start 14.549882 0.199898)
		(end 14.549882 14.029944)
		(stroke
			(width 0.05)
			(type default)
		)
		(layer "Edge.Cuts")
	)
	(gr_line
		(start 14.549882 14.029944)
		(end 15.050008 14.53007)
		(stroke
			(width 0.05)
			(type default)
		)
		(layer "Edge.Cuts")
	)
	(gr_line
		(start 15.050008 14.53007)
		(end 40.679878 14.53007)
		(stroke
			(width 0.05)
			(type default)
		)
		(layer "Edge.Cuts")
	)
	(gr_line
		(start 40.679878 14.53007)
		(end 41.180004 14.029944)
		(stroke
			(width 0.05)
			(type default)
		)
		(layer "Edge.Cuts")
	)
	(gr_arc
		(start 41.180004 9.329928)
		(mid 42.380154 8.129778)
		(end 43.58005 9.329928)
		(stroke
			(width 0.05)
			(type default)
		)
		(layer "Edge.Cuts")
	)
	(gr_line
		(start 41.180004 14.029944)
		(end 41.180004 9.329928)
		(stroke
			(width 0.05)
			(type default)
		)
		(layer "Edge.Cuts")
	)
	(gr_line
		(start 43.58005 9.329928)
		(end 43.58005 14.029944)
		(stroke
			(width 0.05)
			(type default)
		)
		(layer "Edge.Cuts")
	)
	(gr_line
		(start 43.58005 14.029944)
		(end 44.079922 14.53007)
		(stroke
			(width 0.05)
			(type default)
		)
		(layer "Edge.Cuts")
	)
	(gr_line
		(start 44.079922 14.53007)
		(end 98.49993 14.53007)
		(stroke
			(width 0.05)
			(type default)
		)
		(layer "Edge.Cuts")
	)
	(gr_line
		(start 98.49993 14.53007)
		(end 99.000056 14.029944)
		(stroke
			(width 0.05)
			(type default)
		)
		(layer "Edge.Cuts")
	)
	(gr_arc
		(start 99.000056 6.729984)
		(mid 99.058605 6.588635)
		(end 99.199954 6.530086)
		(stroke
			(width 0.05)
			(type default)
		)
		(layer "Edge.Cuts")
	)
	(gr_line
		(start 99.000056 14.029944)
		(end 99.000056 6.729984)
		(stroke
			(width 0.05)
			(type default)
		)
		(layer "Edge.Cuts")
	)
	(gr_line
		(start 99.199954 6.530086)
		(end 107.750102 6.530086)
		(stroke
			(width 0.05)
			(type default)
		)
		(layer "Edge.Cuts")
	)
	(gr_arc
		(start 107.750102 6.530086)
		(mid 107.891451 6.588635)
		(end 107.95 6.729984)
		(stroke
			(width 0.05)
			(type default)
		)
		(layer "Edge.Cuts")
	)
	(gr_line
		(start 107.95 6.729984)
		(end 107.95 14.029944)
		(stroke
			(width 0.05)
			(type default)
		)
		(layer "Edge.Cuts")
	)
	(gr_line
		(start 107.95 14.029944)
		(end 108.450126 14.53007)
		(stroke
			(width 0.05)
			(type default)
		)
		(layer "Edge.Cuts")
	)
	(gr_line
		(start 108.450126 14.53007)
		(end 132.700014 14.53007)
		(stroke
			(width 0.05)
			(type default)
		)
		(layer "Edge.Cuts")
	)
	(gr_line
		(start 132.700014 14.53007)
		(end 133.199886 14.029944)
		(stroke
			(width 0.05)
			(type default)
		)
		(layer "Edge.Cuts")
	)
	(gr_arc
		(start 133.199886 0.199898)
		(mid 133.258599 0.058533)
		(end 133.400038 0)
		(stroke
			(width 0.05)
			(type default)
		)
		(layer "Edge.Cuts")
	)
	(gr_line
		(start 133.199886 14.029944)
		(end 133.199886 0.199898)
		(stroke
			(width 0.05)
			(type default)
		)
		(layer "Edge.Cuts")
	)
	(gr_line
		(start 133.400038 0)
		(end 137.385806 0)
		(stroke
			(width 0.05)
			(type default)
		)
		(layer "Edge.Cuts")
	)
	(gr_arc
		(start 137.700004 -25.584912)
		(mid 140.5001 -28.385008)
		(end 143.299942 -25.584912)
		(stroke
			(width 0.05)
			(type default)
		)
		(layer "Edge.Cuts")
	)
	(gr_arc
		(start 138.092942 -0.292862)
		(mid 137.768489 -0.076142)
		(end 137.385806 0)
		(stroke
			(width 0.05)
			(type default)
		)
		(layer "Edge.Cuts")
	)
	(gr_line
		(start 138.092942 -0.292862)
		(end 138.507216 -0.707136)
		(stroke
			(width 0.05)
			(type default)
		)
		(layer "Edge.Cuts")
	)
	(gr_arc
		(start 138.800078 -7.590028)
		(mid 140.5001 -9.29005)
		(end 142.200122 -7.590028)
		(stroke
			(width 0.05)
			(type default)
		)
		(layer "Edge.Cuts")
	)
	(gr_arc
		(start 138.800078 -1.414272)
		(mid 138.724001 -1.031565)
		(end 138.507216 -0.707136)
		(stroke
			(width 0.05)
			(type default)
		)
		(layer "Edge.Cuts")
	)
	(gr_line
		(start 138.800078 -1.414272)
		(end 138.800078 -7.590028)
		(stroke
			(width 0.05)
			(type default)
		)
		(layer "Edge.Cuts")
	)
	(gr_line
		(start 142.200122 -7.590028)
		(end 142.200122 -1.414272)
		(stroke
			(width 0.05)
			(type default)
		)
		(layer "Edge.Cuts")
	)
	(gr_arc
		(start 142.492984 -0.707136)
		(mid 142.276252 -1.031587)
		(end 142.200122 -1.414272)
		(stroke
			(width 0.05)
			(type default)
		)
		(layer "Edge.Cuts")
	)
	(gr_line
		(start 142.492984 -0.707136)
		(end 142.907004 -0.292862)
		(stroke
			(width 0.05)
			(type default)
		)
		(layer "Edge.Cuts")
	)
	(gr_arc
		(start 143.299942 -25.584912)
		(mid 140.5001 -22.78507)
		(end 137.700004 -25.584912)
		(stroke
			(width 0.05)
			(type default)
		)
		(layer "Edge.Cuts")
	)
	(gr_arc
		(start 143.61414 0)
		(mid 143.231439 -0.076086)
		(end 142.907004 -0.292862)
		(stroke
			(width 0.05)
			(type default)
		)
		(layer "Edge.Cuts")
	)
	(gr_line
		(start 143.61414 0)
		(end 146.500088 0)
		(stroke
			(width 0.05)
			(type default)
		)
		(layer "Edge.Cuts")
	)
	(gr_line
		(start 144.085818 -35.200082)
		(end 3.414268 -35.200082)
		(stroke
			(width 0.05)
			(type default)
		)
		(layer "Edge.Cuts")
	)
	(gr_arc
		(start 144.085818 -35.200082)
		(mid 144.468527 -35.124008)
		(end 144.792954 -34.90722)
		(stroke
			(width 0.05)
			(type default)
		)
		(layer "Edge.Cuts")
	)
	(gr_line
		(start 147.207224 -32.49295)
		(end 144.792954 -34.90722)
		(stroke
			(width 0.05)
			(type default)
		)
		(layer "Edge.Cuts")
	)
	(gr_arc
		(start 147.207224 -32.49295)
		(mid 147.423949 -32.168498)
		(end 147.500086 -31.785814)
		(stroke
			(width 0.05)
			(type default)
		)
		(layer "Edge.Cuts")
	)
	(gr_arc
		(start 147.500086 -0.999998)
		(mid 147.207192 -0.292898)
		(end 146.500088 0)
		(stroke
			(width 0.05)
			(type default)
		)
		(layer "Edge.Cuts")
	)
	(gr_line
		(start 147.500086 -0.999998)
		(end 147.500086 -31.785814)
		(stroke
			(width 0.05)
			(type default)
		)
		(layer "Edge.Cuts")
	)
	(via
		(at 27.9146 -7.239)
		(size 0.7112)
		(drill 0.3556)
		(layers "F.Cu" "B.Cu")
		(net "P3V3_VCC")
	)
	(segment
		(start 27.7876 -7.239)
		(end 27.9146 -7.239)
		(width 0.508)
		(layer "B.Cu")
		(net "P3V3_VCC")
	)
	(segment
		(start 24.623014 -7.431786)
		(end 24.623014 -7.812786)
		(width 0.508)
		(layer "B.Cu")
		(net "P3V3_VCC")
	)
	(segment
		(start 26.7208 -6.6167)
		(end 25.8953 -6.6167)
		(width 0.508)
		(layer "B.Cu")
		(net "P3V3_VCC")
	)
	(segment
		(start 27.1653 -6.6167)
		(end 27.7876 -7.239)
		(width 0.508)
		(layer "B.Cu")
		(net "P3V3_VCC")
	)
	(segment
		(start 25.146 -6.9088)
		(end 24.623014 -7.431786)
		(width 0.508)
		(layer "B.Cu")
		(net "P3V3_VCC")
	)
	(segment
		(start 24.356822 -8.078978)
		(end 23.732998 -8.078978)
		(width 0.3048)
		(layer "B.Cu")
		(net "P3V3_VCC")
	)
	(segment
		(start 24.5872 -7.8486)
		(end 24.356822 -8.078978)
		(width 0.3048)
		(layer "B.Cu")
		(net "P3V3_VCC")
	)
	(segment
		(start 24.623014 -7.812786)
		(end 24.5872 -7.8486)
		(width 0.508)
		(layer "B.Cu")
		(net "P3V3_VCC")
	)
	(segment
		(start 25.8953 -6.6167)
		(end 25.6032 -6.9088)
		(width 0.508)
		(layer "B.Cu")
		(net "P3V3_VCC")
	)
	(segment
		(start 25.6032 -6.9088)
		(end 25.146 -6.9088)
		(width 0.508)
		(layer "B.Cu")
		(net "P3V3_VCC")
	)
	(segment
		(start 26.7208 -6.6167)
		(end 27.1653 -6.6167)
		(width 0.508)
		(layer "B.Cu")
		(net "P3V3_VCC")
	)
	(via
		(at 14.732 -10.6426)
		(size 0.7112)
		(drill 0.3556)
		(layers "F.Cu" "B.Cu")
		(net "P3V3_TRK")
	)
	(segment
		(start 16.7005 -9.5631)
		(end 16.8148 -9.5631)
		(width 0.254)
		(layer "B.Cu")
		(net "P3V3_TRK")
	)
	(segment
		(start 18.322544 -9.9314)
		(end 18.487644 -9.7663)
		(width 0.254)
		(layer "B.Cu")
		(net "P3V3_TRK")
	)
	(segment
		(start 15.6972 -10.4521)
		(end 15.8115 -10.4521)
		(width 0.254)
		(layer "B.Cu")
		(net "P3V3_TRK")
	)
	(segment
		(start 18.487644 -9.7663)
		(end 18.9992 -9.7663)
		(width 0.254)
		(layer "B.Cu")
		(net "P3V3_TRK")
	)
	(segment
		(start 15.8115 -10.4521)
		(end 16.7005 -9.5631)
		(width 0.254)
		(layer "B.Cu")
		(net "P3V3_TRK")
	)
	(segment
		(start 15.6972 -10.4521)
		(end 14.9225 -10.4521)
		(width 0.254)
		(layer "B.Cu")
		(net "P3V3_TRK")
	)
	(segment
		(start 18.9992 -9.7663)
		(end 19.0119 -9.779)
		(width 0.2032)
		(layer "B.Cu")
		(net "P3V3_TRK")
	)
	(segment
		(start 19.0119 -9.779)
		(end 20.971002 -9.779)
		(width 0.2032)
		(layer "B.Cu")
		(net "P3V3_TRK")
	)
	(segment
		(start 17.1831 -9.9314)
		(end 18.322544 -9.9314)
		(width 0.254)
		(layer "B.Cu")
		(net "P3V3_TRK")
	)
	(segment
		(start 14.9225 -10.4521)
		(end 14.732 -10.6426)
		(width 0.254)
		(layer "B.Cu")
		(net "P3V3_TRK")
	)
	(segment
		(start 16.8148 -9.5631)
		(end 17.1831 -9.9314)
		(width 0.254)
		(layer "B.Cu")
		(net "P3V3_TRK")
	)
	(via
		(at 17.145 -4.445)
		(size 0.7112)
		(drill 0.3556)
		(layers "F.Cu" "B.Cu")
		(net "P3V3_SW")
	)
	(via
		(at 17.7165 -12.2428)
		(size 0.7112)
		(drill 0.3556)
		(layers "F.Cu" "B.Cu")
		(net "P3V3_FB")
	)
	(segment
		(start 18.6055 -11.4681)
		(end 18.3261 -11.4681)
		(width 0.254)
		(layer "B.Cu")
		(net "P3V3_FB")
	)
	(segment
		(start 17.9959 -12.2428)
		(end 17.7165 -12.2428)
		(width 0.254)
		(layer "B.Cu")
		(net "P3V3_FB")
	)
	(segment
		(start 16.9545 -11.4808)
		(end 17.7165 -12.2428)
		(width 0.254)
		(layer "B.Cu")
		(net "P3V3_FB")
	)
	(segment
		(start 18.3261 -11.9126)
		(end 17.9959 -12.2428)
		(width 0.254)
		(layer "B.Cu")
		(net "P3V3_FB")
	)
	(segment
		(start 20.971002 -10.5791)
		(end 19.4945 -10.5791)
		(width 0.2032)
		(layer "B.Cu")
		(net "P3V3_FB")
	)
	(segment
		(start 16.7132 -11.4935)
		(end 16.7259 -11.4808)
		(width 0.254)
		(layer "B.Cu")
		(net "P3V3_FB")
	)
	(segment
		(start 16.7259 -11.4808)
		(end 16.9545 -11.4808)
		(width 0.254)
		(layer "B.Cu")
		(net "P3V3_FB")
	)
	(segment
		(start 18.3261 -11.4681)
		(end 18.3261 -11.9126)
		(width 0.254)
		(layer "B.Cu")
		(net "P3V3_FB")
	)
	(segment
		(start 16.7132 -12.4587)
		(end 16.7132 -11.4935)
		(width 0.254)
		(layer "B.Cu")
		(net "P3V3_FB")
	)
	(segment
		(start 19.4945 -10.5791)
		(end 18.6055 -11.4681)
		(width 0.254)
		(layer "B.Cu")
		(net "P3V3_FB")
	)
	(via
		(at 17.568164 -8.118348)
		(size 0.7112)
		(drill 0.3556)
		(layers "F.Cu" "B.Cu")
		(net "P3V3_CS")
	)
	(segment
		(start 16.930116 -7.4803)
		(end 17.568164 -8.118348)
		(width 0.254)
		(layer "B.Cu")
		(net "P3V3_CS")
	)
	(segment
		(start 17.568164 -8.118348)
		(end 17.744948 -8.118348)
		(width 0.254)
		(layer "B.Cu")
		(net "P3V3_CS")
	)
	(segment
		(start 16.7005 -7.4803)
		(end 16.930116 -7.4803)
		(width 0.254)
		(layer "B.Cu")
		(net "P3V3_CS")
	)
	(segment
		(start 19.4056 -8.9789)
		(end 20.971002 -8.9789)
		(width 0.2032)
		(layer "B.Cu")
		(net "P3V3_CS")
	)
	(segment
		(start 17.744948 -8.118348)
		(end 18.6055 -8.9789)
		(width 0.254)
		(layer "B.Cu")
		(net "P3V3_CS")
	)
	(segment
		(start 18.6055 -8.9789)
		(end 19.4056 -8.9789)
		(width 0.254)
		(layer "B.Cu")
		(net "P3V3_CS")
	)
	(via
		(at 18.8976 -7.366)
		(size 0.7112)
		(drill 0.3556)
		(layers "F.Cu" "B.Cu")
		(net "P3V3_BST")
	)
	(segment
		(start 20.971002 -8.078978)
		(end 19.610578 -8.078978)
		(width 0.3048)
		(layer "B.Cu")
		(net "P3V3_BST")
	)
	(segment
		(start 19.610578 -8.078978)
		(end 18.8976 -7.366)
		(width 0.3048)
		(layer "B.Cu")
		(net "P3V3_BST")
	)
	(segment
		(start 18.2626 -6.4516)
		(end 18.3896 -6.3246)
		(width 0.508)
		(layer "B.Cu")
		(net "P3V3_BST")
	)
	(segment
		(start 18.2626 -6.731)
		(end 18.2626 -6.4516)
		(width 0.508)
		(layer "B.Cu")
		(net "P3V3_BST")
	)
	(segment
		(start 18.8976 -7.366)
		(end 18.2626 -6.731)
		(width 0.508)
		(layer "B.Cu")
		(net "P3V3_BST")
	)
	(segment
		(start 101.219 -21.2471)
		(end 101.219 -20.6502)
		(width 0.1016)
		(layer "F.Cu")
		(net "RESET_O_2_R")
	)
	(segment
		(start 99.8347 -19.2659)
		(end 99.8982 -19.3294)
		(width 0.1016)
		(layer "F.Cu")
		(net "RESET_O_2_R")
	)
	(segment
		(start 97.525078 -20.242022)
		(end 98.5012 -19.2659)
		(width 0.1016)
		(layer "F.Cu")
		(net "RESET_O_2_R")
	)
	(segment
		(start 97.525078 -21.183346)
		(end 97.525078 -20.242022)
		(width 0.1016)
		(layer "F.Cu")
		(net "RESET_O_2_R")
	)
	(segment
		(start 101.219 -20.6502)
		(end 99.8982 -19.3294)
		(width 0.1016)
		(layer "F.Cu")
		(net "RESET_O_2_R")
	)
	(segment
		(start 98.5012 -19.2659)
		(end 99.8347 -19.2659)
		(width 0.1016)
		(layer "F.Cu")
		(net "RESET_O_2_R")
	)
	(via
		(at 99.8982 -19.3294)
		(size 0.7112)
		(drill 0.3556)
		(layers "F.Cu" "B.Cu")
		(net "RESET_O_2_R")
	)
	(via
		(at 25.7048 1.4605)
		(size 0.5588)
		(drill 0.3048)
		(layers "F.Cu" "B.Cu")
		(net "P3V3_VR")
	)
	(via
		(at 26.6319 -1.1176)
		(size 0.5588)
		(drill 0.3048)
		(layers "F.Cu" "B.Cu")
		(net "P3V3_VR")
	)
	(via
		(at 28.3718 0.1143)
		(size 0.5588)
		(drill 0.3048)
		(layers "F.Cu" "B.Cu")
		(net "P3V3_VR")
	)
	(via
		(at 26.4795 -0.0889)
		(size 0.5588)
		(drill 0.3048)
		(layers "F.Cu" "B.Cu")
		(net "P3V3_VR")
	)
	(via
		(at 25.6032 -1.0922)
		(size 0.5588)
		(drill 0.3048)
		(layers "F.Cu" "B.Cu")
		(net "P3V3_VR")
	)
	(via
		(at 25.654 0.2159)
		(size 0.5588)
		(drill 0.3048)
		(layers "F.Cu" "B.Cu")
		(net "P3V3_VR")
	)
	(via
		(at 26.5684 0.9398)
		(size 0.5588)
		(drill 0.3048)
		(layers "F.Cu" "B.Cu")
		(net "P3V3_VR")
	)
	(via
		(at 25.8572 4.4831)
		(size 0.7112)
		(drill 0.3556)
		(layers "F.Cu" "B.Cu")
		(net "P3V3_VR")
	)
	(via
		(at 27.432 0.1143)
		(size 0.5588)
		(drill 0.3048)
		(layers "F.Cu" "B.Cu")
		(net "P3V3_VR")
	)
	(via
		(at 29.3497 0.127)
		(size 0.5588)
		(drill 0.3048)
		(layers "F.Cu" "B.Cu")
		(net "P3V3_VR")
	)
	(segment
		(start 31.2293 4.3688)
		(end 31.75 3.8481)
		(width 0.3048)
		(layer "B.Cu")
		(net "P3V3_VR")
	)
	(segment
		(start 19.4056 2.742184)
		(end 19.4056 -0.4318)
		(width 0.3048)
		(layer "B.Cu")
		(net "P3V3_VR")
	)
	(segment
		(start 14.1224 -7.5692)
		(end 14.2748 -7.7216)
		(width 0.3048)
		(layer "B.Cu")
		(net "P3V3_VR")
	)
	(segment
		(start 14.1224 -5.715)
		(end 14.1224 -7.5692)
		(width 0.3048)
		(layer "B.Cu")
		(net "P3V3_VR")
	)
	(segment
		(start 30.7594 1.5748)
		(end 30.4165 1.2319)
		(width 0.3048)
		(layer "B.Cu")
		(net "P3V3_VR")
	)
	(segment
		(start 31.369 1.5748)
		(end 30.7594 1.5748)
		(width 0.3048)
		(layer "B.Cu")
		(net "P3V3_VR")
	)
	(segment
		(start 25.8572 4.4831)
		(end 25.9715 4.3688)
		(width 0.3048)
		(layer "B.Cu")
		(net "P3V3_VR")
	)
	(segment
		(start 25.9715 4.3688)
		(end 31.2293 4.3688)
		(width 0.3048)
		(layer "B.Cu")
		(net "P3V3_VR")
	)
	(segment
		(start 31.75 1.9558)
		(end 31.369 1.5748)
		(width 0.3048)
		(layer "B.Cu")
		(net "P3V3_VR")
	)
	(segment
		(start 21.146516 4.4831)
		(end 19.4056 2.742184)
		(width 0.3048)
		(layer "B.Cu")
		(net "P3V3_VR")
	)
	(segment
		(start 31.75 3.8481)
		(end 31.75 1.9558)
		(width 0.3048)
		(layer "B.Cu")
		(net "P3V3_VR")
	)
	(segment
		(start 25.8572 4.4831)
		(end 21.146516 4.4831)
		(width 0.3048)
		(layer "B.Cu")
		(net "P3V3_VR")
	)
	(segment
		(start 19.4056 -0.4318)
		(end 14.1224 -5.715)
		(width 0.3048)
		(layer "B.Cu")
		(net "P3V3_VR")
	)
	(segment
		(start 113.9444 -27.434794)
		(end 114.079782 -27.570176)
		(width 0.1016)
		(layer "F.Cu")
		(net "TP_RSVD_SLOT3_PIN82")
	)
	(segment
		(start 113.9444 -24.0792)
		(end 113.9444 -27.434794)
		(width 0.1016)
		(layer "F.Cu")
		(net "TP_RSVD_SLOT3_PIN82")
	)
	(segment
		(start 114.079782 -5.935218)
		(end 114.079782 -7.250176)
		(width 0.1016)
		(layer "F.Cu")
		(net "TP_RSVD_SLOT2_PIN82")
	)
	(segment
		(start 115.5446 -4.4704)
		(end 114.079782 -5.935218)
		(width 0.1016)
		(layer "F.Cu")
		(net "TP_RSVD_SLOT2_PIN82")
	)
	(segment
		(start 115.5446 -3.7592)
		(end 115.5446 -4.4704)
		(width 0.1016)
		(layer "F.Cu")
		(net "TP_RSVD_SLOT2_PIN82")
	)
	(via
		(at 131.6609 -3.9243)
		(size 0.7112)
		(drill 0.3556)
		(layers "F.Cu" "B.Cu")
		(net "SMB_PCH_DEVICE_ALERT_N")
	)
	(segment
		(start 131.7879 -4.0513)
		(end 131.6609 -3.9243)
		(width 0.1016)
		(layer "B.Cu")
		(net "SMB_PCH_DEVICE_ALERT_N")
	)
	(segment
		(start 128.4224 -4.1402)
		(end 128.4224 -3.175)
		(width 0.1016)
		(layer "B.Cu")
		(net "SMB_PCH_DEVICE_ALERT_N")
	)
	(segment
		(start 131.6609 -3.9243)
		(end 131.2291 -3.9243)
		(width 0.1016)
		(layer "B.Cu")
		(net "SMB_PCH_DEVICE_ALERT_N")
	)
	(segment
		(start 128.56845 -4.28625)
		(end 128.4224 -4.1402)
		(width 0.1016)
		(layer "B.Cu")
		(net "SMB_PCH_DEVICE_ALERT_N")
	)
	(segment
		(start 131.7879 -4.8514)
		(end 131.7879 -5.842)
		(width 0.1016)
		(layer "B.Cu")
		(net "SMB_PCH_DEVICE_ALERT_N")
	)
	(segment
		(start 131.7879 -5.842)
		(end 131.826 -5.8801)
		(width 0.1016)
		(layer "B.Cu")
		(net "SMB_PCH_DEVICE_ALERT_N")
	)
	(segment
		(start 131.7879 -4.8514)
		(end 131.7879 -4.0513)
		(width 0.1016)
		(layer "B.Cu")
		(net "SMB_PCH_DEVICE_ALERT_N")
	)
	(segment
		(start 131.2291 -3.9243)
		(end 130.86715 -4.28625)
		(width 0.1016)
		(layer "B.Cu")
		(net "SMB_PCH_DEVICE_ALERT_N")
	)
	(segment
		(start 130.86715 -4.28625)
		(end 128.56845 -4.28625)
		(width 0.1016)
		(layer "B.Cu")
		(net "SMB_PCH_DEVICE_ALERT_N")
	)
	(segment
		(start 122.9868 -10.5664)
		(end 122.9868 -12.82192)
		(width 0.1016)
		(layer "F.Cu")
		(net "PCIE_SLOT3_PRSNT2_4_N")
	)
	(segment
		(start 120.0785 -11.2522)
		(end 120.0785 -12.3571)
		(width 0.1016)
		(layer "F.Cu")
		(net "PCIE_SLOT3_PRSNT2_4_N")
	)
	(segment
		(start 120.0785 -11.2522)
		(end 121.30532 -11.2522)
		(width 0.1016)
		(layer "F.Cu")
		(net "PCIE_SLOT3_PRSNT2_4_N")
	)
	(segment
		(start 120.0785 -12.3571)
		(end 120.69572 -12.97432)
		(width 0.1016)
		(layer "F.Cu")
		(net "PCIE_SLOT3_PRSNT2_4_N")
	)
	(segment
		(start 123.87072 -9.68248)
		(end 122.9868 -10.5664)
		(width 0.1016)
		(layer "F.Cu")
		(net "PCIE_SLOT3_PRSNT2_4_N")
	)
	(segment
		(start 120.69572 -12.97432)
		(end 122.047 -12.97432)
		(width 0.1016)
		(layer "F.Cu")
		(net "PCIE_SLOT3_PRSNT2_4_N")
	)
	(segment
		(start 122.9868 -12.82192)
		(end 122.8344 -12.97432)
		(width 0.1016)
		(layer "F.Cu")
		(net "PCIE_SLOT3_PRSNT2_4_N")
	)
	(segment
		(start 123.87072 -8.8138)
		(end 123.87072 -9.68248)
		(width 0.1016)
		(layer "F.Cu")
		(net "PCIE_SLOT3_PRSNT2_4_N")
	)
	(segment
		(start 121.30532 -11.2522)
		(end 121.6914 -11.63828)
		(width 0.1016)
		(layer "F.Cu")
		(net "PCIE_SLOT3_PRSNT2_4_N")
	)
	(segment
		(start 122.8344 -12.97432)
		(end 122.047 -12.97432)
		(width 0.1016)
		(layer "F.Cu")
		(net "PCIE_SLOT3_PRSNT2_4_N")
	)
	(via
		(at 122.3772 -12.4206)
		(size 0.7112)
		(drill 0.3556)
		(layers "F.Cu" "B.Cu")
		(net "PCIE_SLOT3_PRSNT2_4_N")
	)
	(via
		(at 121.6914 -11.63828)
		(size 0.508)
		(drill 0.254)
		(layers "F.Cu" "B.Cu")
		(net "PCIE_SLOT3_PRSNT2_4_N")
	)
	(segment
		(start 122.3772 -12.4206)
		(end 122.3772 -12.32408)
		(width 0.1016)
		(layer "B.Cu")
		(net "PCIE_SLOT3_PRSNT2_4_N")
	)
	(segment
		(start 122.3772 -12.32408)
		(end 121.6914 -11.63828)
		(width 0.1016)
		(layer "B.Cu")
		(net "PCIE_SLOT3_PRSNT2_4_N")
	)
	(segment
		(start 120.1928 -19.5072)
		(end 117.9322 -21.7678)
		(width 0.127)
		(layer "In2.Cu")
		(net "PCIE_SLOT3_PRSNT2_4_N")
	)
	(segment
		(start 115.015518 -29.1592)
		(end 113.491518 -29.1592)
		(width 0.127)
		(layer "In2.Cu")
		(net "PCIE_SLOT3_PRSNT2_4_N")
	)
	(segment
		(start 121.6914 -11.63828)
		(end 121.6914 -17.0688)
		(width 0.127)
		(layer "In2.Cu")
		(net "PCIE_SLOT3_PRSNT2_4_N")
	)
	(segment
		(start 117.9322 -21.7678)
		(end 117.9322 -26.242518)
		(width 0.127)
		(layer "In2.Cu")
		(net "PCIE_SLOT3_PRSNT2_4_N")
	)
	(segment
		(start 113.491518 -29.1592)
		(end 113.080292 -29.570426)
		(width 0.127)
		(layer "In2.Cu")
		(net "PCIE_SLOT3_PRSNT2_4_N")
	)
	(segment
		(start 120.1928 -18.5674)
		(end 120.1928 -19.5072)
		(width 0.127)
		(layer "In2.Cu")
		(net "PCIE_SLOT3_PRSNT2_4_N")
	)
	(segment
		(start 121.6914 -17.0688)
		(end 120.1928 -18.5674)
		(width 0.127)
		(layer "In2.Cu")
		(net "PCIE_SLOT3_PRSNT2_4_N")
	)
	(segment
		(start 117.9322 -26.242518)
		(end 115.015518 -29.1592)
		(width 0.127)
		(layer "In2.Cu")
		(net "PCIE_SLOT3_PRSNT2_4_N")
	)
	(segment
		(start 120.7516 -15.621)
		(end 120.79732 -15.57528)
		(width 0.1016)
		(layer "F.Cu")
		(net "PCIE_SLOT2_PRSNT2_4_N")
	)
	(segment
		(start 124.206 -14.581632)
		(end 124.206 -11.89228)
		(width 0.1016)
		(layer "F.Cu")
		(net "PCIE_SLOT2_PRSNT2_4_N")
	)
	(segment
		(start 126.47168 -9.6266)
		(end 126.47168 -8.8138)
		(width 0.1016)
		(layer "F.Cu")
		(net "PCIE_SLOT2_PRSNT2_4_N")
	)
	(segment
		(start 124.206 -11.89228)
		(end 126.47168 -9.6266)
		(width 0.1016)
		(layer "F.Cu")
		(net "PCIE_SLOT2_PRSNT2_4_N")
	)
	(segment
		(start 120.79732 -15.57528)
		(end 122.047 -15.57528)
		(width 0.1016)
		(layer "F.Cu")
		(net "PCIE_SLOT2_PRSNT2_4_N")
	)
	(segment
		(start 119.9769 -15.5956)
		(end 120.7262 -15.5956)
		(width 0.1016)
		(layer "F.Cu")
		(net "PCIE_SLOT2_PRSNT2_4_N")
	)
	(segment
		(start 123.212352 -15.57528)
		(end 124.206 -14.581632)
		(width 0.1016)
		(layer "F.Cu")
		(net "PCIE_SLOT2_PRSNT2_4_N")
	)
	(segment
		(start 120.7262 -15.5956)
		(end 120.7516 -15.621)
		(width 0.1016)
		(layer "F.Cu")
		(net "PCIE_SLOT2_PRSNT2_4_N")
	)
	(segment
		(start 122.047 -15.57528)
		(end 123.212352 -15.57528)
		(width 0.1016)
		(layer "F.Cu")
		(net "PCIE_SLOT2_PRSNT2_4_N")
	)
	(via
		(at 119.8372 -16.0528)
		(size 0.7112)
		(drill 0.3556)
		(layers "F.Cu" "B.Cu")
		(net "PCIE_SLOT2_PRSNT2_4_N")
	)
	(via
		(at 120.7516 -15.621)
		(size 0.508)
		(drill 0.254)
		(layers "F.Cu" "B.Cu")
		(net "PCIE_SLOT2_PRSNT2_4_N")
	)
	(segment
		(start 120.3198 -16.0528)
		(end 120.7516 -15.621)
		(width 0.1016)
		(layer "B.Cu")
		(net "PCIE_SLOT2_PRSNT2_4_N")
	)
	(segment
		(start 119.8372 -16.0528)
		(end 120.3198 -16.0528)
		(width 0.1016)
		(layer "B.Cu")
		(net "PCIE_SLOT2_PRSNT2_4_N")
	)
	(segment
		(start 113.080292 -9.250426)
		(end 113.080292 -10.083292)
		(width 0.127)
		(layer "In3.Cu")
		(net "PCIE_SLOT2_PRSNT2_4_N")
	)
	(segment
		(start 120.59412 -15.621)
		(end 120.7516 -15.621)
		(width 0.127)
		(layer "In3.Cu")
		(net "PCIE_SLOT2_PRSNT2_4_N")
	)
	(segment
		(start 120.44172 -15.4686)
		(end 120.59412 -15.621)
		(width 0.127)
		(layer "In3.Cu")
		(net "PCIE_SLOT2_PRSNT2_4_N")
	)
	(segment
		(start 113.080292 -10.083292)
		(end 118.4656 -15.4686)
		(width 0.127)
		(layer "In3.Cu")
		(net "PCIE_SLOT2_PRSNT2_4_N")
	)
	(segment
		(start 118.4656 -15.4686)
		(end 120.44172 -15.4686)
		(width 0.127)
		(layer "In3.Cu")
		(net "PCIE_SLOT2_PRSNT2_4_N")
	)
	(via
		(at 20.9804 -12.7254)
		(size 0.5588)
		(drill 0.3048)
		(layers "F.Cu" "B.Cu")
		(net "P3V3_VIN")
	)
	(via
		(at 21.336 -7.239)
		(size 0.5588)
		(drill 0.3048)
		(layers "F.Cu" "B.Cu")
		(net "P3V3_VIN")
	)
	(via
		(at 20.4216 -7.2898)
		(size 0.5588)
		(drill 0.3048)
		(layers "F.Cu" "B.Cu")
		(net "P3V3_VIN")
	)
	(via
		(at 21.0058 -13.6906)
		(size 0.5588)
		(drill 0.3048)
		(layers "F.Cu" "B.Cu")
		(net "P3V3_VIN")
	)
	(via
		(at 20.0406 -12.7)
		(size 0.5588)
		(drill 0.3048)
		(layers "F.Cu" "B.Cu")
		(net "P3V3_VIN")
	)
	(via
		(at 20.0406 -13.6652)
		(size 0.5588)
		(drill 0.3048)
		(layers "F.Cu" "B.Cu")
		(net "P3V3_VIN")
	)
	(via
		(at 20.4978 -14.4907)
		(size 0.7112)
		(drill 0.3556)
		(layers "F.Cu" "B.Cu")
		(net "P3V3_VIN")
	)
	(via
		(at 14.7574 -11.9126)
		(size 0.7112)
		(drill 0.3556)
		(layers "F.Cu" "B.Cu")
		(net "P3V3_VFB_R")
	)
	(segment
		(start 15.8369 -11.4808)
		(end 15.1892 -11.4808)
		(width 0.254)
		(layer "B.Cu")
		(net "P3V3_VFB_R")
	)
	(segment
		(start 14.7574 -11.9126)
		(end 14.097 -11.2522)
		(width 0.254)
		(layer "B.Cu")
		(net "P3V3_VFB_R")
	)
	(segment
		(start 15.1892 -11.4808)
		(end 14.7574 -11.9126)
		(width 0.254)
		(layer "B.Cu")
		(net "P3V3_VFB_R")
	)
	(segment
		(start 15.8242 -11.4935)
		(end 15.8369 -11.4808)
		(width 0.254)
		(layer "B.Cu")
		(net "P3V3_VFB_R")
	)
	(segment
		(start 15.8242 -12.4587)
		(end 15.8242 -11.4935)
		(width 0.254)
		(layer "B.Cu")
		(net "P3V3_VFB_R")
	)
	(segment
		(start 14.097 -11.2522)
		(end 14.097 -9.4234)
		(width 0.254)
		(layer "B.Cu")
		(net "P3V3_VFB_R")
	)
	(segment
		(start 14.097 -9.4234)
		(end 14.2748 -9.2456)
		(width 0.254)
		(layer "B.Cu")
		(net "P3V3_VFB_R")
	)
	(segment
		(start 98.5012 -17.5514)
		(end 98.5012 -18.3769)
		(width 0.254)
		(layer "F.Cu")
		(net "P3V3_PG")
	)
	(segment
		(start 98.171 -17.2212)
		(end 98.5012 -17.5514)
		(width 0.254)
		(layer "F.Cu")
		(net "P3V3_PG")
	)
	(via
		(at 26.7716 -8.7122)
		(size 0.508)
		(drill 0.254)
		(layers "F.Cu" "B.Cu")
		(net "P3V3_PG")
	)
	(via
		(at 19.8374 -11.5316)
		(size 0.508)
		(drill 0.254)
		(layers "F.Cu" "B.Cu")
		(net "P3V3_PG")
	)
	(via
		(at 98.171 -17.2212)
		(size 0.508)
		(drill 0.254)
		(layers "F.Cu" "B.Cu")
		(net "P3V3_PG")
	)
	(via
		(at 27.736546 -8.739124)
		(size 0.7112)
		(drill 0.3556)
		(layers "F.Cu" "B.Cu")
		(net "P3V3_PG")
	)
	(segment
		(start 27.736546 -8.739124)
		(end 26.798524 -8.739124)
		(width 0.254)
		(layer "B.Cu")
		(net "P3V3_PG")
	)
	(segment
		(start 19.8628 -11.5316)
		(end 19.915378 -11.479022)
		(width 0.254)
		(layer "B.Cu")
		(net "P3V3_PG")
	)
	(segment
		(start 19.915378 -11.479022)
		(end 20.971002 -11.479022)
		(width 0.254)
		(layer "B.Cu")
		(net "P3V3_PG")
	)
	(segment
		(start 26.7716 -7.5565)
		(end 26.7716 -8.7122)
		(width 0.254)
		(layer "B.Cu")
		(net "P3V3_PG")
	)
	(segment
		(start 26.798524 -8.739124)
		(end 26.7716 -8.7122)
		(width 0.254)
		(layer "B.Cu")
		(net "P3V3_PG")
	)
	(segment
		(start 26.7208 -7.5057)
		(end 26.7716 -7.5565)
		(width 0.254)
		(layer "B.Cu")
		(net "P3V3_PG")
	)
	(segment
		(start 19.8374 -11.5316)
		(end 19.8628 -11.5316)
		(width 0.254)
		(layer "B.Cu")
		(net "P3V3_PG")
	)
	(segment
		(start 26.7716 -8.636)
		(end 30.5308 -4.8768)
		(width 0.254)
		(layer "In3.Cu")
		(net "P3V3_PG")
	)
	(segment
		(start 98.0186 -17.2212)
		(end 98.171 -17.2212)
		(width 0.254)
		(layer "In3.Cu")
		(net "P3V3_PG")
	)
	(segment
		(start 19.5834 -11.2776)
		(end 19.8374 -11.5316)
		(width 0.254)
		(layer "In3.Cu")
		(net "P3V3_PG")
	)
	(segment
		(start 97.9678 -17.272)
		(end 98.0186 -17.2212)
		(width 0.254)
		(layer "In3.Cu")
		(net "P3V3_PG")
	)
	(segment
		(start 19.7866 3.4798)
		(end 19.7866 -1.2954)
		(width 0.254)
		(layer "In3.Cu")
		(net "P3V3_PG")
	)
	(segment
		(start 17.3482 -11.2776)
		(end 19.5834 -11.2776)
		(width 0.254)
		(layer "In3.Cu")
		(net "P3V3_PG")
	)
	(segment
		(start 28.6639 -14.765528)
		(end 30.153864 -16.255492)
		(width 0.254)
		(layer "In3.Cu")
		(net "P3V3_PG")
	)
	(segment
		(start 16.3576 -10.287)
		(end 17.3482 -11.2776)
		(width 0.254)
		(layer "In3.Cu")
		(net "P3V3_PG")
	)
	(segment
		(start 41.982136 -15.447264)
		(end 50.410364 -15.447264)
		(width 0.254)
		(layer "In3.Cu")
		(net "P3V3_PG")
	)
	(segment
		(start 26.7716 -8.7122)
		(end 26.7716 -8.636)
		(width 0.254)
		(layer "In3.Cu")
		(net "P3V3_PG")
	)
	(segment
		(start 19.7104 -1.3716)
		(end 19.7104 -1.97358)
		(width 0.254)
		(layer "In3.Cu")
		(net "P3V3_PG")
	)
	(segment
		(start 20.32 4.0132)
		(end 19.7866 3.4798)
		(width 0.254)
		(layer "In3.Cu")
		(net "P3V3_PG")
	)
	(segment
		(start 50.410364 -15.447264)
		(end 52.2351 -17.272)
		(width 0.254)
		(layer "In3.Cu")
		(net "P3V3_PG")
	)
	(segment
		(start 26.7716 -8.7122)
		(end 28.6639 -10.6045)
		(width 0.254)
		(layer "In3.Cu")
		(net "P3V3_PG")
	)
	(segment
		(start 30.5308 -4.8768)
		(end 30.5308 0.904748)
		(width 0.254)
		(layer "In3.Cu")
		(net "P3V3_PG")
	)
	(segment
		(start 16.3576 -5.32638)
		(end 16.3576 -10.287)
		(width 0.254)
		(layer "In3.Cu")
		(net "P3V3_PG")
	)
	(segment
		(start 19.7104 -1.97358)
		(end 16.3576 -5.32638)
		(width 0.254)
		(layer "In3.Cu")
		(net "P3V3_PG")
	)
	(segment
		(start 28.6639 -10.6045)
		(end 28.6639 -14.765528)
		(width 0.254)
		(layer "In3.Cu")
		(net "P3V3_PG")
	)
	(segment
		(start 30.5308 0.904748)
		(end 27.422348 4.0132)
		(width 0.254)
		(layer "In3.Cu")
		(net "P3V3_PG")
	)
	(segment
		(start 19.7866 -1.2954)
		(end 19.7104 -1.3716)
		(width 0.254)
		(layer "In3.Cu")
		(net "P3V3_PG")
	)
	(segment
		(start 41.173908 -16.255492)
		(end 41.982136 -15.447264)
		(width 0.254)
		(layer "In3.Cu")
		(net "P3V3_PG")
	)
	(segment
		(start 27.422348 4.0132)
		(end 20.32 4.0132)
		(width 0.254)
		(layer "In3.Cu")
		(net "P3V3_PG")
	)
	(segment
		(start 52.2351 -17.272)
		(end 97.9678 -17.272)
		(width 0.254)
		(layer "In3.Cu")
		(net "P3V3_PG")
	)
	(segment
		(start 30.153864 -16.255492)
		(end 41.173908 -16.255492)
		(width 0.254)
		(layer "In3.Cu")
		(net "P3V3_PG")
	)
	(via
		(at 18.0086 -9.2964)
		(size 0.7112)
		(drill 0.3556)
		(layers "F.Cu" "B.Cu")
		(net "P3V3_MODE")
	)
	(segment
		(start 18.3134 -9.2964)
		(end 18.39595 -9.37895)
		(width 0.2032)
		(layer "B.Cu")
		(net "P3V3_MODE")
	)
	(segment
		(start 18.39595 -9.37895)
		(end 20.971002 -9.37895)
		(width 0.2032)
		(layer "B.Cu")
		(net "P3V3_MODE")
	)
	(segment
		(start 17.7038 -9.2964)
		(end 16.9291 -8.5217)
		(width 0.254)
		(layer "B.Cu")
		(net "P3V3_MODE")
	)
	(segment
		(start 16.9291 -8.5217)
		(end 16.6751 -8.5217)
		(width 0.254)
		(layer "B.Cu")
		(net "P3V3_MODE")
	)
	(segment
		(start 18.0086 -9.2964)
		(end 17.7038 -9.2964)
		(width 0.254)
		(layer "B.Cu")
		(net "P3V3_MODE")
	)
	(segment
		(start 18.0086 -9.2964)
		(end 18.3134 -9.2964)
		(width 0.2032)
		(layer "B.Cu")
		(net "P3V3_MODE")
	)
	(via
		(at 30.8102 5.8928)
		(size 0.5588)
		(drill 0.3048)
		(layers "F.Cu" "B.Cu")
		(net "P3V3_MB")
	)
	(via
		(at 24.3078 9.1059)
		(size 0.5588)
		(drill 0.3048)
		(layers "F.Cu" "B.Cu")
		(net "P3V3_MB")
	)
	(via
		(at 28.956 2.8956)
		(size 0.7112)
		(drill 0.3556)
		(layers "F.Cu" "B.Cu")
		(net "P3V3_MB")
	)
	(via
		(at 25.7302 7.112)
		(size 0.5588)
		(drill 0.3048)
		(layers "F.Cu" "B.Cu")
		(net "P3V3_MB")
	)
	(via
		(at 23.3934 9.1313)
		(size 0.5588)
		(drill 0.3048)
		(layers "F.Cu" "B.Cu")
		(net "P3V3_MB")
	)
	(via
		(at 31.6992 5.4864)
		(size 0.5588)
		(drill 0.3048)
		(layers "F.Cu" "B.Cu")
		(net "P3V3_MB")
	)
	(via
		(at 30.1752 5.3086)
		(size 0.5588)
		(drill 0.3048)
		(layers "F.Cu" "B.Cu")
		(net "P3V3_MB")
	)
	(via
		(at 29.5656 5.9182)
		(size 0.5588)
		(drill 0.3048)
		(layers "F.Cu" "B.Cu")
		(net "P3V3_MB")
	)
	(via
		(at 23.8633 7.1247)
		(size 0.7112)
		(drill 0.3556)
		(layers "F.Cu" "B.Cu")
		(net "P3V3_MB")
	)
	(via
		(at 24.854916 7.37743)
		(size 0.5588)
		(drill 0.3048)
		(layers "F.Cu" "B.Cu")
		(net "P3V3_MB")
	)
	(via
		(at 30.93847 5.028692)
		(size 0.5588)
		(drill 0.3048)
		(layers "F.Cu" "B.Cu")
		(net "P3V3_MB")
	)
	(via
		(at 24.7777 8.255)
		(size 0.5588)
		(drill 0.3048)
		(layers "F.Cu" "B.Cu")
		(net "P3V3_MB")
	)
	(via
		(at 23.9014 8.2931)
		(size 0.5588)
		(drill 0.3048)
		(layers "F.Cu" "B.Cu")
		(net "P3V3_MB")
	)
	(via
		(at 19.2405 -12.1412)
		(size 0.7112)
		(drill 0.3556)
		(layers "F.Cu" "B.Cu")
		(net "P3V3_EN")
	)
	(segment
		(start 19.704304 -10.978896)
		(end 20.971002 -10.978896)
		(width 0.2032)
		(layer "B.Cu")
		(net "P3V3_EN")
	)
	(segment
		(start 19.2405 -12.1412)
		(end 19.2405 -11.4427)
		(width 0.254)
		(layer "B.Cu")
		(net "P3V3_EN")
	)
	(segment
		(start 19.2405 -12.954)
		(end 19.2405 -12.1412)
		(width 0.254)
		(layer "B.Cu")
		(net "P3V3_EN")
	)
	(segment
		(start 16.637 -13.4366)
		(end 16.764 -13.3096)
		(width 0.254)
		(layer "B.Cu")
		(net "P3V3_EN")
	)
	(segment
		(start 17.6657 -13.4112)
		(end 18.7833 -13.4112)
		(width 0.254)
		(layer "B.Cu")
		(net "P3V3_EN")
	)
	(segment
		(start 19.2405 -11.4427)
		(end 19.704304 -10.978896)
		(width 0.2032)
		(layer "B.Cu")
		(net "P3V3_EN")
	)
	(segment
		(start 19.0373 -13.1572)
		(end 19.2405 -12.954)
		(width 0.254)
		(layer "B.Cu")
		(net "P3V3_EN")
	)
	(segment
		(start 16.764 -13.3096)
		(end 17.5641 -13.3096)
		(width 0.254)
		(layer "B.Cu")
		(net "P3V3_EN")
	)
	(segment
		(start 17.5641 -13.3096)
		(end 17.6657 -13.4112)
		(width 0.254)
		(layer "B.Cu")
		(net "P3V3_EN")
	)
	(segment
		(start 18.7833 -13.4112)
		(end 19.0373 -13.1572)
		(width 0.254)
		(layer "B.Cu")
		(net "P3V3_EN")
	)
	(segment
		(start 60.90539 7.577836)
		(end 60.686696 7.890002)
		(width 0.127)
		(layer "F.Cu")
		(net "P3E_CPU0_PE1_SS_C_TXP<7>")
	)
	(segment
		(start 60.686696 7.890002)
		(end 60.442602 7.933182)
		(width 0.127)
		(layer "F.Cu")
		(net "P3E_CPU0_PE1_SS_C_TXP<7>")
	)
	(segment
		(start 82.625438 -8.081772)
		(end 82.691732 -8.048498)
		(width 0.127)
		(layer "F.Cu")
		(net "P3E_CPU0_PE1_SS_C_TXP<7>")
	)
	(segment
		(start 59.827414 10.05713)
		(end 59.827414 10.45718)
		(width 0.127)
		(layer "F.Cu")
		(net "P3E_CPU0_PE1_SS_C_TXP<7>")
	)
	(segment
		(start 82.980022 -7.309358)
		(end 82.980022 -6.969252)
		(width 0.127)
		(layer "F.Cu")
		(net "P3E_CPU0_PE1_SS_C_TXP<7>")
	)
	(segment
		(start 60.048648 8.801354)
		(end 59.827414 10.05713)
		(width 0.127)
		(layer "F.Cu")
		(net "P3E_CPU0_PE1_SS_C_TXP<7>")
	)
	(segment
		(start 82.109818 -5.852414)
		(end 73.5076 -4.335526)
		(width 0.127)
		(layer "F.Cu")
		(net "P3E_CPU0_PE1_SS_C_TXP<7>")
	)
	(segment
		(start 82.672174 -6.246368)
		(end 82.109818 -5.852414)
		(width 0.127)
		(layer "F.Cu")
		(net "P3E_CPU0_PE1_SS_C_TXP<7>")
	)
	(segment
		(start 60.86221 7.333742)
		(end 60.90539 7.577836)
		(width 0.127)
		(layer "F.Cu")
		(net "P3E_CPU0_PE1_SS_C_TXP<7>")
	)
	(segment
		(start 82.979768 -7.309104)
		(end 82.980022 -7.309358)
		(width 0.127)
		(layer "F.Cu")
		(net "P3E_CPU0_PE1_SS_C_TXP<7>")
	)
	(segment
		(start 64.643254 2.239772)
		(end 61.324998 6.97865)
		(width 0.127)
		(layer "F.Cu")
		(net "P3E_CPU0_PE1_SS_C_TXP<7>")
	)
	(segment
		(start 65.14973 1.516634)
		(end 64.643254 2.239772)
		(width 0.127)
		(layer "F.Cu")
		(net "P3E_CPU0_PE1_SS_C_TXP<7>")
	)
	(segment
		(start 61.080904 7.02183)
		(end 60.86221 7.333742)
		(width 0.127)
		(layer "F.Cu")
		(net "P3E_CPU0_PE1_SS_C_TXP<7>")
	)
	(segment
		(start 60.267088 8.489188)
		(end 60.048648 8.801354)
		(width 0.127)
		(layer "F.Cu")
		(net "P3E_CPU0_PE1_SS_C_TXP<7>")
	)
	(segment
		(start 82.079592 -7.250176)
		(end 82.237834 -7.591298)
		(width 0.127)
		(layer "F.Cu")
		(net "P3E_CPU0_PE1_SS_C_TXP<7>")
	)
	(segment
		(start 59.580018 11.054588)
		(end 59.580018 12.133072)
		(width 0.127)
		(layer "F.Cu")
		(net "P3E_CPU0_PE1_SS_C_TXP<7>")
	)
	(segment
		(start 73.5076 -4.335526)
		(end 65.14973 1.516634)
		(width 0.127)
		(layer "F.Cu")
		(net "P3E_CPU0_PE1_SS_C_TXP<7>")
	)
	(segment
		(start 60.224162 8.245094)
		(end 60.267088 8.489188)
		(width 0.127)
		(layer "F.Cu")
		(net "P3E_CPU0_PE1_SS_C_TXP<7>")
	)
	(segment
		(start 82.237834 -7.591298)
		(end 82.455004 -8.02513)
		(width 0.127)
		(layer "F.Cu")
		(net "P3E_CPU0_PE1_SS_C_TXP<7>")
	)
	(segment
		(start 61.324998 6.97865)
		(end 61.080904 7.02183)
		(width 0.127)
		(layer "F.Cu")
		(net "P3E_CPU0_PE1_SS_C_TXP<7>")
	)
	(segment
		(start 60.442602 7.933182)
		(end 60.224162 8.245094)
		(width 0.127)
		(layer "F.Cu")
		(net "P3E_CPU0_PE1_SS_C_TXP<7>")
	)
	(segment
		(start 82.91322 -6.590538)
		(end 82.672174 -6.246368)
		(width 0.127)
		(layer "F.Cu")
		(net "P3E_CPU0_PE1_SS_C_TXP<7>")
	)
	(segment
		(start 82.980022 -6.969252)
		(end 82.91322 -6.590538)
		(width 0.127)
		(layer "F.Cu")
		(net "P3E_CPU0_PE1_SS_C_TXP<7>")
	)
	(arc
		(start 82.691732 -8.048498)
		(mid 82.905231 -7.705866)
		(end 82.979768 -7.309104)
		(width 0.127)
		(layer "F.Cu")
		(net "P3E_CPU0_PE1_SS_C_TXP<7>")
	)
	(arc
		(start 59.703716 10.755884)
		(mid 59.612144 10.892931)
		(end 59.580018 11.054588)
		(width 0.127)
		(layer "F.Cu")
		(net "P3E_CPU0_PE1_SS_C_TXP<7>")
	)
	(arc
		(start 59.827414 10.45718)
		(mid 59.795261 10.618826)
		(end 59.703716 10.755884)
		(width 0.127)
		(layer "F.Cu")
		(net "P3E_CPU0_PE1_SS_C_TXP<7>")
	)
	(arc
		(start 82.455004 -8.02513)
		(mid 82.52849 -8.088749)
		(end 82.625438 -8.081772)
		(width 0.127)
		(layer "F.Cu")
		(net "P3E_CPU0_PE1_SS_C_TXP<7>")
	)
	(segment
		(start 68.3514 0.748538)
		(end 67.312032 1.476248)
		(width 0.127)
		(layer "F.Cu")
		(net "P3E_CPU0_PE1_SS_C_TXP<6>")
	)
	(segment
		(start 63.593472 6.481572)
		(end 63.375032 6.793484)
		(width 0.127)
		(layer "F.Cu")
		(net "P3E_CPU0_PE1_SS_C_TXP<6>")
	)
	(segment
		(start 86.50732 -6.238494)
		(end 84.926932 -5.131816)
		(width 0.127)
		(layer "F.Cu")
		(net "P3E_CPU0_PE1_SS_C_TXP<6>")
	)
	(segment
		(start 67.312032 1.476248)
		(end 63.837566 6.438392)
		(width 0.127)
		(layer "F.Cu")
		(net "P3E_CPU0_PE1_SS_C_TXP<6>")
	)
	(segment
		(start 62.22746 10.155936)
		(end 62.22746 10.46988)
		(width 0.127)
		(layer "F.Cu")
		(net "P3E_CPU0_PE1_SS_C_TXP<6>")
	)
	(segment
		(start 86.624922 -8.081772)
		(end 86.625176 -8.081772)
		(width 0.127)
		(layer "F.Cu")
		(net "P3E_CPU0_PE1_SS_C_TXP<6>")
	)
	(segment
		(start 86.923118 -7.445502)
		(end 86.923372 -7.445756)
		(width 0.127)
		(layer "F.Cu")
		(net "P3E_CPU0_PE1_SS_C_TXP<6>")
	)
	(segment
		(start 86.080092 -7.250176)
		(end 86.213696 -7.54253)
		(width 0.127)
		(layer "F.Cu")
		(net "P3E_CPU0_PE1_SS_C_TXP<6>")
	)
	(segment
		(start 86.213696 -7.54253)
		(end 86.454488 -8.024876)
		(width 0.127)
		(layer "F.Cu")
		(net "P3E_CPU0_PE1_SS_C_TXP<6>")
	)
	(segment
		(start 73.997312 -3.204718)
		(end 68.3514 0.748284)
		(width 0.127)
		(layer "F.Cu")
		(net "P3E_CPU0_PE1_SS_C_TXP<6>")
	)
	(segment
		(start 63.418212 7.037578)
		(end 63.199518 7.349744)
		(width 0.127)
		(layer "F.Cu")
		(net "P3E_CPU0_PE1_SS_C_TXP<6>")
	)
	(segment
		(start 62.77991 7.94893)
		(end 62.56147 8.261096)
		(width 0.127)
		(layer "F.Cu")
		(net "P3E_CPU0_PE1_SS_C_TXP<6>")
	)
	(segment
		(start 63.199518 7.349744)
		(end 62.955424 7.392924)
		(width 0.127)
		(layer "F.Cu")
		(net "P3E_CPU0_PE1_SS_C_TXP<6>")
	)
	(segment
		(start 63.837566 6.438392)
		(end 63.593472 6.481572)
		(width 0.127)
		(layer "F.Cu")
		(net "P3E_CPU0_PE1_SS_C_TXP<6>")
	)
	(segment
		(start 61.97981 11.067796)
		(end 61.97981 12.133072)
		(width 0.127)
		(layer "F.Cu")
		(net "P3E_CPU0_PE1_SS_C_TXP<6>")
	)
	(segment
		(start 86.625176 -8.081772)
		(end 86.691216 -8.048752)
		(width 0.127)
		(layer "F.Cu")
		(net "P3E_CPU0_PE1_SS_C_TXP<6>")
	)
	(segment
		(start 84.926932 -5.131816)
		(end 73.997312 -3.204718)
		(width 0.127)
		(layer "F.Cu")
		(net "P3E_CPU0_PE1_SS_C_TXP<6>")
	)
	(segment
		(start 86.923372 -7.115302)
		(end 86.50732 -6.238494)
		(width 0.127)
		(layer "F.Cu")
		(net "P3E_CPU0_PE1_SS_C_TXP<6>")
	)
	(segment
		(start 62.56147 8.261096)
		(end 62.22746 10.155936)
		(width 0.127)
		(layer "F.Cu")
		(net "P3E_CPU0_PE1_SS_C_TXP<6>")
	)
	(segment
		(start 63.375032 6.793484)
		(end 63.418212 7.037578)
		(width 0.127)
		(layer "F.Cu")
		(net "P3E_CPU0_PE1_SS_C_TXP<6>")
	)
	(segment
		(start 62.736984 7.704836)
		(end 62.77991 7.94893)
		(width 0.127)
		(layer "F.Cu")
		(net "P3E_CPU0_PE1_SS_C_TXP<6>")
	)
	(segment
		(start 68.3514 0.748284)
		(end 68.3514 0.748538)
		(width 0.127)
		(layer "F.Cu")
		(net "P3E_CPU0_PE1_SS_C_TXP<6>")
	)
	(segment
		(start 86.923372 -7.445756)
		(end 86.923372 -7.115302)
		(width 0.127)
		(layer "F.Cu")
		(net "P3E_CPU0_PE1_SS_C_TXP<6>")
	)
	(segment
		(start 62.955424 7.392924)
		(end 62.736984 7.704836)
		(width 0.127)
		(layer "F.Cu")
		(net "P3E_CPU0_PE1_SS_C_TXP<6>")
	)
	(arc
		(start 62.22746 10.46988)
		(mid 62.195249 10.631818)
		(end 62.103508 10.769092)
		(width 0.127)
		(layer "F.Cu")
		(net "P3E_CPU0_PE1_SS_C_TXP<6>")
	)
	(arc
		(start 86.454488 -8.024876)
		(mid 86.527902 -8.088605)
		(end 86.624922 -8.081772)
		(width 0.127)
		(layer "F.Cu")
		(net "P3E_CPU0_PE1_SS_C_TXP<6>")
	)
	(arc
		(start 86.691216 -8.048752)
		(mid 86.863172 -7.768653)
		(end 86.923118 -7.445502)
		(width 0.127)
		(layer "F.Cu")
		(net "P3E_CPU0_PE1_SS_C_TXP<6>")
	)
	(arc
		(start 62.103508 10.769092)
		(mid 62.011936 10.906139)
		(end 61.97981 11.067796)
		(width 0.127)
		(layer "F.Cu")
		(net "P3E_CPU0_PE1_SS_C_TXP<6>")
	)
	(segment
		(start 90.079322 -7.250176)
		(end 90.1827 -7.48157)
		(width 0.127)
		(layer "F.Cu")
		(net "P3E_CPU0_PE1_SS_C_TXP<5>")
	)
	(segment
		(start 65.901824 6.563106)
		(end 65.68313 6.875272)
		(width 0.127)
		(layer "F.Cu")
		(net "P3E_CPU0_PE1_SS_C_TXP<5>")
	)
	(segment
		(start 90.66276 -6.587236)
		(end 87.493856 -4.368546)
		(width 0.127)
		(layer "F.Cu")
		(net "P3E_CPU0_PE1_SS_C_TXP<5>")
	)
	(segment
		(start 90.625168 -8.081772)
		(end 90.625422 -8.081772)
		(width 0.127)
		(layer "F.Cu")
		(net "P3E_CPU0_PE1_SS_C_TXP<5>")
	)
	(segment
		(start 74.472292 -2.072386)
		(end 70.469252 0.730504)
		(width 0.127)
		(layer "F.Cu")
		(net "P3E_CPU0_PE1_SS_C_TXP<5>")
	)
	(segment
		(start 65.220596 7.230364)
		(end 65.263522 7.474458)
		(width 0.127)
		(layer "F.Cu")
		(net "P3E_CPU0_PE1_SS_C_TXP<5>")
	)
	(segment
		(start 69.520816 1.394714)
		(end 66.321432 5.96392)
		(width 0.127)
		(layer "F.Cu")
		(net "P3E_CPU0_PE1_SS_C_TXP<5>")
	)
	(segment
		(start 90.91549 -6.959092)
		(end 90.66276 -6.587236)
		(width 0.127)
		(layer "F.Cu")
		(net "P3E_CPU0_PE1_SS_C_TXP<5>")
	)
	(segment
		(start 90.625422 -8.081772)
		(end 90.628216 -8.080248)
		(width 0.127)
		(layer "F.Cu")
		(net "P3E_CPU0_PE1_SS_C_TXP<5>")
	)
	(segment
		(start 65.68313 6.875272)
		(end 65.439036 6.918452)
		(width 0.127)
		(layer "F.Cu")
		(net "P3E_CPU0_PE1_SS_C_TXP<5>")
	)
	(segment
		(start 65.045082 7.786624)
		(end 64.627506 10.155936)
		(width 0.127)
		(layer "F.Cu")
		(net "P3E_CPU0_PE1_SS_C_TXP<5>")
	)
	(segment
		(start 64.379856 10.97915)
		(end 64.379856 12.133072)
		(width 0.127)
		(layer "F.Cu")
		(net "P3E_CPU0_PE1_SS_C_TXP<5>")
	)
	(segment
		(start 90.1827 -7.48157)
		(end 90.454734 -8.02513)
		(width 0.127)
		(layer "F.Cu")
		(net "P3E_CPU0_PE1_SS_C_TXP<5>")
	)
	(segment
		(start 70.469252 0.730504)
		(end 69.520816 1.394714)
		(width 0.127)
		(layer "F.Cu")
		(net "P3E_CPU0_PE1_SS_C_TXP<5>")
	)
	(segment
		(start 90.628216 -8.080248)
		(end 90.738706 -8.024876)
		(width 0.127)
		(layer "F.Cu")
		(net "P3E_CPU0_PE1_SS_C_TXP<5>")
	)
	(segment
		(start 66.077338 6.0071)
		(end 65.858644 6.319012)
		(width 0.127)
		(layer "F.Cu")
		(net "P3E_CPU0_PE1_SS_C_TXP<5>")
	)
	(segment
		(start 87.493856 -4.368546)
		(end 74.472292 -2.072386)
		(width 0.127)
		(layer "F.Cu")
		(net "P3E_CPU0_PE1_SS_C_TXP<5>")
	)
	(segment
		(start 64.504062 10.680192)
		(end 64.503808 10.680446)
		(width 0.127)
		(layer "F.Cu")
		(net "P3E_CPU0_PE1_SS_C_TXP<5>")
	)
	(segment
		(start 64.627506 10.155936)
		(end 64.627506 10.381742)
		(width 0.127)
		(layer "F.Cu")
		(net "P3E_CPU0_PE1_SS_C_TXP<5>")
	)
	(segment
		(start 65.439036 6.918452)
		(end 65.220596 7.230364)
		(width 0.127)
		(layer "F.Cu")
		(net "P3E_CPU0_PE1_SS_C_TXP<5>")
	)
	(segment
		(start 65.858644 6.319012)
		(end 65.901824 6.563106)
		(width 0.127)
		(layer "F.Cu")
		(net "P3E_CPU0_PE1_SS_C_TXP<5>")
	)
	(segment
		(start 65.263522 7.474458)
		(end 65.045082 7.786624)
		(width 0.127)
		(layer "F.Cu")
		(net "P3E_CPU0_PE1_SS_C_TXP<5>")
	)
	(segment
		(start 66.321432 5.96392)
		(end 66.077338 6.0071)
		(width 0.127)
		(layer "F.Cu")
		(net "P3E_CPU0_PE1_SS_C_TXP<5>")
	)
	(arc
		(start 90.454734 -8.02513)
		(mid 90.52822 -8.088749)
		(end 90.625168 -8.081772)
		(width 0.127)
		(layer "F.Cu")
		(net "P3E_CPU0_PE1_SS_C_TXP<5>")
	)
	(arc
		(start 64.627506 10.381742)
		(mid 64.595421 10.543222)
		(end 64.504062 10.680192)
		(width 0.127)
		(layer "F.Cu")
		(net "P3E_CPU0_PE1_SS_C_TXP<5>")
	)
	(arc
		(start 90.94851 -7.11962)
		(mid 90.948053 -7.036052)
		(end 90.91549 -6.959092)
		(width 0.127)
		(layer "F.Cu")
		(net "P3E_CPU0_PE1_SS_C_TXP<5>")
	)
	(arc
		(start 90.93835 -7.639558)
		(mid 90.920927 -7.379148)
		(end 90.94851 -7.11962)
		(width 0.127)
		(layer "F.Cu")
		(net "P3E_CPU0_PE1_SS_C_TXP<5>")
	)
	(arc
		(start 90.738706 -8.024876)
		(mid 90.901389 -7.864779)
		(end 90.93835 -7.639558)
		(width 0.127)
		(layer "F.Cu")
		(net "P3E_CPU0_PE1_SS_C_TXP<5>")
	)
	(arc
		(start 64.503808 10.680446)
		(mid 64.412153 10.817478)
		(end 64.379856 10.97915)
		(width 0.127)
		(layer "F.Cu")
		(net "P3E_CPU0_PE1_SS_C_TXP<5>")
	)
	(segment
		(start 94.691454 -8.048498)
		(end 94.624906 -8.081772)
		(width 0.127)
		(layer "F.Cu")
		(net "P3E_CPU0_PE1_SS_C_TXP<4>")
	)
	(segment
		(start 71.46798 1.616964)
		(end 74.939906 -0.813816)
		(width 0.127)
		(layer "F.Cu")
		(net "P3E_CPU0_PE1_SS_C_TXP<4>")
	)
	(segment
		(start 66.779902 12.133072)
		(end 66.779902 11.065256)
		(width 0.127)
		(layer "F.Cu")
		(net "P3E_CPU0_PE1_SS_C_TXP<4>")
	)
	(segment
		(start 87.402162 -3.01117)
		(end 90.603578 -3.575812)
		(width 0.127)
		(layer "F.Cu")
		(net "P3E_CPU0_PE1_SS_C_TXP<4>")
	)
	(segment
		(start 68.57746 5.439664)
		(end 68.821554 5.396484)
		(width 0.127)
		(layer "F.Cu")
		(net "P3E_CPU0_PE1_SS_C_TXP<4>")
	)
	(segment
		(start 94.961456 -7.022846)
		(end 94.961456 -7.352792)
		(width 0.127)
		(layer "F.Cu")
		(net "P3E_CPU0_PE1_SS_C_TXP<4>")
	)
	(segment
		(start 68.35902 5.751576)
		(end 68.57746 5.439664)
		(width 0.127)
		(layer "F.Cu")
		(net "P3E_CPU0_PE1_SS_C_TXP<4>")
	)
	(segment
		(start 74.939906 -0.813816)
		(end 87.402162 -3.01117)
		(width 0.127)
		(layer "F.Cu")
		(net "P3E_CPU0_PE1_SS_C_TXP<4>")
	)
	(segment
		(start 94.624906 -8.081772)
		(end 94.624652 -8.081772)
		(width 0.127)
		(layer "F.Cu")
		(net "P3E_CPU0_PE1_SS_C_TXP<4>")
	)
	(segment
		(start 67.720972 6.662928)
		(end 67.939412 6.351016)
		(width 0.127)
		(layer "F.Cu")
		(net "P3E_CPU0_PE1_SS_C_TXP<4>")
	)
	(segment
		(start 90.603578 -3.575812)
		(end 94.403164 -6.236208)
		(width 0.127)
		(layer "F.Cu")
		(net "P3E_CPU0_PE1_SS_C_TXP<4>")
	)
	(segment
		(start 67.545458 7.219188)
		(end 67.763898 6.907022)
		(width 0.127)
		(layer "F.Cu")
		(net "P3E_CPU0_PE1_SS_C_TXP<4>")
	)
	(segment
		(start 68.183506 6.307836)
		(end 68.4022 5.99567)
		(width 0.127)
		(layer "F.Cu")
		(net "P3E_CPU0_PE1_SS_C_TXP<4>")
	)
	(segment
		(start 94.454218 -8.024876)
		(end 94.26702 -7.649972)
		(width 0.127)
		(layer "F.Cu")
		(net "P3E_CPU0_PE1_SS_C_TXP<4>")
	)
	(segment
		(start 68.4022 5.99567)
		(end 68.35902 5.751576)
		(width 0.127)
		(layer "F.Cu")
		(net "P3E_CPU0_PE1_SS_C_TXP<4>")
	)
	(segment
		(start 67.763898 6.907022)
		(end 67.720972 6.662928)
		(width 0.127)
		(layer "F.Cu")
		(net "P3E_CPU0_PE1_SS_C_TXP<4>")
	)
	(segment
		(start 67.939412 6.351016)
		(end 68.183506 6.307836)
		(width 0.127)
		(layer "F.Cu")
		(net "P3E_CPU0_PE1_SS_C_TXP<4>")
	)
	(segment
		(start 67.027552 10.155682)
		(end 67.545458 7.219188)
		(width 0.127)
		(layer "F.Cu")
		(net "P3E_CPU0_PE1_SS_C_TXP<4>")
	)
	(segment
		(start 94.26702 -7.649972)
		(end 94.079822 -7.250176)
		(width 0.127)
		(layer "F.Cu")
		(net "P3E_CPU0_PE1_SS_C_TXP<4>")
	)
	(segment
		(start 68.821554 5.396484)
		(end 71.46798 1.616964)
		(width 0.127)
		(layer "F.Cu")
		(net "P3E_CPU0_PE1_SS_C_TXP<4>")
	)
	(segment
		(start 94.403164 -6.236208)
		(end 94.721934 -6.506718)
		(width 0.127)
		(layer "F.Cu")
		(net "P3E_CPU0_PE1_SS_C_TXP<4>")
	)
	(segment
		(start 94.961202 -7.0231)
		(end 94.961456 -7.022846)
		(width 0.127)
		(layer "F.Cu")
		(net "P3E_CPU0_PE1_SS_C_TXP<4>")
	)
	(segment
		(start 67.027552 10.46734)
		(end 67.027552 10.155682)
		(width 0.127)
		(layer "F.Cu")
		(net "P3E_CPU0_PE1_SS_C_TXP<4>")
	)
	(arc
		(start 66.779902 11.065256)
		(mid 66.812055 10.90361)
		(end 66.9036 10.766552)
		(width 0.127)
		(layer "F.Cu")
		(net "P3E_CPU0_PE1_SS_C_TXP<4>")
	)
	(arc
		(start 94.721934 -6.506718)
		(mid 94.898529 -6.738524)
		(end 94.961202 -7.0231)
		(width 0.127)
		(layer "F.Cu")
		(net "P3E_CPU0_PE1_SS_C_TXP<4>")
	)
	(arc
		(start 66.9036 10.766552)
		(mid 66.995327 10.629272)
		(end 67.027552 10.46734)
		(width 0.127)
		(layer "F.Cu")
		(net "P3E_CPU0_PE1_SS_C_TXP<4>")
	)
	(arc
		(start 94.624652 -8.081772)
		(mid 94.527596 -8.088713)
		(end 94.454218 -8.024876)
		(width 0.127)
		(layer "F.Cu")
		(net "P3E_CPU0_PE1_SS_C_TXP<4>")
	)
	(arc
		(start 94.961456 -7.352792)
		(mid 94.891599 -7.725932)
		(end 94.691454 -8.048498)
		(width 0.127)
		(layer "F.Cu")
		(net "P3E_CPU0_PE1_SS_C_TXP<4>")
	)
	(segment
		(start 98.442272 -6.414516)
		(end 98.740722 -6.668516)
		(width 0.127)
		(layer "F.Cu")
		(net "P3E_CPU0_PE1_SS_C_TXP<3>")
	)
	(segment
		(start 69.662294 8.725408)
		(end 69.728588 8.35025)
		(width 0.127)
		(layer "F.Cu")
		(net "P3E_CPU0_PE1_SS_C_TXP<3>")
	)
	(segment
		(start 69.586348 8.147304)
		(end 69.652388 7.772146)
		(width 0.127)
		(layer "F.Cu")
		(net "P3E_CPU0_PE1_SS_C_TXP<3>")
	)
	(segment
		(start 69.3039 10.757154)
		(end 69.304154 10.7569)
		(width 0.127)
		(layer "F.Cu")
		(net "P3E_CPU0_PE1_SS_C_TXP<3>")
	)
	(segment
		(start 98.625406 -8.081772)
		(end 98.625152 -8.081772)
		(width 0.127)
		(layer "F.Cu")
		(net "P3E_CPU0_PE1_SS_C_TXP<3>")
	)
	(segment
		(start 73.067672 1.973072)
		(end 75.325732 0.392176)
		(width 0.127)
		(layer "F.Cu")
		(net "P3E_CPU0_PE1_SS_C_TXP<3>")
	)
	(segment
		(start 75.325732 0.392176)
		(end 92.187776 -2.577592)
		(width 0.127)
		(layer "F.Cu")
		(net "P3E_CPU0_PE1_SS_C_TXP<3>")
	)
	(segment
		(start 69.652388 7.772146)
		(end 69.855588 7.629906)
		(width 0.127)
		(layer "F.Cu")
		(net "P3E_CPU0_PE1_SS_C_TXP<3>")
	)
	(segment
		(start 69.427598 10.056876)
		(end 69.535294 9.446006)
		(width 0.127)
		(layer "F.Cu")
		(net "P3E_CPU0_PE1_SS_C_TXP<3>")
	)
	(segment
		(start 69.535294 9.446006)
		(end 69.393054 9.242806)
		(width 0.127)
		(layer "F.Cu")
		(net "P3E_CPU0_PE1_SS_C_TXP<3>")
	)
	(segment
		(start 70.098666 6.275832)
		(end 70.098412 6.275832)
		(width 0.127)
		(layer "F.Cu")
		(net "P3E_CPU0_PE1_SS_C_TXP<3>")
	)
	(segment
		(start 69.459348 8.867648)
		(end 69.662294 8.725408)
		(width 0.127)
		(layer "F.Cu")
		(net "P3E_CPU0_PE1_SS_C_TXP<3>")
	)
	(segment
		(start 98.454718 -8.024876)
		(end 98.26752 -7.649972)
		(width 0.127)
		(layer "F.Cu")
		(net "P3E_CPU0_PE1_SS_C_TXP<3>")
	)
	(segment
		(start 98.96475 -7.00659)
		(end 98.96475 -7.346442)
		(width 0.127)
		(layer "F.Cu")
		(net "P3E_CPU0_PE1_SS_C_TXP<3>")
	)
	(segment
		(start 69.728588 8.35025)
		(end 69.586348 8.147304)
		(width 0.127)
		(layer "F.Cu")
		(net "P3E_CPU0_PE1_SS_C_TXP<3>")
	)
	(segment
		(start 69.855588 7.629906)
		(end 70.09384 6.278118)
		(width 0.127)
		(layer "F.Cu")
		(net "P3E_CPU0_PE1_SS_C_TXP<3>")
	)
	(segment
		(start 69.393054 9.242806)
		(end 69.459348 8.867648)
		(width 0.127)
		(layer "F.Cu")
		(net "P3E_CPU0_PE1_SS_C_TXP<3>")
	)
	(segment
		(start 69.427598 10.45845)
		(end 69.427598 10.056876)
		(width 0.127)
		(layer "F.Cu")
		(net "P3E_CPU0_PE1_SS_C_TXP<3>")
	)
	(segment
		(start 98.96475 -7.346442)
		(end 98.964496 -7.346188)
		(width 0.127)
		(layer "F.Cu")
		(net "P3E_CPU0_PE1_SS_C_TXP<3>")
	)
	(segment
		(start 92.187776 -2.577592)
		(end 97.413826 -6.237224)
		(width 0.127)
		(layer "F.Cu")
		(net "P3E_CPU0_PE1_SS_C_TXP<3>")
	)
	(segment
		(start 70.09384 6.278118)
		(end 70.098666 6.275832)
		(width 0.127)
		(layer "F.Cu")
		(net "P3E_CPU0_PE1_SS_C_TXP<3>")
	)
	(segment
		(start 98.740722 -6.668516)
		(end 98.96475 -7.00659)
		(width 0.127)
		(layer "F.Cu")
		(net "P3E_CPU0_PE1_SS_C_TXP<3>")
	)
	(segment
		(start 98.26752 -7.649972)
		(end 98.080322 -7.250176)
		(width 0.127)
		(layer "F.Cu")
		(net "P3E_CPU0_PE1_SS_C_TXP<3>")
	)
	(segment
		(start 97.413826 -6.237224)
		(end 98.442272 -6.414516)
		(width 0.127)
		(layer "F.Cu")
		(net "P3E_CPU0_PE1_SS_C_TXP<3>")
	)
	(segment
		(start 70.098412 6.275832)
		(end 70.161404 6.12394)
		(width 0.127)
		(layer "F.Cu")
		(net "P3E_CPU0_PE1_SS_C_TXP<3>")
	)
	(segment
		(start 69.179948 12.133072)
		(end 69.179948 11.055858)
		(width 0.127)
		(layer "F.Cu")
		(net "P3E_CPU0_PE1_SS_C_TXP<3>")
	)
	(segment
		(start 98.691954 -8.048498)
		(end 98.625406 -8.081772)
		(width 0.127)
		(layer "F.Cu")
		(net "P3E_CPU0_PE1_SS_C_TXP<3>")
	)
	(segment
		(start 70.161404 6.12394)
		(end 73.067672 1.973072)
		(width 0.127)
		(layer "F.Cu")
		(net "P3E_CPU0_PE1_SS_C_TXP<3>")
	)
	(arc
		(start 98.625152 -8.081772)
		(mid 98.528096 -8.088713)
		(end 98.454718 -8.024876)
		(width 0.127)
		(layer "F.Cu")
		(net "P3E_CPU0_PE1_SS_C_TXP<3>")
	)
	(arc
		(start 69.179948 11.055858)
		(mid 69.212204 10.894168)
		(end 69.3039 10.757154)
		(width 0.127)
		(layer "F.Cu")
		(net "P3E_CPU0_PE1_SS_C_TXP<3>")
	)
	(arc
		(start 69.304154 10.7569)
		(mid 69.39554 10.619942)
		(end 69.427598 10.45845)
		(width 0.127)
		(layer "F.Cu")
		(net "P3E_CPU0_PE1_SS_C_TXP<3>")
	)
	(arc
		(start 98.964496 -7.346188)
		(mid 98.893958 -7.722845)
		(end 98.691954 -8.048498)
		(width 0.127)
		(layer "F.Cu")
		(net "P3E_CPU0_PE1_SS_C_TXP<3>")
	)
	(segment
		(start 72.213978 6.236462)
		(end 72.296528 5.76834)
		(width 0.127)
		(layer "F.Cu")
		(net "P3E_CPU0_PE1_SS_C_TXP<2>")
	)
	(segment
		(start 72.020938 7.332218)
		(end 72.086978 6.956806)
		(width 0.127)
		(layer "F.Cu")
		(net "P3E_CPU0_PE1_SS_C_TXP<2>")
	)
	(segment
		(start 72.011032 6.378702)
		(end 72.213978 6.236462)
		(width 0.127)
		(layer "F.Cu")
		(net "P3E_CPU0_PE1_SS_C_TXP<2>")
	)
	(segment
		(start 101.94544 -5.767578)
		(end 102.473252 -6.137148)
		(width 0.127)
		(layer "F.Cu")
		(net "P3E_CPU0_PE1_SS_C_TXP<2>")
	)
	(segment
		(start 76.063856 1.513586)
		(end 93.303852 -1.52654)
		(width 0.127)
		(layer "F.Cu")
		(net "P3E_CPU0_PE1_SS_C_TXP<2>")
	)
	(segment
		(start 98.48977 -5.15747)
		(end 101.94544 -5.767578)
		(width 0.127)
		(layer "F.Cu")
		(net "P3E_CPU0_PE1_SS_C_TXP<2>")
	)
	(segment
		(start 74.475848 2.655824)
		(end 74.479404 2.655824)
		(width 0.127)
		(layer "F.Cu")
		(net "P3E_CPU0_PE1_SS_C_TXP<2>")
	)
	(segment
		(start 102.22611 -7.568184)
		(end 102.079552 -7.250176)
		(width 0.127)
		(layer "F.Cu")
		(net "P3E_CPU0_PE1_SS_C_TXP<2>")
	)
	(segment
		(start 102.690676 -8.049006)
		(end 102.625398 -8.081772)
		(width 0.127)
		(layer "F.Cu")
		(net "P3E_CPU0_PE1_SS_C_TXP<2>")
	)
	(segment
		(start 102.454964 -8.02513)
		(end 102.22611 -7.568184)
		(width 0.127)
		(layer "F.Cu")
		(net "P3E_CPU0_PE1_SS_C_TXP<2>")
	)
	(segment
		(start 71.944738 6.75386)
		(end 72.011032 6.378702)
		(width 0.127)
		(layer "F.Cu")
		(net "P3E_CPU0_PE1_SS_C_TXP<2>")
	)
	(segment
		(start 71.579994 12.133072)
		(end 71.579994 10.992866)
		(width 0.127)
		(layer "F.Cu")
		(net "P3E_CPU0_PE1_SS_C_TXP<2>")
	)
	(segment
		(start 74.475594 2.656078)
		(end 74.475848 2.655824)
		(width 0.127)
		(layer "F.Cu")
		(net "P3E_CPU0_PE1_SS_C_TXP<2>")
	)
	(segment
		(start 71.893684 8.052562)
		(end 71.751698 7.849362)
		(width 0.127)
		(layer "F.Cu")
		(net "P3E_CPU0_PE1_SS_C_TXP<2>")
	)
	(segment
		(start 102.785926 -6.58368)
		(end 102.88397 -7.140448)
		(width 0.127)
		(layer "F.Cu")
		(net "P3E_CPU0_PE1_SS_C_TXP<2>")
	)
	(segment
		(start 93.303852 -1.52654)
		(end 98.48977 -5.15747)
		(width 0.127)
		(layer "F.Cu")
		(net "P3E_CPU0_PE1_SS_C_TXP<2>")
	)
	(segment
		(start 72.296528 5.76834)
		(end 74.475594 2.656078)
		(width 0.127)
		(layer "F.Cu")
		(net "P3E_CPU0_PE1_SS_C_TXP<2>")
	)
	(segment
		(start 74.58964 2.545334)
		(end 76.063856 1.513586)
		(width 0.127)
		(layer "F.Cu")
		(net "P3E_CPU0_PE1_SS_C_TXP<2>")
	)
	(segment
		(start 102.473252 -6.137148)
		(end 102.785926 -6.58368)
		(width 0.127)
		(layer "F.Cu")
		(net "P3E_CPU0_PE1_SS_C_TXP<2>")
	)
	(segment
		(start 72.086978 6.956806)
		(end 71.944738 6.75386)
		(width 0.127)
		(layer "F.Cu")
		(net "P3E_CPU0_PE1_SS_C_TXP<2>")
	)
	(segment
		(start 71.827644 8.42772)
		(end 71.893684 8.052562)
		(width 0.127)
		(layer "F.Cu")
		(net "P3E_CPU0_PE1_SS_C_TXP<2>")
	)
	(segment
		(start 71.751698 7.849362)
		(end 71.817738 7.474204)
		(width 0.127)
		(layer "F.Cu")
		(net "P3E_CPU0_PE1_SS_C_TXP<2>")
	)
	(segment
		(start 71.817738 7.474204)
		(end 72.020938 7.332218)
		(width 0.127)
		(layer "F.Cu")
		(net "P3E_CPU0_PE1_SS_C_TXP<2>")
	)
	(segment
		(start 102.88397 -7.140448)
		(end 102.88397 -7.540244)
		(width 0.127)
		(layer "F.Cu")
		(net "P3E_CPU0_PE1_SS_C_TXP<2>")
	)
	(segment
		(start 74.479404 2.655824)
		(end 74.58964 2.545334)
		(width 0.127)
		(layer "F.Cu")
		(net "P3E_CPU0_PE1_SS_C_TXP<2>")
	)
	(segment
		(start 71.827644 10.39495)
		(end 71.827644 8.42772)
		(width 0.127)
		(layer "F.Cu")
		(net "P3E_CPU0_PE1_SS_C_TXP<2>")
	)
	(arc
		(start 71.579994 10.992866)
		(mid 71.612205 10.830928)
		(end 71.703946 10.693654)
		(width 0.127)
		(layer "F.Cu")
		(net "P3E_CPU0_PE1_SS_C_TXP<2>")
	)
	(arc
		(start 71.703946 10.693654)
		(mid 71.795518 10.556607)
		(end 71.827644 10.39495)
		(width 0.127)
		(layer "F.Cu")
		(net "P3E_CPU0_PE1_SS_C_TXP<2>")
	)
	(arc
		(start 102.625398 -8.081772)
		(mid 102.52845 -8.088749)
		(end 102.454964 -8.02513)
		(width 0.127)
		(layer "F.Cu")
		(net "P3E_CPU0_PE1_SS_C_TXP<2>")
	)
	(arc
		(start 102.88397 -7.540244)
		(mid 102.834011 -7.81236)
		(end 102.690676 -8.049006)
		(width 0.127)
		(layer "F.Cu")
		(net "P3E_CPU0_PE1_SS_C_TXP<2>")
	)
	(segment
		(start 74.172064 8.424418)
		(end 74.10577 8.04926)
		(width 0.127)
		(layer "F.Cu")
		(net "P3E_CPU0_PE1_SS_C_TXP<1>")
	)
	(segment
		(start 74.37501 8.566658)
		(end 74.172064 8.424418)
		(width 0.127)
		(layer "F.Cu")
		(net "P3E_CPU0_PE1_SS_C_TXP<1>")
	)
	(segment
		(start 74.031856 5.74802)
		(end 75.804522 3.216148)
		(width 0.127)
		(layer "F.Cu")
		(net "P3E_CPU0_PE1_SS_C_TXP<1>")
	)
	(segment
		(start 74.441304 8.941816)
		(end 74.37501 8.566658)
		(width 0.127)
		(layer "F.Cu")
		(net "P3E_CPU0_PE1_SS_C_TXP<1>")
	)
	(segment
		(start 98.929698 -3.984752)
		(end 105.447846 -5.133848)
		(width 0.127)
		(layer "F.Cu")
		(net "P3E_CPU0_PE1_SS_C_TXP<1>")
	)
	(segment
		(start 75.804522 3.216148)
		(end 76.657708 2.61874)
		(width 0.127)
		(layer "F.Cu")
		(net "P3E_CPU0_PE1_SS_C_TXP<1>")
	)
	(segment
		(start 74.10577 8.04926)
		(end 74.247756 7.846314)
		(width 0.127)
		(layer "F.Cu")
		(net "P3E_CPU0_PE1_SS_C_TXP<1>")
	)
	(segment
		(start 73.912222 6.953758)
		(end 74.054462 6.750558)
		(width 0.127)
		(layer "F.Cu")
		(net "P3E_CPU0_PE1_SS_C_TXP<1>")
	)
	(segment
		(start 106.454448 -8.024876)
		(end 106.26725 -7.649972)
		(width 0.127)
		(layer "F.Cu")
		(net "P3E_CPU0_PE1_SS_C_TXP<1>")
	)
	(segment
		(start 106.625136 -8.081772)
		(end 106.624882 -8.081772)
		(width 0.127)
		(layer "F.Cu")
		(net "P3E_CPU0_PE1_SS_C_TXP<1>")
	)
	(segment
		(start 74.247756 7.846314)
		(end 74.181716 7.471156)
		(width 0.127)
		(layer "F.Cu")
		(net "P3E_CPU0_PE1_SS_C_TXP<1>")
	)
	(segment
		(start 105.447846 -5.133848)
		(end 106.495342 -5.8674)
		(width 0.127)
		(layer "F.Cu")
		(net "P3E_CPU0_PE1_SS_C_TXP<1>")
	)
	(segment
		(start 73.95464 6.185408)
		(end 74.031856 5.74802)
		(width 0.127)
		(layer "F.Cu")
		(net "P3E_CPU0_PE1_SS_C_TXP<1>")
	)
	(segment
		(start 106.495342 -5.8674)
		(end 106.885486 -6.424422)
		(width 0.127)
		(layer "F.Cu")
		(net "P3E_CPU0_PE1_SS_C_TXP<1>")
	)
	(segment
		(start 106.26725 -7.649972)
		(end 106.080052 -7.250176)
		(width 0.127)
		(layer "F.Cu")
		(net "P3E_CPU0_PE1_SS_C_TXP<1>")
	)
	(segment
		(start 93.820234 -0.407162)
		(end 98.929698 -3.984752)
		(width 0.127)
		(layer "F.Cu")
		(net "P3E_CPU0_PE1_SS_C_TXP<1>")
	)
	(segment
		(start 73.979786 12.133072)
		(end 73.979786 11.031474)
		(width 0.127)
		(layer "F.Cu")
		(net "P3E_CPU0_PE1_SS_C_TXP<1>")
	)
	(segment
		(start 106.691684 -8.048498)
		(end 106.625136 -8.081772)
		(width 0.127)
		(layer "F.Cu")
		(net "P3E_CPU0_PE1_SS_C_TXP<1>")
	)
	(segment
		(start 74.227436 10.155936)
		(end 74.441304 8.941816)
		(width 0.127)
		(layer "F.Cu")
		(net "P3E_CPU0_PE1_SS_C_TXP<1>")
	)
	(segment
		(start 74.227436 10.433558)
		(end 74.227436 10.155936)
		(width 0.127)
		(layer "F.Cu")
		(net "P3E_CPU0_PE1_SS_C_TXP<1>")
	)
	(segment
		(start 106.885486 -6.424422)
		(end 106.96448 -6.872224)
		(width 0.127)
		(layer "F.Cu")
		(net "P3E_CPU0_PE1_SS_C_TXP<1>")
	)
	(segment
		(start 73.978516 7.328916)
		(end 73.912222 6.953758)
		(width 0.127)
		(layer "F.Cu")
		(net "P3E_CPU0_PE1_SS_C_TXP<1>")
	)
	(segment
		(start 74.054462 6.750558)
		(end 73.95464 6.185408)
		(width 0.127)
		(layer "F.Cu")
		(net "P3E_CPU0_PE1_SS_C_TXP<1>")
	)
	(segment
		(start 74.181716 7.471156)
		(end 73.978516 7.328916)
		(width 0.127)
		(layer "F.Cu")
		(net "P3E_CPU0_PE1_SS_C_TXP<1>")
	)
	(segment
		(start 106.96448 -6.872224)
		(end 106.96448 -7.346442)
		(width 0.127)
		(layer "F.Cu")
		(net "P3E_CPU0_PE1_SS_C_TXP<1>")
	)
	(segment
		(start 76.657708 2.61874)
		(end 93.820234 -0.407162)
		(width 0.127)
		(layer "F.Cu")
		(net "P3E_CPU0_PE1_SS_C_TXP<1>")
	)
	(segment
		(start 106.96448 -7.346442)
		(end 106.964226 -7.346188)
		(width 0.127)
		(layer "F.Cu")
		(net "P3E_CPU0_PE1_SS_C_TXP<1>")
	)
	(arc
		(start 106.624882 -8.081772)
		(mid 106.527826 -8.088713)
		(end 106.454448 -8.024876)
		(width 0.127)
		(layer "F.Cu")
		(net "P3E_CPU0_PE1_SS_C_TXP<1>")
	)
	(arc
		(start 106.964226 -7.346188)
		(mid 106.893688 -7.722845)
		(end 106.691684 -8.048498)
		(width 0.127)
		(layer "F.Cu")
		(net "P3E_CPU0_PE1_SS_C_TXP<1>")
	)
	(arc
		(start 74.103738 10.732262)
		(mid 74.19531 10.595215)
		(end 74.227436 10.433558)
		(width 0.127)
		(layer "F.Cu")
		(net "P3E_CPU0_PE1_SS_C_TXP<1>")
	)
	(arc
		(start 73.979786 11.031474)
		(mid 74.011997 10.869536)
		(end 74.103738 10.732262)
		(width 0.127)
		(layer "F.Cu")
		(net "P3E_CPU0_PE1_SS_C_TXP<1>")
	)
	(segment
		(start 110.316264 -7.74827)
		(end 110.079282 -7.250176)
		(width 0.127)
		(layer "F.Cu")
		(net "P3E_CPU0_PE1_SS_C_TXP<0>")
	)
	(segment
		(start 108.179616 -5.13207)
		(end 108.530136 -5.281422)
		(width 0.127)
		(layer "F.Cu")
		(net "P3E_CPU0_PE1_SS_C_TXP<0>")
	)
	(segment
		(start 110.454694 -8.02513)
		(end 110.316264 -7.74827)
		(width 0.127)
		(layer "F.Cu")
		(net "P3E_CPU0_PE1_SS_C_TXP<0>")
	)
	(segment
		(start 105.903268 -3.970528)
		(end 108.08716 -4.901946)
		(width 0.127)
		(layer "F.Cu")
		(net "P3E_CPU0_PE1_SS_C_TXP<0>")
	)
	(segment
		(start 110.690914 -8.048752)
		(end 110.625128 -8.081772)
		(width 0.127)
		(layer "F.Cu")
		(net "P3E_CPU0_PE1_SS_C_TXP<0>")
	)
	(segment
		(start 99.397566 -2.826004)
		(end 105.903268 -3.970528)
		(width 0.127)
		(layer "F.Cu")
		(net "P3E_CPU0_PE1_SS_C_TXP<0>")
	)
	(segment
		(start 75.80249 5.97535)
		(end 76.930758 4.36372)
		(width 0.127)
		(layer "F.Cu")
		(net "P3E_CPU0_PE1_SS_C_TXP<0>")
	)
	(segment
		(start 77.04455 4.252722)
		(end 77.806296 3.719576)
		(width 0.127)
		(layer "F.Cu")
		(net "P3E_CPU0_PE1_SS_C_TXP<0>")
	)
	(segment
		(start 77.806296 3.719576)
		(end 86.054438 2.265426)
		(width 0.127)
		(layer "F.Cu")
		(net "P3E_CPU0_PE1_SS_C_TXP<0>")
	)
	(segment
		(start 76.379832 12.133072)
		(end 76.379832 10.967974)
		(width 0.127)
		(layer "F.Cu")
		(net "P3E_CPU0_PE1_SS_C_TXP<0>")
	)
	(segment
		(start 109.783372 -5.625592)
		(end 110.133892 -5.774944)
		(width 0.127)
		(layer "F.Cu")
		(net "P3E_CPU0_PE1_SS_C_TXP<0>")
	)
	(segment
		(start 110.84941 -6.746748)
		(end 110.84941 -6.747002)
		(width 0.127)
		(layer "F.Cu")
		(net "P3E_CPU0_PE1_SS_C_TXP<0>")
	)
	(segment
		(start 110.84941 -6.747002)
		(end 110.850426 -6.749542)
		(width 0.127)
		(layer "F.Cu")
		(net "P3E_CPU0_PE1_SS_C_TXP<0>")
	)
	(segment
		(start 109.553502 -5.717794)
		(end 109.783372 -5.625592)
		(width 0.127)
		(layer "F.Cu")
		(net "P3E_CPU0_PE1_SS_C_TXP<0>")
	)
	(segment
		(start 75.687174 6.6294)
		(end 75.80249 5.97535)
		(width 0.127)
		(layer "F.Cu")
		(net "P3E_CPU0_PE1_SS_C_TXP<0>")
	)
	(segment
		(start 108.760006 -5.188966)
		(end 109.110526 -5.338572)
		(width 0.127)
		(layer "F.Cu")
		(net "P3E_CPU0_PE1_SS_C_TXP<0>")
	)
	(segment
		(start 110.707678 -6.405372)
		(end 110.84941 -6.746748)
		(width 0.127)
		(layer "F.Cu")
		(net "P3E_CPU0_PE1_SS_C_TXP<0>")
	)
	(segment
		(start 110.133892 -5.774944)
		(end 110.179612 -5.803138)
		(width 0.127)
		(layer "F.Cu")
		(net "P3E_CPU0_PE1_SS_C_TXP<0>")
	)
	(segment
		(start 110.850426 -6.749542)
		(end 110.853982 -6.757924)
		(width 0.127)
		(layer "F.Cu")
		(net "P3E_CPU0_PE1_SS_C_TXP<0>")
	)
	(segment
		(start 110.92942 -7.43077)
		(end 110.929166 -7.430516)
		(width 0.127)
		(layer "F.Cu")
		(net "P3E_CPU0_PE1_SS_C_TXP<0>")
	)
	(segment
		(start 94.16923 0.834644)
		(end 99.397566 -2.826004)
		(width 0.127)
		(layer "F.Cu")
		(net "P3E_CPU0_PE1_SS_C_TXP<0>")
	)
	(segment
		(start 76.930758 4.36372)
		(end 76.931266 4.363212)
		(width 0.127)
		(layer "F.Cu")
		(net "P3E_CPU0_PE1_SS_C_TXP<0>")
	)
	(segment
		(start 76.615544 8.940546)
		(end 75.91933 7.94639)
		(width 0.127)
		(layer "F.Cu")
		(net "P3E_CPU0_PE1_SS_C_TXP<0>")
	)
	(segment
		(start 110.852204 -6.76275)
		(end 110.92942 -7.199376)
		(width 0.127)
		(layer "F.Cu")
		(net "P3E_CPU0_PE1_SS_C_TXP<0>")
	)
	(segment
		(start 110.853982 -6.757924)
		(end 110.852204 -6.76275)
		(width 0.127)
		(layer "F.Cu")
		(net "P3E_CPU0_PE1_SS_C_TXP<0>")
	)
	(segment
		(start 75.91933 7.94639)
		(end 75.687174 6.6294)
		(width 0.127)
		(layer "F.Cu")
		(net "P3E_CPU0_PE1_SS_C_TXP<0>")
	)
	(segment
		(start 110.92942 -7.199376)
		(end 110.92942 -7.43077)
		(width 0.127)
		(layer "F.Cu")
		(net "P3E_CPU0_PE1_SS_C_TXP<0>")
	)
	(segment
		(start 76.934314 4.363212)
		(end 77.04455 4.252722)
		(width 0.127)
		(layer "F.Cu")
		(net "P3E_CPU0_PE1_SS_C_TXP<0>")
	)
	(segment
		(start 86.054438 2.265426)
		(end 94.16923 0.834644)
		(width 0.127)
		(layer "F.Cu")
		(net "P3E_CPU0_PE1_SS_C_TXP<0>")
	)
	(segment
		(start 108.08716 -4.901946)
		(end 108.179616 -5.13207)
		(width 0.127)
		(layer "F.Cu")
		(net "P3E_CPU0_PE1_SS_C_TXP<0>")
	)
	(segment
		(start 108.530136 -5.281422)
		(end 108.760006 -5.188966)
		(width 0.127)
		(layer "F.Cu")
		(net "P3E_CPU0_PE1_SS_C_TXP<0>")
	)
	(segment
		(start 76.728574 9.581642)
		(end 76.615544 8.940546)
		(width 0.127)
		(layer "F.Cu")
		(net "P3E_CPU0_PE1_SS_C_TXP<0>")
	)
	(segment
		(start 76.627482 10.370312)
		(end 76.627482 10.155936)
		(width 0.127)
		(layer "F.Cu")
		(net "P3E_CPU0_PE1_SS_C_TXP<0>")
	)
	(segment
		(start 110.179612 -5.803138)
		(end 110.707678 -6.405372)
		(width 0.127)
		(layer "F.Cu")
		(net "P3E_CPU0_PE1_SS_C_TXP<0>")
	)
	(segment
		(start 76.627482 10.155936)
		(end 76.728574 9.581642)
		(width 0.127)
		(layer "F.Cu")
		(net "P3E_CPU0_PE1_SS_C_TXP<0>")
	)
	(segment
		(start 109.202982 -5.568442)
		(end 109.553502 -5.717794)
		(width 0.127)
		(layer "F.Cu")
		(net "P3E_CPU0_PE1_SS_C_TXP<0>")
	)
	(segment
		(start 109.110526 -5.338572)
		(end 109.202982 -5.568442)
		(width 0.127)
		(layer "F.Cu")
		(net "P3E_CPU0_PE1_SS_C_TXP<0>")
	)
	(segment
		(start 76.931266 4.363212)
		(end 76.934314 4.363212)
		(width 0.127)
		(layer "F.Cu")
		(net "P3E_CPU0_PE1_SS_C_TXP<0>")
	)
	(arc
		(start 110.929166 -7.430516)
		(mid 110.867542 -7.761794)
		(end 110.690914 -8.048752)
		(width 0.127)
		(layer "F.Cu")
		(net "P3E_CPU0_PE1_SS_C_TXP<0>")
	)
	(arc
		(start 110.625128 -8.081772)
		(mid 110.52818 -8.088749)
		(end 110.454694 -8.02513)
		(width 0.127)
		(layer "F.Cu")
		(net "P3E_CPU0_PE1_SS_C_TXP<0>")
	)
	(arc
		(start 76.503784 10.669016)
		(mid 76.595356 10.531969)
		(end 76.627482 10.370312)
		(width 0.127)
		(layer "F.Cu")
		(net "P3E_CPU0_PE1_SS_C_TXP<0>")
	)
	(arc
		(start 76.379832 10.967974)
		(mid 76.412054 10.806162)
		(end 76.503784 10.669016)
		(width 0.127)
		(layer "F.Cu")
		(net "P3E_CPU0_PE1_SS_C_TXP<0>")
	)
	(segment
		(start 60.132214 10.0838)
		(end 60.132214 10.528554)
		(width 0.127)
		(layer "F.Cu")
		(net "P3E_CPU0_PE1_SS_C_TXN<7>")
	)
	(segment
		(start 83.284822 -6.942582)
		(end 83.201764 -6.471158)
		(width 0.127)
		(layer "F.Cu")
		(net "P3E_CPU0_PE1_SS_C_TXN<7>")
	)
	(segment
		(start 60.379864 11.12647)
		(end 60.379864 12.133072)
		(width 0.127)
		(layer "F.Cu")
		(net "P3E_CPU0_PE1_SS_C_TXN<7>")
	)
	(segment
		(start 65.36817 1.736344)
		(end 65.175384 2.011426)
		(width 0.127)
		(layer "F.Cu")
		(net "P3E_CPU0_PE1_SS_C_TXN<7>")
	)
	(segment
		(start 82.229198 -5.56387)
		(end 73.62698 -4.046982)
		(width 0.127)
		(layer "F.Cu")
		(net "P3E_CPU0_PE1_SS_C_TXN<7>")
	)
	(segment
		(start 82.761582 -8.354568)
		(end 82.761836 -8.354568)
		(width 0.127)
		(layer "F.Cu")
		(net "P3E_CPU0_PE1_SS_C_TXN<7>")
	)
	(segment
		(start 83.080352 -9.250426)
		(end 82.838798 -8.792464)
		(width 0.127)
		(layer "F.Cu")
		(net "P3E_CPU0_PE1_SS_C_TXN<7>")
	)
	(segment
		(start 82.891122 -6.02742)
		(end 82.229198 -5.56387)
		(width 0.127)
		(layer "F.Cu")
		(net "P3E_CPU0_PE1_SS_C_TXN<7>")
	)
	(segment
		(start 83.284822 -7.309104)
		(end 83.284822 -6.942582)
		(width 0.127)
		(layer "F.Cu")
		(net "P3E_CPU0_PE1_SS_C_TXN<7>")
	)
	(segment
		(start 82.761836 -8.354568)
		(end 82.875374 -8.297672)
		(width 0.127)
		(layer "F.Cu")
		(net "P3E_CPU0_PE1_SS_C_TXN<7>")
	)
	(segment
		(start 65.175384 2.011426)
		(end 60.337192 8.920734)
		(width 0.127)
		(layer "F.Cu")
		(net "P3E_CPU0_PE1_SS_C_TXN<7>")
	)
	(segment
		(start 82.838798 -8.792464)
		(end 82.70494 -8.525002)
		(width 0.127)
		(layer "F.Cu")
		(net "P3E_CPU0_PE1_SS_C_TXN<7>")
	)
	(segment
		(start 83.201764 -6.471158)
		(end 82.891122 -6.02742)
		(width 0.127)
		(layer "F.Cu")
		(net "P3E_CPU0_PE1_SS_C_TXN<7>")
	)
	(segment
		(start 73.62698 -4.046982)
		(end 65.368678 1.735582)
		(width 0.127)
		(layer "F.Cu")
		(net "P3E_CPU0_PE1_SS_C_TXN<7>")
	)
	(segment
		(start 65.368678 1.735582)
		(end 65.36817 1.736344)
		(width 0.127)
		(layer "F.Cu")
		(net "P3E_CPU0_PE1_SS_C_TXN<7>")
	)
	(segment
		(start 60.337192 8.920734)
		(end 60.132214 10.0838)
		(width 0.127)
		(layer "F.Cu")
		(net "P3E_CPU0_PE1_SS_C_TXN<7>")
	)
	(arc
		(start 82.875374 -8.297672)
		(mid 83.178432 -7.844113)
		(end 83.284822 -7.309104)
		(width 0.127)
		(layer "F.Cu")
		(net "P3E_CPU0_PE1_SS_C_TXN<7>")
	)
	(arc
		(start 60.132214 10.528554)
		(mid 60.164425 10.690492)
		(end 60.256166 10.827766)
		(width 0.127)
		(layer "F.Cu")
		(net "P3E_CPU0_PE1_SS_C_TXN<7>")
	)
	(arc
		(start 60.256166 10.827766)
		(mid 60.347738 10.964813)
		(end 60.379864 11.12647)
		(width 0.127)
		(layer "F.Cu")
		(net "P3E_CPU0_PE1_SS_C_TXN<7>")
	)
	(arc
		(start 82.70494 -8.525002)
		(mid 82.697963 -8.428054)
		(end 82.761582 -8.354568)
		(width 0.127)
		(layer "F.Cu")
		(net "P3E_CPU0_PE1_SS_C_TXN<7>")
	)
	(segment
		(start 62.850014 8.380476)
		(end 62.53226 10.182606)
		(width 0.127)
		(layer "F.Cu")
		(net "P3E_CPU0_PE1_SS_C_TXN<6>")
	)
	(segment
		(start 68.6562 0.907034)
		(end 68.6562 0.907288)
		(width 0.127)
		(layer "F.Cu")
		(net "P3E_CPU0_PE1_SS_C_TXN<6>")
	)
	(segment
		(start 87.079582 -9.250426)
		(end 86.954614 -9.025128)
		(width 0.127)
		(layer "F.Cu")
		(net "P3E_CPU0_PE1_SS_C_TXN<6>")
	)
	(segment
		(start 86.954614 -9.025128)
		(end 86.704678 -8.524748)
		(width 0.127)
		(layer "F.Cu")
		(net "P3E_CPU0_PE1_SS_C_TXN<6>")
	)
	(segment
		(start 87.228172 -7.445502)
		(end 87.228172 -7.046722)
		(width 0.127)
		(layer "F.Cu")
		(net "P3E_CPU0_PE1_SS_C_TXN<6>")
	)
	(segment
		(start 62.77991 11.113262)
		(end 62.77991 12.133072)
		(width 0.127)
		(layer "F.Cu")
		(net "P3E_CPU0_PE1_SS_C_TXN<6>")
	)
	(segment
		(start 67.53098 1.695196)
		(end 62.850014 8.380476)
		(width 0.127)
		(layer "F.Cu")
		(net "P3E_CPU0_PE1_SS_C_TXN<6>")
	)
	(segment
		(start 74.116692 -2.916174)
		(end 73.70445 -2.627376)
		(width 0.127)
		(layer "F.Cu")
		(net "P3E_CPU0_PE1_SS_C_TXN<6>")
	)
	(segment
		(start 68.6562 0.907288)
		(end 67.53098 1.695196)
		(width 0.127)
		(layer "F.Cu")
		(net "P3E_CPU0_PE1_SS_C_TXN<6>")
	)
	(segment
		(start 87.228172 -7.046722)
		(end 86.748366 -6.034786)
		(width 0.127)
		(layer "F.Cu")
		(net "P3E_CPU0_PE1_SS_C_TXN<6>")
	)
	(segment
		(start 86.748366 -6.034786)
		(end 85.046312 -4.843272)
		(width 0.127)
		(layer "F.Cu")
		(net "P3E_CPU0_PE1_SS_C_TXN<6>")
	)
	(segment
		(start 85.046312 -4.843272)
		(end 74.116692 -2.916174)
		(width 0.127)
		(layer "F.Cu")
		(net "P3E_CPU0_PE1_SS_C_TXN<6>")
	)
	(segment
		(start 86.761828 -8.354314)
		(end 86.875112 -8.297926)
		(width 0.127)
		(layer "F.Cu")
		(net "P3E_CPU0_PE1_SS_C_TXN<6>")
	)
	(segment
		(start 62.656212 10.814558)
		(end 62.656466 10.814812)
		(width 0.127)
		(layer "F.Cu")
		(net "P3E_CPU0_PE1_SS_C_TXN<6>")
	)
	(segment
		(start 73.70445 -2.627376)
		(end 68.6562 0.907034)
		(width 0.127)
		(layer "F.Cu")
		(net "P3E_CPU0_PE1_SS_C_TXN<6>")
	)
	(segment
		(start 86.761574 -8.354314)
		(end 86.761828 -8.354314)
		(width 0.127)
		(layer "F.Cu")
		(net "P3E_CPU0_PE1_SS_C_TXN<6>")
	)
	(segment
		(start 62.53226 10.182606)
		(end 62.53226 10.515854)
		(width 0.127)
		(layer "F.Cu")
		(net "P3E_CPU0_PE1_SS_C_TXN<6>")
	)
	(arc
		(start 62.656466 10.814812)
		(mid 62.747852 10.95177)
		(end 62.77991 11.113262)
		(width 0.127)
		(layer "F.Cu")
		(net "P3E_CPU0_PE1_SS_C_TXN<6>")
	)
	(arc
		(start 86.875112 -8.297926)
		(mid 87.136434 -7.906831)
		(end 87.228172 -7.445502)
		(width 0.127)
		(layer "F.Cu")
		(net "P3E_CPU0_PE1_SS_C_TXN<6>")
	)
	(arc
		(start 62.53226 10.515854)
		(mid 62.564516 10.677544)
		(end 62.656212 10.814558)
		(width 0.127)
		(layer "F.Cu")
		(net "P3E_CPU0_PE1_SS_C_TXN<6>")
	)
	(arc
		(start 86.704678 -8.524748)
		(mid 86.697919 -8.427803)
		(end 86.761574 -8.354314)
		(width 0.127)
		(layer "F.Cu")
		(net "P3E_CPU0_PE1_SS_C_TXN<6>")
	)
	(segment
		(start 90.892376 -8.90016)
		(end 90.70467 -8.525002)
		(width 0.127)
		(layer "F.Cu")
		(net "P3E_CPU0_PE1_SS_C_TXN<5>")
	)
	(segment
		(start 90.764868 -8.35279)
		(end 90.875104 -8.297672)
		(width 0.127)
		(layer "F.Cu")
		(net "P3E_CPU0_PE1_SS_C_TXN<5>")
	)
	(segment
		(start 90.761312 -8.354568)
		(end 90.761566 -8.354568)
		(width 0.127)
		(layer "F.Cu")
		(net "P3E_CPU0_PE1_SS_C_TXN<5>")
	)
	(segment
		(start 69.739764 1.613662)
		(end 65.333626 7.906004)
		(width 0.127)
		(layer "F.Cu")
		(net "P3E_CPU0_PE1_SS_C_TXN<5>")
	)
	(segment
		(start 65.056004 10.725658)
		(end 65.093088 10.762742)
		(width 0.127)
		(layer "F.Cu")
		(net "P3E_CPU0_PE1_SS_C_TXN<5>")
	)
	(segment
		(start 91.080082 -9.250426)
		(end 90.892376 -8.90016)
		(width 0.127)
		(layer "F.Cu")
		(net "P3E_CPU0_PE1_SS_C_TXN<5>")
	)
	(segment
		(start 91.167712 -6.787896)
		(end 90.883486 -6.369558)
		(width 0.127)
		(layer "F.Cu")
		(net "P3E_CPU0_PE1_SS_C_TXN<5>")
	)
	(segment
		(start 64.932306 10.182606)
		(end 64.932306 10.4267)
		(width 0.127)
		(layer "F.Cu")
		(net "P3E_CPU0_PE1_SS_C_TXN<5>")
	)
	(segment
		(start 90.761566 -8.354568)
		(end 90.764868 -8.35279)
		(width 0.127)
		(layer "F.Cu")
		(net "P3E_CPU0_PE1_SS_C_TXN<5>")
	)
	(segment
		(start 65.333626 7.906004)
		(end 64.932306 10.182606)
		(width 0.127)
		(layer "F.Cu")
		(net "P3E_CPU0_PE1_SS_C_TXN<5>")
	)
	(segment
		(start 65.179956 10.972038)
		(end 65.179956 12.133072)
		(width 0.127)
		(layer "F.Cu")
		(net "P3E_CPU0_PE1_SS_C_TXN<5>")
	)
	(segment
		(start 87.613236 -4.080002)
		(end 74.591672 -1.783842)
		(width 0.127)
		(layer "F.Cu")
		(net "P3E_CPU0_PE1_SS_C_TXN<5>")
	)
	(segment
		(start 90.883486 -6.369558)
		(end 87.613236 -4.080002)
		(width 0.127)
		(layer "F.Cu")
		(net "P3E_CPU0_PE1_SS_C_TXN<5>")
	)
	(segment
		(start 70.23227 1.26873)
		(end 69.739764 1.613662)
		(width 0.127)
		(layer "F.Cu")
		(net "P3E_CPU0_PE1_SS_C_TXN<5>")
	)
	(segment
		(start 74.591672 -1.783842)
		(end 70.23227 1.26873)
		(width 0.127)
		(layer "F.Cu")
		(net "P3E_CPU0_PE1_SS_C_TXN<5>")
	)
	(arc
		(start 65.093088 10.762742)
		(mid 65.157358 10.858739)
		(end 65.179956 10.972038)
		(width 0.127)
		(layer "F.Cu")
		(net "P3E_CPU0_PE1_SS_C_TXN<5>")
	)
	(arc
		(start 90.875104 -8.297672)
		(mid 91.172217 -8.004802)
		(end 91.239594 -7.593076)
		(width 0.127)
		(layer "F.Cu")
		(net "P3E_CPU0_PE1_SS_C_TXN<5>")
	)
	(arc
		(start 91.247722 -7.177786)
		(mid 91.246658 -6.97485)
		(end 91.167712 -6.787896)
		(width 0.127)
		(layer "F.Cu")
		(net "P3E_CPU0_PE1_SS_C_TXN<5>")
	)
	(arc
		(start 90.70467 -8.525002)
		(mid 90.697693 -8.428054)
		(end 90.761312 -8.354568)
		(width 0.127)
		(layer "F.Cu")
		(net "P3E_CPU0_PE1_SS_C_TXN<5>")
	)
	(arc
		(start 64.932306 10.4267)
		(mid 64.964449 10.588472)
		(end 65.056004 10.725658)
		(width 0.127)
		(layer "F.Cu")
		(net "P3E_CPU0_PE1_SS_C_TXN<5>")
	)
	(arc
		(start 91.239594 -7.593076)
		(mid 91.225678 -7.385078)
		(end 91.247722 -7.177786)
		(width 0.127)
		(layer "F.Cu")
		(net "P3E_CPU0_PE1_SS_C_TXN<5>")
	)
	(segment
		(start 67.332352 10.413746)
		(end 67.332352 10.182606)
		(width 0.127)
		(layer "F.Cu")
		(net "P3E_CPU0_PE1_SS_C_TXN<4>")
	)
	(segment
		(start 94.761558 -8.354314)
		(end 94.761304 -8.354314)
		(width 0.127)
		(layer "F.Cu")
		(net "P3E_CPU0_PE1_SS_C_TXN<4>")
	)
	(segment
		(start 90.722958 -3.287268)
		(end 94.5896 -5.994654)
		(width 0.127)
		(layer "F.Cu")
		(net "P3E_CPU0_PE1_SS_C_TXN<4>")
	)
	(segment
		(start 94.5896 -5.994654)
		(end 94.919292 -6.274054)
		(width 0.127)
		(layer "F.Cu")
		(net "P3E_CPU0_PE1_SS_C_TXN<4>")
	)
	(segment
		(start 94.875096 -8.297672)
		(end 94.874842 -8.297926)
		(width 0.127)
		(layer "F.Cu")
		(net "P3E_CPU0_PE1_SS_C_TXN<4>")
	)
	(segment
		(start 94.8944 -8.904986)
		(end 95.079312 -9.250426)
		(width 0.127)
		(layer "F.Cu")
		(net "P3E_CPU0_PE1_SS_C_TXN<4>")
	)
	(segment
		(start 95.266256 -7.0231)
		(end 95.266256 -7.353046)
		(width 0.127)
		(layer "F.Cu")
		(net "P3E_CPU0_PE1_SS_C_TXN<4>")
	)
	(segment
		(start 67.332352 10.182606)
		(end 67.834002 7.338568)
		(width 0.127)
		(layer "F.Cu")
		(net "P3E_CPU0_PE1_SS_C_TXN<4>")
	)
	(segment
		(start 75.059286 -0.525272)
		(end 87.454994 -2.710942)
		(width 0.127)
		(layer "F.Cu")
		(net "P3E_CPU0_PE1_SS_C_TXN<4>")
	)
	(segment
		(start 87.454994 -2.710942)
		(end 90.722958 -3.287268)
		(width 0.127)
		(layer "F.Cu")
		(net "P3E_CPU0_PE1_SS_C_TXN<4>")
	)
	(segment
		(start 67.834002 7.338568)
		(end 71.686928 1.835912)
		(width 0.127)
		(layer "F.Cu")
		(net "P3E_CPU0_PE1_SS_C_TXN<4>")
	)
	(segment
		(start 94.874842 -8.297926)
		(end 94.761558 -8.354314)
		(width 0.127)
		(layer "F.Cu")
		(net "P3E_CPU0_PE1_SS_C_TXN<4>")
	)
	(segment
		(start 71.686928 1.835912)
		(end 75.059286 -0.525272)
		(width 0.127)
		(layer "F.Cu")
		(net "P3E_CPU0_PE1_SS_C_TXN<4>")
	)
	(segment
		(start 94.704408 -8.524748)
		(end 94.8944 -8.904986)
		(width 0.127)
		(layer "F.Cu")
		(net "P3E_CPU0_PE1_SS_C_TXN<4>")
	)
	(segment
		(start 67.580002 12.133072)
		(end 67.580002 11.011408)
		(width 0.127)
		(layer "F.Cu")
		(net "P3E_CPU0_PE1_SS_C_TXN<4>")
	)
	(arc
		(start 94.916752 -8.254238)
		(mid 94.896169 -8.27619)
		(end 94.875096 -8.297672)
		(width 0.127)
		(layer "F.Cu")
		(net "P3E_CPU0_PE1_SS_C_TXN<4>")
	)
	(arc
		(start 67.580002 11.011408)
		(mid 67.547849 10.849762)
		(end 67.456304 10.712704)
		(width 0.127)
		(layer "F.Cu")
		(net "P3E_CPU0_PE1_SS_C_TXN<4>")
	)
	(arc
		(start 67.456304 10.712704)
		(mid 67.364547 10.575569)
		(end 67.332352 10.413746)
		(width 0.127)
		(layer "F.Cu")
		(net "P3E_CPU0_PE1_SS_C_TXN<4>")
	)
	(arc
		(start 95.266256 -7.353046)
		(mid 95.175803 -7.836327)
		(end 94.916752 -8.254238)
		(width 0.127)
		(layer "F.Cu")
		(net "P3E_CPU0_PE1_SS_C_TXN<4>")
	)
	(arc
		(start 94.761304 -8.354314)
		(mid 94.697541 -8.427767)
		(end 94.704408 -8.524748)
		(width 0.127)
		(layer "F.Cu")
		(net "P3E_CPU0_PE1_SS_C_TXN<4>")
	)
	(arc
		(start 94.919292 -6.274054)
		(mid 95.175295 -6.610343)
		(end 95.266256 -7.0231)
		(width 0.127)
		(layer "F.Cu")
		(net "P3E_CPU0_PE1_SS_C_TXN<4>")
	)
	(segment
		(start 98.762058 -8.354314)
		(end 98.761804 -8.354314)
		(width 0.127)
		(layer "F.Cu")
		(net "P3E_CPU0_PE1_SS_C_TXN<3>")
	)
	(segment
		(start 99.26955 -6.914642)
		(end 99.26955 -7.346188)
		(width 0.127)
		(layer "F.Cu")
		(net "P3E_CPU0_PE1_SS_C_TXN<3>")
	)
	(segment
		(start 69.732398 10.476992)
		(end 69.732398 10.0838)
		(width 0.127)
		(layer "F.Cu")
		(net "P3E_CPU0_PE1_SS_C_TXN<3>")
	)
	(segment
		(start 98.9711 -6.4643)
		(end 99.10699 -6.669278)
		(width 0.127)
		(layer "F.Cu")
		(net "P3E_CPU0_PE1_SS_C_TXN<3>")
	)
	(segment
		(start 75.445112 0.68072)
		(end 92.307156 -2.289048)
		(width 0.127)
		(layer "F.Cu")
		(net "P3E_CPU0_PE1_SS_C_TXN<3>")
	)
	(segment
		(start 73.28662 2.19202)
		(end 75.445112 0.68072)
		(width 0.127)
		(layer "F.Cu")
		(net "P3E_CPU0_PE1_SS_C_TXN<3>")
	)
	(segment
		(start 98.875342 -8.297926)
		(end 98.762058 -8.354314)
		(width 0.127)
		(layer "F.Cu")
		(net "P3E_CPU0_PE1_SS_C_TXN<3>")
	)
	(segment
		(start 97.532952 -5.948172)
		(end 98.576384 -6.128258)
		(width 0.127)
		(layer "F.Cu")
		(net "P3E_CPU0_PE1_SS_C_TXN<3>")
	)
	(segment
		(start 70.43039 6.271514)
		(end 73.28662 2.19202)
		(width 0.127)
		(layer "F.Cu")
		(net "P3E_CPU0_PE1_SS_C_TXN<3>")
	)
	(segment
		(start 92.307156 -2.289048)
		(end 97.532952 -5.948172)
		(width 0.127)
		(layer "F.Cu")
		(net "P3E_CPU0_PE1_SS_C_TXN<3>")
	)
	(segment
		(start 98.704908 -8.524748)
		(end 98.954844 -9.025128)
		(width 0.127)
		(layer "F.Cu")
		(net "P3E_CPU0_PE1_SS_C_TXN<3>")
	)
	(segment
		(start 99.10699 -6.669278)
		(end 99.26955 -6.914642)
		(width 0.127)
		(layer "F.Cu")
		(net "P3E_CPU0_PE1_SS_C_TXN<3>")
	)
	(segment
		(start 69.732398 10.0838)
		(end 70.382384 6.397498)
		(width 0.127)
		(layer "F.Cu")
		(net "P3E_CPU0_PE1_SS_C_TXN<3>")
	)
	(segment
		(start 70.382384 6.397498)
		(end 70.380352 6.392418)
		(width 0.127)
		(layer "F.Cu")
		(net "P3E_CPU0_PE1_SS_C_TXN<3>")
	)
	(segment
		(start 69.979794 12.133072)
		(end 69.979794 11.0744)
		(width 0.127)
		(layer "F.Cu")
		(net "P3E_CPU0_PE1_SS_C_TXN<3>")
	)
	(segment
		(start 98.954844 -9.025128)
		(end 99.079812 -9.250426)
		(width 0.127)
		(layer "F.Cu")
		(net "P3E_CPU0_PE1_SS_C_TXN<3>")
	)
	(segment
		(start 98.576384 -6.128258)
		(end 98.9711 -6.4643)
		(width 0.127)
		(layer "F.Cu")
		(net "P3E_CPU0_PE1_SS_C_TXN<3>")
	)
	(segment
		(start 70.380352 6.392418)
		(end 70.43039 6.271514)
		(width 0.127)
		(layer "F.Cu")
		(net "P3E_CPU0_PE1_SS_C_TXN<3>")
	)
	(arc
		(start 69.856096 10.775696)
		(mid 69.764524 10.638649)
		(end 69.732398 10.476992)
		(width 0.127)
		(layer "F.Cu")
		(net "P3E_CPU0_PE1_SS_C_TXN<3>")
	)
	(arc
		(start 69.979794 11.0744)
		(mid 69.947641 10.912754)
		(end 69.856096 10.775696)
		(width 0.127)
		(layer "F.Cu")
		(net "P3E_CPU0_PE1_SS_C_TXN<3>")
	)
	(arc
		(start 98.761804 -8.354314)
		(mid 98.698041 -8.427767)
		(end 98.704908 -8.524748)
		(width 0.127)
		(layer "F.Cu")
		(net "P3E_CPU0_PE1_SS_C_TXN<3>")
	)
	(arc
		(start 99.26955 -7.346188)
		(mid 99.167096 -7.861259)
		(end 98.875342 -8.297926)
		(width 0.127)
		(layer "F.Cu")
		(net "P3E_CPU0_PE1_SS_C_TXN<3>")
	)
	(segment
		(start 74.69505 2.87147)
		(end 74.78649 2.78003)
		(width 0.127)
		(layer "F.Cu")
		(net "P3E_CPU0_PE1_SS_C_TXN<2>")
	)
	(segment
		(start 72.132444 8.45439)
		(end 72.585072 5.88772)
		(width 0.127)
		(layer "F.Cu")
		(net "P3E_CPU0_PE1_SS_C_TXN<2>")
	)
	(segment
		(start 93.423232 -1.237996)
		(end 98.60915 -4.868926)
		(width 0.127)
		(layer "F.Cu")
		(net "P3E_CPU0_PE1_SS_C_TXN<2>")
	)
	(segment
		(start 72.132444 10.438638)
		(end 72.132444 8.45439)
		(width 0.127)
		(layer "F.Cu")
		(net "P3E_CPU0_PE1_SS_C_TXN<2>")
	)
	(segment
		(start 72.585072 5.88772)
		(end 74.694542 2.875026)
		(width 0.127)
		(layer "F.Cu")
		(net "P3E_CPU0_PE1_SS_C_TXN<2>")
	)
	(segment
		(start 103.07447 -6.4643)
		(end 103.18877 -7.113778)
		(width 0.127)
		(layer "F.Cu")
		(net "P3E_CPU0_PE1_SS_C_TXN<2>")
	)
	(segment
		(start 102.875334 -8.297672)
		(end 102.761796 -8.354568)
		(width 0.127)
		(layer "F.Cu")
		(net "P3E_CPU0_PE1_SS_C_TXN<2>")
	)
	(segment
		(start 102.6922 -5.9182)
		(end 103.07447 -6.4643)
		(width 0.127)
		(layer "F.Cu")
		(net "P3E_CPU0_PE1_SS_C_TXN<2>")
	)
	(segment
		(start 74.69505 2.874518)
		(end 74.69505 2.87147)
		(width 0.127)
		(layer "F.Cu")
		(net "P3E_CPU0_PE1_SS_C_TXN<2>")
	)
	(segment
		(start 102.875334 -8.297418)
		(end 102.875588 -8.297418)
		(width 0.127)
		(layer "F.Cu")
		(net "P3E_CPU0_PE1_SS_C_TXN<2>")
	)
	(segment
		(start 98.60915 -4.868926)
		(end 102.065074 -5.479034)
		(width 0.127)
		(layer "F.Cu")
		(net "P3E_CPU0_PE1_SS_C_TXN<2>")
	)
	(segment
		(start 102.875588 -8.297418)
		(end 102.875334 -8.297672)
		(width 0.127)
		(layer "F.Cu")
		(net "P3E_CPU0_PE1_SS_C_TXN<2>")
	)
	(segment
		(start 102.615492 -5.864352)
		(end 102.6922 -5.9182)
		(width 0.127)
		(layer "F.Cu")
		(net "P3E_CPU0_PE1_SS_C_TXN<2>")
	)
	(segment
		(start 102.761796 -8.354568)
		(end 102.761542 -8.354568)
		(width 0.127)
		(layer "F.Cu")
		(net "P3E_CPU0_PE1_SS_C_TXN<2>")
	)
	(segment
		(start 74.694542 2.875026)
		(end 74.69505 2.874518)
		(width 0.127)
		(layer "F.Cu")
		(net "P3E_CPU0_PE1_SS_C_TXN<2>")
	)
	(segment
		(start 74.78649 2.78003)
		(end 76.183236 1.80213)
		(width 0.127)
		(layer "F.Cu")
		(net "P3E_CPU0_PE1_SS_C_TXN<2>")
	)
	(segment
		(start 72.37984 12.133072)
		(end 72.37984 11.036046)
		(width 0.127)
		(layer "F.Cu")
		(net "P3E_CPU0_PE1_SS_C_TXN<2>")
	)
	(segment
		(start 102.7049 -8.525002)
		(end 102.892606 -8.90016)
		(width 0.127)
		(layer "F.Cu")
		(net "P3E_CPU0_PE1_SS_C_TXN<2>")
	)
	(segment
		(start 103.18877 -7.113778)
		(end 103.18877 -7.53999)
		(width 0.127)
		(layer "F.Cu")
		(net "P3E_CPU0_PE1_SS_C_TXN<2>")
	)
	(segment
		(start 76.183236 1.80213)
		(end 93.423232 -1.237996)
		(width 0.127)
		(layer "F.Cu")
		(net "P3E_CPU0_PE1_SS_C_TXN<2>")
	)
	(segment
		(start 102.892606 -8.90016)
		(end 103.080312 -9.250426)
		(width 0.127)
		(layer "F.Cu")
		(net "P3E_CPU0_PE1_SS_C_TXN<2>")
	)
	(segment
		(start 102.065074 -5.479034)
		(end 102.615492 -5.864352)
		(width 0.127)
		(layer "F.Cu")
		(net "P3E_CPU0_PE1_SS_C_TXN<2>")
	)
	(arc
		(start 72.37984 11.036046)
		(mid 72.347687 10.8744)
		(end 72.256142 10.737342)
		(width 0.127)
		(layer "F.Cu")
		(net "P3E_CPU0_PE1_SS_C_TXN<2>")
	)
	(arc
		(start 72.256142 10.737342)
		(mid 72.16457 10.600295)
		(end 72.132444 10.438638)
		(width 0.127)
		(layer "F.Cu")
		(net "P3E_CPU0_PE1_SS_C_TXN<2>")
	)
	(arc
		(start 102.761542 -8.354568)
		(mid 102.697923 -8.428054)
		(end 102.7049 -8.525002)
		(width 0.127)
		(layer "F.Cu")
		(net "P3E_CPU0_PE1_SS_C_TXN<2>")
	)
	(arc
		(start 102.918768 -8.251444)
		(mid 102.897389 -8.274751)
		(end 102.875334 -8.297418)
		(width 0.127)
		(layer "F.Cu")
		(net "P3E_CPU0_PE1_SS_C_TXN<2>")
	)
	(arc
		(start 103.18877 -7.53999)
		(mid 103.119093 -7.920511)
		(end 102.918768 -8.251444)
		(width 0.127)
		(layer "F.Cu")
		(net "P3E_CPU0_PE1_SS_C_TXN<2>")
	)
	(segment
		(start 76.02347 3.435096)
		(end 76.777088 2.907284)
		(width 0.127)
		(layer "F.Cu")
		(net "P3E_CPU0_PE1_SS_C_TXN<1>")
	)
	(segment
		(start 74.532236 10.399776)
		(end 74.532236 10.182606)
		(width 0.127)
		(layer "F.Cu")
		(net "P3E_CPU0_PE1_SS_C_TXN<1>")
	)
	(segment
		(start 106.761788 -8.354314)
		(end 106.761534 -8.354314)
		(width 0.127)
		(layer "F.Cu")
		(net "P3E_CPU0_PE1_SS_C_TXN<1>")
	)
	(segment
		(start 107.26928 -6.8453)
		(end 107.26928 -7.346188)
		(width 0.127)
		(layer "F.Cu")
		(net "P3E_CPU0_PE1_SS_C_TXN<1>")
	)
	(segment
		(start 74.532236 10.182606)
		(end 74.75093 8.941816)
		(width 0.127)
		(layer "F.Cu")
		(net "P3E_CPU0_PE1_SS_C_TXN<1>")
	)
	(segment
		(start 74.779886 12.133072)
		(end 74.779886 10.997692)
		(width 0.127)
		(layer "F.Cu")
		(net "P3E_CPU0_PE1_SS_C_TXN<1>")
	)
	(segment
		(start 106.954574 -9.025128)
		(end 107.079542 -9.250426)
		(width 0.127)
		(layer "F.Cu")
		(net "P3E_CPU0_PE1_SS_C_TXN<1>")
	)
	(segment
		(start 107.17403 -6.305042)
		(end 107.26928 -6.8453)
		(width 0.127)
		(layer "F.Cu")
		(net "P3E_CPU0_PE1_SS_C_TXN<1>")
	)
	(segment
		(start 74.264266 6.185408)
		(end 74.3204 5.8674)
		(width 0.127)
		(layer "F.Cu")
		(net "P3E_CPU0_PE1_SS_C_TXN<1>")
	)
	(segment
		(start 93.939614 -0.118618)
		(end 99.049078 -3.696208)
		(width 0.127)
		(layer "F.Cu")
		(net "P3E_CPU0_PE1_SS_C_TXN<1>")
	)
	(segment
		(start 106.875072 -8.297926)
		(end 106.761788 -8.354314)
		(width 0.127)
		(layer "F.Cu")
		(net "P3E_CPU0_PE1_SS_C_TXN<1>")
	)
	(segment
		(start 74.3204 5.8674)
		(end 76.02347 3.435096)
		(width 0.127)
		(layer "F.Cu")
		(net "P3E_CPU0_PE1_SS_C_TXN<1>")
	)
	(segment
		(start 106.704638 -8.524748)
		(end 106.954574 -9.025128)
		(width 0.127)
		(layer "F.Cu")
		(net "P3E_CPU0_PE1_SS_C_TXN<1>")
	)
	(segment
		(start 74.75093 8.941816)
		(end 74.264266 6.185408)
		(width 0.127)
		(layer "F.Cu")
		(net "P3E_CPU0_PE1_SS_C_TXN<1>")
	)
	(segment
		(start 76.777088 2.907284)
		(end 93.939614 -0.118618)
		(width 0.127)
		(layer "F.Cu")
		(net "P3E_CPU0_PE1_SS_C_TXN<1>")
	)
	(segment
		(start 105.567226 -4.845304)
		(end 106.71429 -5.648452)
		(width 0.127)
		(layer "F.Cu")
		(net "P3E_CPU0_PE1_SS_C_TXN<1>")
	)
	(segment
		(start 106.71429 -5.648452)
		(end 107.17403 -6.305042)
		(width 0.127)
		(layer "F.Cu")
		(net "P3E_CPU0_PE1_SS_C_TXN<1>")
	)
	(segment
		(start 99.049078 -3.696208)
		(end 105.567226 -4.845304)
		(width 0.127)
		(layer "F.Cu")
		(net "P3E_CPU0_PE1_SS_C_TXN<1>")
	)
	(arc
		(start 106.761534 -8.354314)
		(mid 106.697771 -8.427767)
		(end 106.704638 -8.524748)
		(width 0.127)
		(layer "F.Cu")
		(net "P3E_CPU0_PE1_SS_C_TXN<1>")
	)
	(arc
		(start 74.656188 10.698988)
		(mid 74.564461 10.561708)
		(end 74.532236 10.399776)
		(width 0.127)
		(layer "F.Cu")
		(net "P3E_CPU0_PE1_SS_C_TXN<1>")
	)
	(arc
		(start 74.779886 10.997692)
		(mid 74.747733 10.836046)
		(end 74.656188 10.698988)
		(width 0.127)
		(layer "F.Cu")
		(net "P3E_CPU0_PE1_SS_C_TXN<1>")
	)
	(arc
		(start 107.26928 -7.346188)
		(mid 107.166826 -7.861259)
		(end 106.875072 -8.297926)
		(width 0.127)
		(layer "F.Cu")
		(net "P3E_CPU0_PE1_SS_C_TXN<1>")
	)
	(segment
		(start 110.378748 -5.567426)
		(end 110.93704 -6.204204)
		(width 0.127)
		(layer "F.Cu")
		(net "P3E_CPU0_PE1_SS_C_TXN<0>")
	)
	(segment
		(start 76.932282 10.182606)
		(end 77.0382 9.581642)
		(width 0.127)
		(layer "F.Cu")
		(net "P3E_CPU0_PE1_SS_C_TXN<0>")
	)
	(segment
		(start 110.933992 -8.983726)
		(end 111.080042 -9.250426)
		(width 0.127)
		(layer "F.Cu")
		(net "P3E_CPU0_PE1_SS_C_TXN<0>")
	)
	(segment
		(start 76.932282 10.387076)
		(end 76.932282 10.182606)
		(width 0.127)
		(layer "F.Cu")
		(net "P3E_CPU0_PE1_SS_C_TXN<0>")
	)
	(segment
		(start 111.135668 -6.641084)
		(end 111.140748 -6.643116)
		(width 0.127)
		(layer "F.Cu")
		(net "P3E_CPU0_PE1_SS_C_TXN<0>")
	)
	(segment
		(start 110.970314 -6.24205)
		(end 111.13516 -6.639814)
		(width 0.127)
		(layer "F.Cu")
		(net "P3E_CPU0_PE1_SS_C_TXN<0>")
	)
	(segment
		(start 77.14996 4.578858)
		(end 77.2414 4.487418)
		(width 0.127)
		(layer "F.Cu")
		(net "P3E_CPU0_PE1_SS_C_TXN<0>")
	)
	(segment
		(start 77.179932 12.133072)
		(end 77.179932 10.932414)
		(width 0.127)
		(layer "F.Cu")
		(net "P3E_CPU0_PE1_SS_C_TXN<0>")
	)
	(segment
		(start 110.70463 -8.525002)
		(end 110.933992 -8.983726)
		(width 0.127)
		(layer "F.Cu")
		(net "P3E_CPU0_PE1_SS_C_TXN<0>")
	)
	(segment
		(start 77.925676 4.00812)
		(end 94.28861 1.123188)
		(width 0.127)
		(layer "F.Cu")
		(net "P3E_CPU0_PE1_SS_C_TXN<0>")
	)
	(segment
		(start 105.990644 -3.676396)
		(end 110.274354 -5.503418)
		(width 0.127)
		(layer "F.Cu")
		(net "P3E_CPU0_PE1_SS_C_TXN<0>")
	)
	(segment
		(start 77.14996 4.582414)
		(end 77.14996 4.578858)
		(width 0.127)
		(layer "F.Cu")
		(net "P3E_CPU0_PE1_SS_C_TXN<0>")
	)
	(segment
		(start 76.904088 8.821166)
		(end 76.207874 7.82701)
		(width 0.127)
		(layer "F.Cu")
		(net "P3E_CPU0_PE1_SS_C_TXN<0>")
	)
	(segment
		(start 110.274354 -5.503418)
		(end 110.378748 -5.567426)
		(width 0.127)
		(layer "F.Cu")
		(net "P3E_CPU0_PE1_SS_C_TXN<0>")
	)
	(segment
		(start 111.23422 -7.172452)
		(end 111.23422 -7.430516)
		(width 0.127)
		(layer "F.Cu")
		(net "P3E_CPU0_PE1_SS_C_TXN<0>")
	)
	(segment
		(start 111.13516 -6.639814)
		(end 111.135668 -6.641084)
		(width 0.127)
		(layer "F.Cu")
		(net "P3E_CPU0_PE1_SS_C_TXN<0>")
	)
	(segment
		(start 75.9968 6.6294)
		(end 76.091034 6.09473)
		(width 0.127)
		(layer "F.Cu")
		(net "P3E_CPU0_PE1_SS_C_TXN<0>")
	)
	(segment
		(start 76.091034 6.09473)
		(end 77.149706 4.582668)
		(width 0.127)
		(layer "F.Cu")
		(net "P3E_CPU0_PE1_SS_C_TXN<0>")
	)
	(segment
		(start 77.093064 10.723118)
		(end 77.05598 10.686034)
		(width 0.127)
		(layer "F.Cu")
		(net "P3E_CPU0_PE1_SS_C_TXN<0>")
	)
	(segment
		(start 110.761526 -8.354568)
		(end 110.761272 -8.354568)
		(width 0.127)
		(layer "F.Cu")
		(net "P3E_CPU0_PE1_SS_C_TXN<0>")
	)
	(segment
		(start 111.140748 -6.643116)
		(end 111.23422 -7.172452)
		(width 0.127)
		(layer "F.Cu")
		(net "P3E_CPU0_PE1_SS_C_TXN<0>")
	)
	(segment
		(start 110.93704 -6.204204)
		(end 110.970314 -6.24205)
		(width 0.127)
		(layer "F.Cu")
		(net "P3E_CPU0_PE1_SS_C_TXN<0>")
	)
	(segment
		(start 94.28861 1.123188)
		(end 99.516946 -2.53746)
		(width 0.127)
		(layer "F.Cu")
		(net "P3E_CPU0_PE1_SS_C_TXN<0>")
	)
	(segment
		(start 99.516946 -2.53746)
		(end 105.990644 -3.676396)
		(width 0.127)
		(layer "F.Cu")
		(net "P3E_CPU0_PE1_SS_C_TXN<0>")
	)
	(segment
		(start 77.149706 4.582668)
		(end 77.14996 4.582414)
		(width 0.127)
		(layer "F.Cu")
		(net "P3E_CPU0_PE1_SS_C_TXN<0>")
	)
	(segment
		(start 76.207874 7.82701)
		(end 75.9968 6.6294)
		(width 0.127)
		(layer "F.Cu")
		(net "P3E_CPU0_PE1_SS_C_TXN<0>")
	)
	(segment
		(start 77.2414 4.487418)
		(end 77.925676 4.00812)
		(width 0.127)
		(layer "F.Cu")
		(net "P3E_CPU0_PE1_SS_C_TXN<0>")
	)
	(segment
		(start 110.875064 -8.297672)
		(end 110.761526 -8.354568)
		(width 0.127)
		(layer "F.Cu")
		(net "P3E_CPU0_PE1_SS_C_TXN<0>")
	)
	(segment
		(start 77.0382 9.581642)
		(end 76.904088 8.821166)
		(width 0.127)
		(layer "F.Cu")
		(net "P3E_CPU0_PE1_SS_C_TXN<0>")
	)
	(arc
		(start 77.179932 10.932414)
		(mid 77.157358 10.819105)
		(end 77.093064 10.723118)
		(width 0.127)
		(layer "F.Cu")
		(net "P3E_CPU0_PE1_SS_C_TXN<0>")
	)
	(arc
		(start 111.23422 -7.430516)
		(mid 111.140873 -7.899805)
		(end 110.875064 -8.297672)
		(width 0.127)
		(layer "F.Cu")
		(net "P3E_CPU0_PE1_SS_C_TXN<0>")
	)
	(arc
		(start 110.761272 -8.354568)
		(mid 110.697653 -8.428054)
		(end 110.70463 -8.525002)
		(width 0.127)
		(layer "F.Cu")
		(net "P3E_CPU0_PE1_SS_C_TXN<0>")
	)
	(arc
		(start 77.05598 10.686034)
		(mid 76.964438 10.548842)
		(end 76.932282 10.387076)
		(width 0.127)
		(layer "F.Cu")
		(net "P3E_CPU0_PE1_SS_C_TXN<0>")
	)
	(segment
		(start 64.364362 3.330702)
		(end 64.365886 3.329686)
		(width 0.127)
		(layer "B.Cu")
		(net "P3E_CPU0_PE1_SS_C_RXP<7>")
	)
	(segment
		(start 74.452734 -3.635502)
		(end 74.86396 -3.919982)
		(width 0.127)
		(layer "B.Cu")
		(net "P3E_CPU0_PE1_SS_C_RXP<7>")
	)
	(segment
		(start 60.884308 8.193532)
		(end 64.21628 3.434588)
		(width 0.127)
		(layer "B.Cu")
		(net "P3E_CPU0_PE1_SS_C_RXP<7>")
	)
	(segment
		(start 64.365886 3.329686)
		(end 64.366648 3.328924)
		(width 0.127)
		(layer "B.Cu")
		(net "P3E_CPU0_PE1_SS_C_RXP<7>")
	)
	(segment
		(start 60.627514 9.65073)
		(end 60.884308 8.193532)
		(width 0.127)
		(layer "B.Cu")
		(net "P3E_CPU0_PE1_SS_C_RXP<7>")
	)
	(segment
		(start 81.268316 -8.188706)
		(end 81.73339 -8.65378)
		(width 0.127)
		(layer "B.Cu")
		(net "P3E_CPU0_PE1_SS_C_RXP<7>")
	)
	(segment
		(start 78.859888 -4.62407)
		(end 79.287116 -4.699508)
		(width 0.127)
		(layer "B.Cu")
		(net "P3E_CPU0_PE1_SS_C_RXP<7>")
	)
	(segment
		(start 79.292196 -4.697476)
		(end 79.4131 -4.747514)
		(width 0.127)
		(layer "B.Cu")
		(net "P3E_CPU0_PE1_SS_C_RXP<7>")
	)
	(segment
		(start 84.202778 -13.528802)
		(end 84.079842 -13.750036)
		(width 0.127)
		(layer "B.Cu")
		(net "P3E_CPU0_PE1_SS_C_RXP<7>")
	)
	(segment
		(start 60.627514 10.419334)
		(end 60.627514 9.65073)
		(width 0.127)
		(layer "B.Cu")
		(net "P3E_CPU0_PE1_SS_C_RXP<7>")
	)
	(segment
		(start 79.287116 -4.699508)
		(end 79.292196 -4.697476)
		(width 0.127)
		(layer "B.Cu")
		(net "P3E_CPU0_PE1_SS_C_RXP<7>")
	)
	(segment
		(start 81.914492 -9.090406)
		(end 81.914492 -9.616948)
		(width 0.127)
		(layer "B.Cu")
		(net "P3E_CPU0_PE1_SS_C_RXP<7>")
	)
	(segment
		(start 80.91424 -6.901434)
		(end 80.91424 -7.333742)
		(width 0.127)
		(layer "B.Cu")
		(net "P3E_CPU0_PE1_SS_C_RXP<7>")
	)
	(segment
		(start 71.040498 -1.27889)
		(end 74.452734 -3.635502)
		(width 0.127)
		(layer "B.Cu")
		(net "P3E_CPU0_PE1_SS_C_RXP<7>")
	)
	(segment
		(start 82.103214 -10.073894)
		(end 82.500216 -10.470896)
		(width 0.127)
		(layer "B.Cu")
		(net "P3E_CPU0_PE1_SS_C_RXP<7>")
	)
	(segment
		(start 83.929728 -11.613642)
		(end 83.929728 -12.07643)
		(width 0.127)
		(layer "B.Cu")
		(net "P3E_CPU0_PE1_SS_C_RXP<7>")
	)
	(segment
		(start 78.859888 -4.624324)
		(end 78.859888 -4.62407)
		(width 0.127)
		(layer "B.Cu")
		(net "P3E_CPU0_PE1_SS_C_RXP<7>")
	)
	(segment
		(start 60.379864 12.514072)
		(end 60.379864 11.016742)
		(width 0.127)
		(layer "B.Cu")
		(net "P3E_CPU0_PE1_SS_C_RXP<7>")
	)
	(segment
		(start 74.86396 -3.919982)
		(end 78.859888 -4.624324)
		(width 0.127)
		(layer "B.Cu")
		(net "P3E_CPU0_PE1_SS_C_RXP<7>")
	)
	(segment
		(start 64.366648 3.328924)
		(end 65.464436 2.572004)
		(width 0.127)
		(layer "B.Cu")
		(net "P3E_CPU0_PE1_SS_C_RXP<7>")
	)
	(segment
		(start 84.454492 -13.024866)
		(end 84.202778 -13.528802)
		(width 0.127)
		(layer "B.Cu")
		(net "P3E_CPU0_PE1_SS_C_RXP<7>")
	)
	(segment
		(start 84.243926 -12.777978)
		(end 84.397342 -12.854432)
		(width 0.127)
		(layer "B.Cu")
		(net "P3E_CPU0_PE1_SS_C_RXP<7>")
	)
	(segment
		(start 60.503816 10.718038)
		(end 60.50407 10.717784)
		(width 0.127)
		(layer "B.Cu")
		(net "P3E_CPU0_PE1_SS_C_RXP<7>")
	)
	(segment
		(start 65.464436 2.572004)
		(end 71.040498 -1.27889)
		(width 0.127)
		(layer "B.Cu")
		(net "P3E_CPU0_PE1_SS_C_RXP<7>")
	)
	(segment
		(start 81.914238 -9.09066)
		(end 81.914492 -9.090406)
		(width 0.127)
		(layer "B.Cu")
		(net "P3E_CPU0_PE1_SS_C_RXP<7>")
	)
	(segment
		(start 64.21628 3.434588)
		(end 64.364362 3.330702)
		(width 0.127)
		(layer "B.Cu")
		(net "P3E_CPU0_PE1_SS_C_RXP<7>")
	)
	(segment
		(start 84.397342 -12.854432)
		(end 84.397596 -12.854432)
		(width 0.127)
		(layer "B.Cu")
		(net "P3E_CPU0_PE1_SS_C_RXP<7>")
	)
	(arc
		(start 60.379864 11.016742)
		(mid 60.41212 10.855052)
		(end 60.503816 10.718038)
		(width 0.127)
		(layer "B.Cu")
		(net "P3E_CPU0_PE1_SS_C_RXP<7>")
	)
	(arc
		(start 80.91424 -7.333742)
		(mid 81.006258 -7.796436)
		(end 81.268316 -8.188706)
		(width 0.127)
		(layer "B.Cu")
		(net "P3E_CPU0_PE1_SS_C_RXP<7>")
	)
	(arc
		(start 79.4131 -4.747514)
		(mid 80.479044 -5.604667)
		(end 80.91424 -6.901434)
		(width 0.127)
		(layer "B.Cu")
		(net "P3E_CPU0_PE1_SS_C_RXP<7>")
	)
	(arc
		(start 82.989166 -10.67308)
		(mid 83.654244 -10.948564)
		(end 83.929728 -11.613642)
		(width 0.127)
		(layer "B.Cu")
		(net "P3E_CPU0_PE1_SS_C_RXP<7>")
	)
	(arc
		(start 83.929728 -12.07643)
		(mid 84.011775 -12.460812)
		(end 84.243926 -12.777978)
		(width 0.127)
		(layer "B.Cu")
		(net "P3E_CPU0_PE1_SS_C_RXP<7>")
	)
	(arc
		(start 81.914492 -9.616948)
		(mid 81.963377 -9.86421)
		(end 82.103214 -10.073894)
		(width 0.127)
		(layer "B.Cu")
		(net "P3E_CPU0_PE1_SS_C_RXP<7>")
	)
	(arc
		(start 82.500216 -10.470896)
		(mid 82.724592 -10.62057)
		(end 82.989166 -10.67308)
		(width 0.127)
		(layer "B.Cu")
		(net "P3E_CPU0_PE1_SS_C_RXP<7>")
	)
	(arc
		(start 84.397596 -12.854432)
		(mid 84.461359 -12.927885)
		(end 84.454492 -13.024866)
		(width 0.127)
		(layer "B.Cu")
		(net "P3E_CPU0_PE1_SS_C_RXP<7>")
	)
	(arc
		(start 81.73339 -8.65378)
		(mid 81.867321 -8.854222)
		(end 81.914238 -9.09066)
		(width 0.127)
		(layer "B.Cu")
		(net "P3E_CPU0_PE1_SS_C_RXP<7>")
	)
	(arc
		(start 60.50407 10.717784)
		(mid 60.595456 10.580826)
		(end 60.627514 10.419334)
		(width 0.127)
		(layer "B.Cu")
		(net "P3E_CPU0_PE1_SS_C_RXP<7>")
	)
	(segment
		(start 63.02756 10.40638)
		(end 63.02756 9.496552)
		(width 0.127)
		(layer "B.Cu")
		(net "P3E_CPU0_PE1_SS_C_RXP<6>")
	)
	(segment
		(start 62.77991 12.514072)
		(end 62.77991 11.004296)
		(width 0.127)
		(layer "B.Cu")
		(net "P3E_CPU0_PE1_SS_C_RXP<6>")
	)
	(segment
		(start 84.91474 -7.27837)
		(end 84.91474 -7.333742)
		(width 0.127)
		(layer "B.Cu")
		(net "P3E_CPU0_PE1_SS_C_RXP<6>")
	)
	(segment
		(start 85.914992 -9.090406)
		(end 85.914992 -9.616948)
		(width 0.127)
		(layer "B.Cu")
		(net "P3E_CPU0_PE1_SS_C_RXP<6>")
	)
	(segment
		(start 88.244426 -12.777978)
		(end 88.397842 -12.854432)
		(width 0.127)
		(layer "B.Cu")
		(net "P3E_CPU0_PE1_SS_C_RXP<6>")
	)
	(segment
		(start 75.325224 -2.794508)
		(end 82.16011 -3.947922)
		(width 0.127)
		(layer "B.Cu")
		(net "P3E_CPU0_PE1_SS_C_RXP<6>")
	)
	(segment
		(start 88.397842 -12.854432)
		(end 88.398096 -12.854432)
		(width 0.127)
		(layer "B.Cu")
		(net "P3E_CPU0_PE1_SS_C_RXP<6>")
	)
	(segment
		(start 85.914738 -9.09066)
		(end 85.914992 -9.090406)
		(width 0.127)
		(layer "B.Cu")
		(net "P3E_CPU0_PE1_SS_C_RXP<6>")
	)
	(segment
		(start 85.268816 -8.188706)
		(end 85.73389 -8.65378)
		(width 0.127)
		(layer "B.Cu")
		(net "P3E_CPU0_PE1_SS_C_RXP<6>")
	)
	(segment
		(start 88.454992 -13.024866)
		(end 88.203278 -13.528802)
		(width 0.127)
		(layer "B.Cu")
		(net "P3E_CPU0_PE1_SS_C_RXP<6>")
	)
	(segment
		(start 87.930228 -11.613642)
		(end 87.930228 -12.07643)
		(width 0.127)
		(layer "B.Cu")
		(net "P3E_CPU0_PE1_SS_C_RXP<6>")
	)
	(segment
		(start 63.245492 8.260842)
		(end 66.811398 3.16738)
		(width 0.127)
		(layer "B.Cu")
		(net "P3E_CPU0_PE1_SS_C_RXP<6>")
	)
	(segment
		(start 86.103714 -10.073894)
		(end 86.500716 -10.470896)
		(width 0.127)
		(layer "B.Cu")
		(net "P3E_CPU0_PE1_SS_C_RXP<6>")
	)
	(segment
		(start 88.203278 -13.528802)
		(end 88.080342 -13.750036)
		(width 0.127)
		(layer "B.Cu")
		(net "P3E_CPU0_PE1_SS_C_RXP<6>")
	)
	(segment
		(start 63.02756 9.496552)
		(end 63.245492 8.260842)
		(width 0.127)
		(layer "B.Cu")
		(net "P3E_CPU0_PE1_SS_C_RXP<6>")
	)
	(segment
		(start 66.811398 3.16738)
		(end 75.325224 -2.794508)
		(width 0.127)
		(layer "B.Cu")
		(net "P3E_CPU0_PE1_SS_C_RXP<6>")
	)
	(arc
		(start 87.930228 -12.07643)
		(mid 88.012275 -12.460812)
		(end 88.244426 -12.777978)
		(width 0.127)
		(layer "B.Cu")
		(net "P3E_CPU0_PE1_SS_C_RXP<6>")
	)
	(arc
		(start 85.914992 -9.616948)
		(mid 85.963877 -9.86421)
		(end 86.103714 -10.073894)
		(width 0.127)
		(layer "B.Cu")
		(net "P3E_CPU0_PE1_SS_C_RXP<6>")
	)
	(arc
		(start 62.77991 11.004296)
		(mid 62.812063 10.84265)
		(end 62.903608 10.705592)
		(width 0.127)
		(layer "B.Cu")
		(net "P3E_CPU0_PE1_SS_C_RXP<6>")
	)
	(arc
		(start 84.91474 -7.333742)
		(mid 85.006758 -7.796436)
		(end 85.268816 -8.188706)
		(width 0.127)
		(layer "B.Cu")
		(net "P3E_CPU0_PE1_SS_C_RXP<6>")
	)
	(arc
		(start 88.398096 -12.854432)
		(mid 88.461859 -12.927885)
		(end 88.454992 -13.024866)
		(width 0.127)
		(layer "B.Cu")
		(net "P3E_CPU0_PE1_SS_C_RXP<6>")
	)
	(arc
		(start 62.903608 10.705592)
		(mid 62.995335 10.568312)
		(end 63.02756 10.40638)
		(width 0.127)
		(layer "B.Cu")
		(net "P3E_CPU0_PE1_SS_C_RXP<6>")
	)
	(arc
		(start 84.9122 -7.189216)
		(mid 84.912835 -7.233811)
		(end 84.91474 -7.27837)
		(width 0.127)
		(layer "B.Cu")
		(net "P3E_CPU0_PE1_SS_C_RXP<6>")
	)
	(arc
		(start 83.534504 -4.519422)
		(mid 84.544939 -5.688365)
		(end 84.9122 -7.189216)
		(width 0.127)
		(layer "B.Cu")
		(net "P3E_CPU0_PE1_SS_C_RXP<6>")
	)
	(arc
		(start 86.500716 -10.470896)
		(mid 86.725092 -10.62057)
		(end 86.989666 -10.67308)
		(width 0.127)
		(layer "B.Cu")
		(net "P3E_CPU0_PE1_SS_C_RXP<6>")
	)
	(arc
		(start 86.989666 -10.67308)
		(mid 87.654744 -10.948564)
		(end 87.930228 -11.613642)
		(width 0.127)
		(layer "B.Cu")
		(net "P3E_CPU0_PE1_SS_C_RXP<6>")
	)
	(arc
		(start 85.73389 -8.65378)
		(mid 85.867821 -8.854222)
		(end 85.914738 -9.09066)
		(width 0.127)
		(layer "B.Cu")
		(net "P3E_CPU0_PE1_SS_C_RXP<6>")
	)
	(arc
		(start 82.16011 -3.947922)
		(mid 82.879947 -4.155173)
		(end 83.534504 -4.519422)
		(width 0.127)
		(layer "B.Cu")
		(net "P3E_CPU0_PE1_SS_C_RXP<6>")
	)
	(segment
		(start 90.104214 -10.073894)
		(end 90.501216 -10.470896)
		(width 0.127)
		(layer "B.Cu")
		(net "P3E_CPU0_PE1_SS_C_RXP<5>")
	)
	(segment
		(start 65.303908 10.769346)
		(end 65.304162 10.769092)
		(width 0.127)
		(layer "B.Cu")
		(net "P3E_CPU0_PE1_SS_C_RXP<5>")
	)
	(segment
		(start 92.455492 -13.024866)
		(end 92.20073 -13.533374)
		(width 0.127)
		(layer "B.Cu")
		(net "P3E_CPU0_PE1_SS_C_RXP<5>")
	)
	(segment
		(start 89.915238 -9.09066)
		(end 89.915492 -9.090406)
		(width 0.127)
		(layer "B.Cu")
		(net "P3E_CPU0_PE1_SS_C_RXP<5>")
	)
	(segment
		(start 65.427606 9.6012)
		(end 65.699132 8.060436)
		(width 0.127)
		(layer "B.Cu")
		(net "P3E_CPU0_PE1_SS_C_RXP<5>")
	)
	(segment
		(start 65.179956 12.514072)
		(end 65.179956 11.06805)
		(width 0.127)
		(layer "B.Cu")
		(net "P3E_CPU0_PE1_SS_C_RXP<5>")
	)
	(segment
		(start 91.930728 -11.613642)
		(end 91.930728 -12.07643)
		(width 0.127)
		(layer "B.Cu")
		(net "P3E_CPU0_PE1_SS_C_RXP<5>")
	)
	(segment
		(start 69.322442 2.88544)
		(end 70.146164 2.307336)
		(width 0.127)
		(layer "B.Cu")
		(net "P3E_CPU0_PE1_SS_C_RXP<5>")
	)
	(segment
		(start 85.28812 -3.292094)
		(end 88.059768 -5.233162)
		(width 0.127)
		(layer "B.Cu")
		(net "P3E_CPU0_PE1_SS_C_RXP<5>")
	)
	(segment
		(start 92.244926 -12.777978)
		(end 92.398342 -12.854432)
		(width 0.127)
		(layer "B.Cu")
		(net "P3E_CPU0_PE1_SS_C_RXP<5>")
	)
	(segment
		(start 65.699132 8.060436)
		(end 69.322442 2.88544)
		(width 0.127)
		(layer "B.Cu")
		(net "P3E_CPU0_PE1_SS_C_RXP<5>")
	)
	(segment
		(start 92.398342 -12.854432)
		(end 92.398596 -12.854432)
		(width 0.127)
		(layer "B.Cu")
		(net "P3E_CPU0_PE1_SS_C_RXP<5>")
	)
	(segment
		(start 88.059768 -5.233162)
		(end 88.80348 -6.295136)
		(width 0.127)
		(layer "B.Cu")
		(net "P3E_CPU0_PE1_SS_C_RXP<5>")
	)
	(segment
		(start 80.950562 -2.527554)
		(end 80.951324 -2.527808)
		(width 0.127)
		(layer "B.Cu")
		(net "P3E_CPU0_PE1_SS_C_RXP<5>")
	)
	(segment
		(start 70.149212 2.306828)
		(end 75.752198 -1.610614)
		(width 0.127)
		(layer "B.Cu")
		(net "P3E_CPU0_PE1_SS_C_RXP<5>")
	)
	(segment
		(start 70.146164 2.307336)
		(end 70.149212 2.306828)
		(width 0.127)
		(layer "B.Cu")
		(net "P3E_CPU0_PE1_SS_C_RXP<5>")
	)
	(segment
		(start 84.077302 -3.078734)
		(end 85.28812 -3.292094)
		(width 0.127)
		(layer "B.Cu")
		(net "P3E_CPU0_PE1_SS_C_RXP<5>")
	)
	(segment
		(start 89.915492 -9.090406)
		(end 89.915492 -9.616948)
		(width 0.127)
		(layer "B.Cu")
		(net "P3E_CPU0_PE1_SS_C_RXP<5>")
	)
	(segment
		(start 92.20073 -13.533374)
		(end 92.079572 -13.750036)
		(width 0.127)
		(layer "B.Cu")
		(net "P3E_CPU0_PE1_SS_C_RXP<5>")
	)
	(segment
		(start 75.752198 -1.610614)
		(end 80.950562 -2.527554)
		(width 0.127)
		(layer "B.Cu")
		(net "P3E_CPU0_PE1_SS_C_RXP<5>")
	)
	(segment
		(start 80.951324 -2.527808)
		(end 83.109308 -2.908046)
		(width 0.127)
		(layer "B.Cu")
		(net "P3E_CPU0_PE1_SS_C_RXP<5>")
	)
	(segment
		(start 65.427606 10.470642)
		(end 65.427606 9.6012)
		(width 0.127)
		(layer "B.Cu")
		(net "P3E_CPU0_PE1_SS_C_RXP<5>")
	)
	(segment
		(start 88.80348 -6.295136)
		(end 88.91524 -6.928612)
		(width 0.127)
		(layer "B.Cu")
		(net "P3E_CPU0_PE1_SS_C_RXP<5>")
	)
	(segment
		(start 83.109308 -2.908046)
		(end 84.077302 -3.078734)
		(width 0.127)
		(layer "B.Cu")
		(net "P3E_CPU0_PE1_SS_C_RXP<5>")
	)
	(segment
		(start 88.91524 -6.928612)
		(end 88.91524 -7.333742)
		(width 0.127)
		(layer "B.Cu")
		(net "P3E_CPU0_PE1_SS_C_RXP<5>")
	)
	(segment
		(start 89.269316 -8.188706)
		(end 89.73439 -8.65378)
		(width 0.127)
		(layer "B.Cu")
		(net "P3E_CPU0_PE1_SS_C_RXP<5>")
	)
	(arc
		(start 89.73439 -8.65378)
		(mid 89.868321 -8.854222)
		(end 89.915238 -9.09066)
		(width 0.127)
		(layer "B.Cu")
		(net "P3E_CPU0_PE1_SS_C_RXP<5>")
	)
	(arc
		(start 65.304162 10.769092)
		(mid 65.395548 10.632134)
		(end 65.427606 10.470642)
		(width 0.127)
		(layer "B.Cu")
		(net "P3E_CPU0_PE1_SS_C_RXP<5>")
	)
	(arc
		(start 90.501216 -10.470896)
		(mid 90.725592 -10.62057)
		(end 90.990166 -10.67308)
		(width 0.127)
		(layer "B.Cu")
		(net "P3E_CPU0_PE1_SS_C_RXP<5>")
	)
	(arc
		(start 92.398596 -12.854432)
		(mid 92.462359 -12.927885)
		(end 92.455492 -13.024866)
		(width 0.127)
		(layer "B.Cu")
		(net "P3E_CPU0_PE1_SS_C_RXP<5>")
	)
	(arc
		(start 91.930728 -12.07643)
		(mid 92.012775 -12.460812)
		(end 92.244926 -12.777978)
		(width 0.127)
		(layer "B.Cu")
		(net "P3E_CPU0_PE1_SS_C_RXP<5>")
	)
	(arc
		(start 89.915492 -9.616948)
		(mid 89.964377 -9.86421)
		(end 90.104214 -10.073894)
		(width 0.127)
		(layer "B.Cu")
		(net "P3E_CPU0_PE1_SS_C_RXP<5>")
	)
	(arc
		(start 88.91524 -7.333742)
		(mid 89.007258 -7.796436)
		(end 89.269316 -8.188706)
		(width 0.127)
		(layer "B.Cu")
		(net "P3E_CPU0_PE1_SS_C_RXP<5>")
	)
	(arc
		(start 65.179956 11.06805)
		(mid 65.212212 10.90636)
		(end 65.303908 10.769346)
		(width 0.127)
		(layer "B.Cu")
		(net "P3E_CPU0_PE1_SS_C_RXP<5>")
	)
	(arc
		(start 90.990166 -10.67308)
		(mid 91.655244 -10.948564)
		(end 91.930728 -11.613642)
		(width 0.127)
		(layer "B.Cu")
		(net "P3E_CPU0_PE1_SS_C_RXP<5>")
	)
	(segment
		(start 96.080072 -13.750036)
		(end 96.200468 -13.533882)
		(width 0.127)
		(layer "B.Cu")
		(net "P3E_CPU0_PE1_SS_C_RXP<4>")
	)
	(segment
		(start 71.595742 2.886456)
		(end 71.3994 3.070098)
		(width 0.127)
		(layer "B.Cu")
		(net "P3E_CPU0_PE1_SS_C_RXP<4>")
	)
	(segment
		(start 70.416674 3.989832)
		(end 68.135754 7.247636)
		(width 0.127)
		(layer "B.Cu")
		(net "P3E_CPU0_PE1_SS_C_RXP<4>")
	)
	(segment
		(start 93.73362 -8.65378)
		(end 93.268546 -8.188706)
		(width 0.127)
		(layer "B.Cu")
		(net "P3E_CPU0_PE1_SS_C_RXP<4>")
	)
	(segment
		(start 68.000372 8.014462)
		(end 68.000372 8.014716)
		(width 0.127)
		(layer "B.Cu")
		(net "P3E_CPU0_PE1_SS_C_RXP<4>")
	)
	(segment
		(start 95.929958 -12.07643)
		(end 95.929958 -11.613642)
		(width 0.127)
		(layer "B.Cu")
		(net "P3E_CPU0_PE1_SS_C_RXP<4>")
	)
	(segment
		(start 93.914722 -9.616948)
		(end 93.914722 -9.090406)
		(width 0.127)
		(layer "B.Cu")
		(net "P3E_CPU0_PE1_SS_C_RXP<4>")
	)
	(segment
		(start 93.914722 -9.090406)
		(end 93.914468 -9.09066)
		(width 0.127)
		(layer "B.Cu")
		(net "P3E_CPU0_PE1_SS_C_RXP<4>")
	)
	(segment
		(start 96.397826 -12.854432)
		(end 96.397572 -12.854432)
		(width 0.127)
		(layer "B.Cu")
		(net "P3E_CPU0_PE1_SS_C_RXP<4>")
	)
	(segment
		(start 68.000372 8.014716)
		(end 67.725544 9.573768)
		(width 0.127)
		(layer "B.Cu")
		(net "P3E_CPU0_PE1_SS_C_RXP<4>")
	)
	(segment
		(start 86.775798 -2.349754)
		(end 85.75294 -2.169414)
		(width 0.127)
		(layer "B.Cu")
		(net "P3E_CPU0_PE1_SS_C_RXP<4>")
	)
	(segment
		(start 67.725544 9.573768)
		(end 67.827652 10.151872)
		(width 0.127)
		(layer "B.Cu")
		(net "P3E_CPU0_PE1_SS_C_RXP<4>")
	)
	(segment
		(start 71.3994 3.070098)
		(end 71.005446 3.438652)
		(width 0.127)
		(layer "B.Cu")
		(net "P3E_CPU0_PE1_SS_C_RXP<4>")
	)
	(segment
		(start 71.005446 3.438652)
		(end 70.416674 3.989832)
		(width 0.127)
		(layer "B.Cu")
		(net "P3E_CPU0_PE1_SS_C_RXP<4>")
	)
	(segment
		(start 92.695268 -6.495034)
		(end 86.775798 -2.349754)
		(width 0.127)
		(layer "B.Cu")
		(net "P3E_CPU0_PE1_SS_C_RXP<4>")
	)
	(segment
		(start 68.135754 7.247636)
		(end 68.000372 8.014462)
		(width 0.127)
		(layer "B.Cu")
		(net "P3E_CPU0_PE1_SS_C_RXP<4>")
	)
	(segment
		(start 81.283048 -1.381252)
		(end 76.216764 -0.487934)
		(width 0.127)
		(layer "B.Cu")
		(net "P3E_CPU0_PE1_SS_C_RXP<4>")
	)
	(segment
		(start 92.877132 -6.754622)
		(end 92.695268 -6.495034)
		(width 0.127)
		(layer "B.Cu")
		(net "P3E_CPU0_PE1_SS_C_RXP<4>")
	)
	(segment
		(start 71.884032 2.616708)
		(end 71.595742 2.886456)
		(width 0.127)
		(layer "B.Cu")
		(net "P3E_CPU0_PE1_SS_C_RXP<4>")
	)
	(segment
		(start 76.216764 -0.487934)
		(end 72.200516 2.320544)
		(width 0.127)
		(layer "B.Cu")
		(net "P3E_CPU0_PE1_SS_C_RXP<4>")
	)
	(segment
		(start 96.397572 -12.854432)
		(end 96.244156 -12.777978)
		(width 0.127)
		(layer "B.Cu")
		(net "P3E_CPU0_PE1_SS_C_RXP<4>")
	)
	(segment
		(start 72.200516 2.320544)
		(end 71.884032 2.616708)
		(width 0.127)
		(layer "B.Cu")
		(net "P3E_CPU0_PE1_SS_C_RXP<4>")
	)
	(segment
		(start 94.500446 -10.470896)
		(end 94.103444 -10.073894)
		(width 0.127)
		(layer "B.Cu")
		(net "P3E_CPU0_PE1_SS_C_RXP<4>")
	)
	(segment
		(start 85.75294 -2.169414)
		(end 81.283048 -1.381252)
		(width 0.127)
		(layer "B.Cu")
		(net "P3E_CPU0_PE1_SS_C_RXP<4>")
	)
	(segment
		(start 67.827652 10.151872)
		(end 67.827652 10.483088)
		(width 0.127)
		(layer "B.Cu")
		(net "P3E_CPU0_PE1_SS_C_RXP<4>")
	)
	(segment
		(start 67.580002 11.081004)
		(end 67.580002 12.514072)
		(width 0.127)
		(layer "B.Cu")
		(net "P3E_CPU0_PE1_SS_C_RXP<4>")
	)
	(segment
		(start 96.200468 -13.533882)
		(end 96.454722 -13.024866)
		(width 0.127)
		(layer "B.Cu")
		(net "P3E_CPU0_PE1_SS_C_RXP<4>")
	)
	(arc
		(start 96.244156 -12.777978)
		(mid 96.011961 -12.460831)
		(end 95.929958 -12.07643)
		(width 0.127)
		(layer "B.Cu")
		(net "P3E_CPU0_PE1_SS_C_RXP<4>")
	)
	(arc
		(start 93.914468 -9.09066)
		(mid 93.867446 -8.854266)
		(end 93.73362 -8.65378)
		(width 0.127)
		(layer "B.Cu")
		(net "P3E_CPU0_PE1_SS_C_RXP<4>")
	)
	(arc
		(start 67.827652 10.483088)
		(mid 67.795441 10.645026)
		(end 67.7037 10.7823)
		(width 0.127)
		(layer "B.Cu")
		(net "P3E_CPU0_PE1_SS_C_RXP<4>")
	)
	(arc
		(start 96.454722 -13.024866)
		(mid 96.461481 -12.927921)
		(end 96.397826 -12.854432)
		(width 0.127)
		(layer "B.Cu")
		(net "P3E_CPU0_PE1_SS_C_RXP<4>")
	)
	(arc
		(start 92.914216 -7.333488)
		(mid 92.904943 -7.043461)
		(end 92.877132 -6.754622)
		(width 0.127)
		(layer "B.Cu")
		(net "P3E_CPU0_PE1_SS_C_RXP<4>")
	)
	(arc
		(start 67.7037 10.7823)
		(mid 67.612128 10.919347)
		(end 67.580002 11.081004)
		(width 0.127)
		(layer "B.Cu")
		(net "P3E_CPU0_PE1_SS_C_RXP<4>")
	)
	(arc
		(start 94.989396 -10.67308)
		(mid 94.724789 -10.620652)
		(end 94.500446 -10.470896)
		(width 0.127)
		(layer "B.Cu")
		(net "P3E_CPU0_PE1_SS_C_RXP<4>")
	)
	(arc
		(start 93.268546 -8.188706)
		(mid 93.006368 -7.796329)
		(end 92.914216 -7.333488)
		(width 0.127)
		(layer "B.Cu")
		(net "P3E_CPU0_PE1_SS_C_RXP<4>")
	)
	(arc
		(start 95.929958 -11.613642)
		(mid 95.654474 -10.948564)
		(end 94.989396 -10.67308)
		(width 0.127)
		(layer "B.Cu")
		(net "P3E_CPU0_PE1_SS_C_RXP<4>")
	)
	(arc
		(start 94.103444 -10.073894)
		(mid 93.963664 -9.864186)
		(end 93.914722 -9.616948)
		(width 0.127)
		(layer "B.Cu")
		(net "P3E_CPU0_PE1_SS_C_RXP<4>")
	)
	(segment
		(start 97.915222 -9.616948)
		(end 97.915222 -9.090406)
		(width 0.127)
		(layer "B.Cu")
		(net "P3E_CPU0_PE1_SS_C_RXP<3>")
	)
	(segment
		(start 99.930458 -12.07643)
		(end 99.930458 -11.613642)
		(width 0.127)
		(layer "B.Cu")
		(net "P3E_CPU0_PE1_SS_C_RXP<3>")
	)
	(segment
		(start 75.597258 1.393952)
		(end 74.830432 1.930908)
		(width 0.127)
		(layer "B.Cu")
		(net "P3E_CPU0_PE1_SS_C_RXP<3>")
	)
	(segment
		(start 100.398072 -12.854432)
		(end 100.244656 -12.777978)
		(width 0.127)
		(layer "B.Cu")
		(net "P3E_CPU0_PE1_SS_C_RXP<3>")
	)
	(segment
		(start 97.915222 -9.090406)
		(end 97.914968 -9.09066)
		(width 0.127)
		(layer "B.Cu")
		(net "P3E_CPU0_PE1_SS_C_RXP<3>")
	)
	(segment
		(start 100.398326 -12.854432)
		(end 100.398072 -12.854432)
		(width 0.127)
		(layer "B.Cu")
		(net "P3E_CPU0_PE1_SS_C_RXP<3>")
	)
	(segment
		(start 96.91497 -7.333742)
		(end 96.78289 -6.584442)
		(width 0.127)
		(layer "B.Cu")
		(net "P3E_CPU0_PE1_SS_C_RXP<3>")
	)
	(segment
		(start 70.108318 9.365488)
		(end 70.113144 9.4107)
		(width 0.127)
		(layer "B.Cu")
		(net "P3E_CPU0_PE1_SS_C_RXP<3>")
	)
	(segment
		(start 70.71995 6.157468)
		(end 70.108318 9.365488)
		(width 0.127)
		(layer "B.Cu")
		(net "P3E_CPU0_PE1_SS_C_RXP<3>")
	)
	(segment
		(start 87.258398 -1.229106)
		(end 76.682092 0.634746)
		(width 0.127)
		(layer "B.Cu")
		(net "P3E_CPU0_PE1_SS_C_RXP<3>")
	)
	(segment
		(start 87.767414 -1.319022)
		(end 87.258398 -1.229106)
		(width 0.127)
		(layer "B.Cu")
		(net "P3E_CPU0_PE1_SS_C_RXP<3>")
	)
	(segment
		(start 97.73412 -8.65378)
		(end 97.269046 -8.188706)
		(width 0.127)
		(layer "B.Cu")
		(net "P3E_CPU0_PE1_SS_C_RXP<3>")
	)
	(segment
		(start 95.344996 -5.474462)
		(end 95.115126 -5.313426)
		(width 0.127)
		(layer "B.Cu")
		(net "P3E_CPU0_PE1_SS_C_RXP<3>")
	)
	(segment
		(start 88.862916 -1.516888)
		(end 87.767414 -1.319022)
		(width 0.127)
		(layer "B.Cu")
		(net "P3E_CPU0_PE1_SS_C_RXP<3>")
	)
	(segment
		(start 95.115126 -5.313426)
		(end 89.979246 -1.891538)
		(width 0.127)
		(layer "B.Cu")
		(net "P3E_CPU0_PE1_SS_C_RXP<3>")
	)
	(segment
		(start 100.140008 -13.654024)
		(end 100.455222 -13.024866)
		(width 0.127)
		(layer "B.Cu")
		(net "P3E_CPU0_PE1_SS_C_RXP<3>")
	)
	(segment
		(start 96.641158 -6.382004)
		(end 95.344996 -5.474462)
		(width 0.127)
		(layer "B.Cu")
		(net "P3E_CPU0_PE1_SS_C_RXP<3>")
	)
	(segment
		(start 98.500946 -10.470896)
		(end 98.103944 -10.073894)
		(width 0.127)
		(layer "B.Cu")
		(net "P3E_CPU0_PE1_SS_C_RXP<3>")
	)
	(segment
		(start 89.979246 -1.891538)
		(end 89.3953 -1.64973)
		(width 0.127)
		(layer "B.Cu")
		(net "P3E_CPU0_PE1_SS_C_RXP<3>")
	)
	(segment
		(start 70.22465 10.439654)
		(end 70.224904 10.439654)
		(width 0.127)
		(layer "B.Cu")
		(net "P3E_CPU0_PE1_SS_C_RXP<3>")
	)
	(segment
		(start 70.141084 10.783316)
		(end 70.103238 10.821162)
		(width 0.127)
		(layer "B.Cu")
		(net "P3E_CPU0_PE1_SS_C_RXP<3>")
	)
	(segment
		(start 73.014586 3.202178)
		(end 70.71995 6.157468)
		(width 0.127)
		(layer "B.Cu")
		(net "P3E_CPU0_PE1_SS_C_RXP<3>")
	)
	(segment
		(start 96.78289 -6.584442)
		(end 96.641158 -6.382004)
		(width 0.127)
		(layer "B.Cu")
		(net "P3E_CPU0_PE1_SS_C_RXP<3>")
	)
	(segment
		(start 89.3953 -1.64973)
		(end 88.862916 -1.516888)
		(width 0.127)
		(layer "B.Cu")
		(net "P3E_CPU0_PE1_SS_C_RXP<3>")
	)
	(segment
		(start 70.226682 10.47115)
		(end 70.226682 10.57656)
		(width 0.127)
		(layer "B.Cu")
		(net "P3E_CPU0_PE1_SS_C_RXP<3>")
	)
	(segment
		(start 74.830432 1.930908)
		(end 73.014586 3.202178)
		(width 0.127)
		(layer "B.Cu")
		(net "P3E_CPU0_PE1_SS_C_RXP<3>")
	)
	(segment
		(start 100.079302 -13.750036)
		(end 100.140008 -13.654024)
		(width 0.127)
		(layer "B.Cu")
		(net "P3E_CPU0_PE1_SS_C_RXP<3>")
	)
	(segment
		(start 76.682092 0.634746)
		(end 75.597258 1.393952)
		(width 0.127)
		(layer "B.Cu")
		(net "P3E_CPU0_PE1_SS_C_RXP<3>")
	)
	(segment
		(start 70.113144 9.4107)
		(end 70.22465 10.439654)
		(width 0.127)
		(layer "B.Cu")
		(net "P3E_CPU0_PE1_SS_C_RXP<3>")
	)
	(segment
		(start 69.979794 11.119104)
		(end 69.979794 12.514072)
		(width 0.127)
		(layer "B.Cu")
		(net "P3E_CPU0_PE1_SS_C_RXP<3>")
	)
	(arc
		(start 70.103238 10.821162)
		(mid 70.0119 10.957859)
		(end 69.979794 11.119104)
		(width 0.127)
		(layer "B.Cu")
		(net "P3E_CPU0_PE1_SS_C_RXP<3>")
	)
	(arc
		(start 98.989896 -10.67308)
		(mid 98.725289 -10.620652)
		(end 98.500946 -10.470896)
		(width 0.127)
		(layer "B.Cu")
		(net "P3E_CPU0_PE1_SS_C_RXP<3>")
	)
	(arc
		(start 99.930458 -11.613642)
		(mid 99.654974 -10.948564)
		(end 98.989896 -10.67308)
		(width 0.127)
		(layer "B.Cu")
		(net "P3E_CPU0_PE1_SS_C_RXP<3>")
	)
	(arc
		(start 98.103944 -10.073894)
		(mid 97.964164 -9.864186)
		(end 97.915222 -9.616948)
		(width 0.127)
		(layer "B.Cu")
		(net "P3E_CPU0_PE1_SS_C_RXP<3>")
	)
	(arc
		(start 70.226682 10.57656)
		(mid 70.204443 10.688453)
		(end 70.141084 10.783316)
		(width 0.127)
		(layer "B.Cu")
		(net "P3E_CPU0_PE1_SS_C_RXP<3>")
	)
	(arc
		(start 100.455222 -13.024866)
		(mid 100.461981 -12.927921)
		(end 100.398326 -12.854432)
		(width 0.127)
		(layer "B.Cu")
		(net "P3E_CPU0_PE1_SS_C_RXP<3>")
	)
	(arc
		(start 70.224904 10.439654)
		(mid 70.226221 10.455378)
		(end 70.226682 10.47115)
		(width 0.127)
		(layer "B.Cu")
		(net "P3E_CPU0_PE1_SS_C_RXP<3>")
	)
	(arc
		(start 97.269046 -8.188706)
		(mid 97.006999 -7.796431)
		(end 96.91497 -7.333742)
		(width 0.127)
		(layer "B.Cu")
		(net "P3E_CPU0_PE1_SS_C_RXP<3>")
	)
	(arc
		(start 97.914968 -9.09066)
		(mid 97.867946 -8.854266)
		(end 97.73412 -8.65378)
		(width 0.127)
		(layer "B.Cu")
		(net "P3E_CPU0_PE1_SS_C_RXP<3>")
	)
	(arc
		(start 100.244656 -12.777978)
		(mid 100.012461 -12.460831)
		(end 99.930458 -12.07643)
		(width 0.127)
		(layer "B.Cu")
		(net "P3E_CPU0_PE1_SS_C_RXP<3>")
	)
	(segment
		(start 72.504046 10.706608)
		(end 72.503792 10.706862)
		(width 0.127)
		(layer "B.Cu")
		(net "P3E_CPU0_PE1_SS_C_RXP<2>")
	)
	(segment
		(start 77.224128 1.789938)
		(end 74.345292 3.736594)
		(width 0.127)
		(layer "B.Cu")
		(net "P3E_CPU0_PE1_SS_C_RXP<2>")
	)
	(segment
		(start 103.929688 -12.07643)
		(end 103.929688 -11.613642)
		(width 0.127)
		(layer "B.Cu")
		(net "P3E_CPU0_PE1_SS_C_RXP<2>")
	)
	(segment
		(start 104.249728 -13.434568)
		(end 104.454452 -13.024866)
		(width 0.127)
		(layer "B.Cu")
		(net "P3E_CPU0_PE1_SS_C_RXP<2>")
	)
	(segment
		(start 101.914452 -9.616948)
		(end 101.914452 -9.090406)
		(width 0.127)
		(layer "B.Cu")
		(net "P3E_CPU0_PE1_SS_C_RXP<2>")
	)
	(segment
		(start 72.242172 7.871968)
		(end 72.22109 7.991856)
		(width 0.127)
		(layer "B.Cu")
		(net "P3E_CPU0_PE1_SS_C_RXP<2>")
	)
	(segment
		(start 104.397556 -12.854432)
		(end 104.397302 -12.854432)
		(width 0.127)
		(layer "B.Cu")
		(net "P3E_CPU0_PE1_SS_C_RXP<2>")
	)
	(segment
		(start 88.701372 -0.253746)
		(end 87.573104 -0.05461)
		(width 0.127)
		(layer "B.Cu")
		(net "P3E_CPU0_PE1_SS_C_RXP<2>")
	)
	(segment
		(start 94.084902 -2.968498)
		(end 91.82227 -1.37033)
		(width 0.127)
		(layer "B.Cu")
		(net "P3E_CPU0_PE1_SS_C_RXP<2>")
	)
	(segment
		(start 72.607678 10.1854)
		(end 72.626982 10.425176)
		(width 0.127)
		(layer "B.Cu")
		(net "P3E_CPU0_PE1_SS_C_RXP<2>")
	)
	(segment
		(start 72.22109 7.991856)
		(end 72.607678 10.1854)
		(width 0.127)
		(layer "B.Cu")
		(net "P3E_CPU0_PE1_SS_C_RXP<2>")
	)
	(segment
		(start 101.914452 -9.090406)
		(end 101.914198 -9.09066)
		(width 0.127)
		(layer "B.Cu")
		(net "P3E_CPU0_PE1_SS_C_RXP<2>")
	)
	(segment
		(start 95.650812 -4.07416)
		(end 95.627952 -4.057904)
		(width 0.127)
		(layer "B.Cu")
		(net "P3E_CPU0_PE1_SS_C_RXP<2>")
	)
	(segment
		(start 72.508872 6.359652)
		(end 72.242172 7.871968)
		(width 0.127)
		(layer "B.Cu")
		(net "P3E_CPU0_PE1_SS_C_RXP<2>")
	)
	(segment
		(start 77.613256 1.703324)
		(end 77.570838 1.703324)
		(width 0.127)
		(layer "B.Cu")
		(net "P3E_CPU0_PE1_SS_C_RXP<2>")
	)
	(segment
		(start 74.345292 3.736594)
		(end 73.824592 4.480306)
		(width 0.127)
		(layer "B.Cu")
		(net "P3E_CPU0_PE1_SS_C_RXP<2>")
	)
	(segment
		(start 77.570838 1.703324)
		(end 77.224128 1.789938)
		(width 0.127)
		(layer "B.Cu")
		(net "P3E_CPU0_PE1_SS_C_RXP<2>")
	)
	(segment
		(start 102.500176 -10.470896)
		(end 102.103174 -10.073894)
		(width 0.127)
		(layer "B.Cu")
		(net "P3E_CPU0_PE1_SS_C_RXP<2>")
	)
	(segment
		(start 89.767918 -0.519938)
		(end 88.701372 -0.253746)
		(width 0.127)
		(layer "B.Cu")
		(net "P3E_CPU0_PE1_SS_C_RXP<2>")
	)
	(segment
		(start 73.82383 4.481322)
		(end 72.508872 6.359652)
		(width 0.127)
		(layer "B.Cu")
		(net "P3E_CPU0_PE1_SS_C_RXP<2>")
	)
	(segment
		(start 101.73335 -8.65378)
		(end 101.268276 -8.188706)
		(width 0.127)
		(layer "B.Cu")
		(net "P3E_CPU0_PE1_SS_C_RXP<2>")
	)
	(segment
		(start 72.37984 11.005566)
		(end 72.37984 12.514072)
		(width 0.127)
		(layer "B.Cu")
		(net "P3E_CPU0_PE1_SS_C_RXP<2>")
	)
	(segment
		(start 95.656908 -4.078478)
		(end 95.651828 -4.074922)
		(width 0.127)
		(layer "B.Cu")
		(net "P3E_CPU0_PE1_SS_C_RXP<2>")
	)
	(segment
		(start 104.397302 -12.854432)
		(end 104.243886 -12.777978)
		(width 0.127)
		(layer "B.Cu")
		(net "P3E_CPU0_PE1_SS_C_RXP<2>")
	)
	(segment
		(start 100.421694 -6.347968)
		(end 98.594418 -6.134862)
		(width 0.127)
		(layer "B.Cu")
		(net "P3E_CPU0_PE1_SS_C_RXP<2>")
	)
	(segment
		(start 95.651828 -4.074922)
		(end 95.650812 -4.07416)
		(width 0.127)
		(layer "B.Cu")
		(net "P3E_CPU0_PE1_SS_C_RXP<2>")
	)
	(segment
		(start 87.572596 -0.05461)
		(end 77.613256 1.703324)
		(width 0.127)
		(layer "B.Cu")
		(net "P3E_CPU0_PE1_SS_C_RXP<2>")
	)
	(segment
		(start 73.824592 4.480306)
		(end 73.82383 4.481322)
		(width 0.127)
		(layer "B.Cu")
		(net "P3E_CPU0_PE1_SS_C_RXP<2>")
	)
	(segment
		(start 97.283016 -5.216906)
		(end 95.656908 -4.078478)
		(width 0.127)
		(layer "B.Cu")
		(net "P3E_CPU0_PE1_SS_C_RXP<2>")
	)
	(segment
		(start 100.9142 -7.333742)
		(end 100.9142 -6.90118)
		(width 0.127)
		(layer "B.Cu")
		(net "P3E_CPU0_PE1_SS_C_RXP<2>")
	)
	(segment
		(start 95.627952 -4.057904)
		(end 94.679262 -3.388106)
		(width 0.127)
		(layer "B.Cu")
		(net "P3E_CPU0_PE1_SS_C_RXP<2>")
	)
	(segment
		(start 87.573104 -0.05461)
		(end 87.572596 -0.05461)
		(width 0.127)
		(layer "B.Cu")
		(net "P3E_CPU0_PE1_SS_C_RXP<2>")
	)
	(segment
		(start 98.594418 -6.134862)
		(end 97.283016 -5.216906)
		(width 0.127)
		(layer "B.Cu")
		(net "P3E_CPU0_PE1_SS_C_RXP<2>")
	)
	(segment
		(start 91.82227 -1.37033)
		(end 89.767918 -0.519938)
		(width 0.127)
		(layer "B.Cu")
		(net "P3E_CPU0_PE1_SS_C_RXP<2>")
	)
	(segment
		(start 104.079802 -13.750036)
		(end 104.249728 -13.434568)
		(width 0.127)
		(layer "B.Cu")
		(net "P3E_CPU0_PE1_SS_C_RXP<2>")
	)
	(segment
		(start 94.679262 -3.388106)
		(end 94.084902 -2.968498)
		(width 0.127)
		(layer "B.Cu")
		(net "P3E_CPU0_PE1_SS_C_RXP<2>")
	)
	(arc
		(start 102.989126 -10.67308)
		(mid 102.724519 -10.620652)
		(end 102.500176 -10.470896)
		(width 0.127)
		(layer "B.Cu")
		(net "P3E_CPU0_PE1_SS_C_RXP<2>")
	)
	(arc
		(start 72.503792 10.706862)
		(mid 72.412137 10.843894)
		(end 72.37984 11.005566)
		(width 0.127)
		(layer "B.Cu")
		(net "P3E_CPU0_PE1_SS_C_RXP<2>")
	)
	(arc
		(start 72.626982 10.425176)
		(mid 72.592014 10.577473)
		(end 72.504046 10.706608)
		(width 0.127)
		(layer "B.Cu")
		(net "P3E_CPU0_PE1_SS_C_RXP<2>")
	)
	(arc
		(start 104.243886 -12.777978)
		(mid 104.011691 -12.460831)
		(end 103.929688 -12.07643)
		(width 0.127)
		(layer "B.Cu")
		(net "P3E_CPU0_PE1_SS_C_RXP<2>")
	)
	(arc
		(start 100.9142 -6.90118)
		(mid 100.773239 -6.53082)
		(end 100.421694 -6.347968)
		(width 0.127)
		(layer "B.Cu")
		(net "P3E_CPU0_PE1_SS_C_RXP<2>")
	)
	(arc
		(start 103.929688 -11.613642)
		(mid 103.654204 -10.948564)
		(end 102.989126 -10.67308)
		(width 0.127)
		(layer "B.Cu")
		(net "P3E_CPU0_PE1_SS_C_RXP<2>")
	)
	(arc
		(start 101.914198 -9.09066)
		(mid 101.867176 -8.854266)
		(end 101.73335 -8.65378)
		(width 0.127)
		(layer "B.Cu")
		(net "P3E_CPU0_PE1_SS_C_RXP<2>")
	)
	(arc
		(start 104.454452 -13.024866)
		(mid 104.461211 -12.927921)
		(end 104.397556 -12.854432)
		(width 0.127)
		(layer "B.Cu")
		(net "P3E_CPU0_PE1_SS_C_RXP<2>")
	)
	(arc
		(start 101.268276 -8.188706)
		(mid 101.006229 -7.796431)
		(end 100.9142 -7.333742)
		(width 0.127)
		(layer "B.Cu")
		(net "P3E_CPU0_PE1_SS_C_RXP<2>")
	)
	(arc
		(start 102.103174 -10.073894)
		(mid 101.963394 -9.864186)
		(end 101.914452 -9.616948)
		(width 0.127)
		(layer "B.Cu")
		(net "P3E_CPU0_PE1_SS_C_RXP<2>")
	)
	(segment
		(start 77.71511 2.890012)
		(end 89.764616 0.76581)
		(width 0.127)
		(layer "B.Cu")
		(net "P3E_CPU0_PE1_SS_C_RXP<1>")
	)
	(segment
		(start 98.985578 -4.801362)
		(end 99.422712 -4.878324)
		(width 0.127)
		(layer "B.Cu")
		(net "P3E_CPU0_PE1_SS_C_RXP<1>")
	)
	(segment
		(start 105.268776 -8.188706)
		(end 105.73385 -8.65378)
		(width 0.127)
		(layer "B.Cu")
		(net "P3E_CPU0_PE1_SS_C_RXP<1>")
	)
	(segment
		(start 96.787208 -3.264916)
		(end 98.985578 -4.801362)
		(width 0.127)
		(layer "B.Cu")
		(net "P3E_CPU0_PE1_SS_C_RXP<1>")
	)
	(segment
		(start 74.45375 7.185152)
		(end 74.736198 5.583428)
		(width 0.127)
		(layer "B.Cu")
		(net "P3E_CPU0_PE1_SS_C_RXP<1>")
	)
	(segment
		(start 92.845128 -0.509524)
		(end 92.845128 -0.509778)
		(width 0.127)
		(layer "B.Cu")
		(net "P3E_CPU0_PE1_SS_C_RXP<1>")
	)
	(segment
		(start 108.244386 -12.777978)
		(end 108.397802 -12.854432)
		(width 0.127)
		(layer "B.Cu")
		(net "P3E_CPU0_PE1_SS_C_RXP<1>")
	)
	(segment
		(start 105.914698 -9.09066)
		(end 105.914952 -9.090406)
		(width 0.127)
		(layer "B.Cu")
		(net "P3E_CPU0_PE1_SS_C_RXP<1>")
	)
	(segment
		(start 108.209588 -13.516356)
		(end 108.080302 -13.750036)
		(width 0.127)
		(layer "B.Cu")
		(net "P3E_CPU0_PE1_SS_C_RXP<1>")
	)
	(segment
		(start 107.930188 -11.613642)
		(end 107.930188 -12.07643)
		(width 0.127)
		(layer "B.Cu")
		(net "P3E_CPU0_PE1_SS_C_RXP<1>")
	)
	(segment
		(start 108.397802 -12.854432)
		(end 108.398056 -12.854432)
		(width 0.127)
		(layer "B.Cu")
		(net "P3E_CPU0_PE1_SS_C_RXP<1>")
	)
	(segment
		(start 75.63866 4.294378)
		(end 77.71511 2.890012)
		(width 0.127)
		(layer "B.Cu")
		(net "P3E_CPU0_PE1_SS_C_RXP<1>")
	)
	(segment
		(start 99.422712 -4.878324)
		(end 99.800918 -4.945126)
		(width 0.127)
		(layer "B.Cu")
		(net "P3E_CPU0_PE1_SS_C_RXP<1>")
	)
	(segment
		(start 93.858588 -1.218184)
		(end 96.787208 -3.264916)
		(width 0.127)
		(layer "B.Cu")
		(net "P3E_CPU0_PE1_SS_C_RXP<1>")
	)
	(segment
		(start 99.800918 -4.945126)
		(end 101.04882 -5.165344)
		(width 0.127)
		(layer "B.Cu")
		(net "P3E_CPU0_PE1_SS_C_RXP<1>")
	)
	(segment
		(start 105.914952 -9.090406)
		(end 105.914952 -9.616948)
		(width 0.127)
		(layer "B.Cu")
		(net "P3E_CPU0_PE1_SS_C_RXP<1>")
	)
	(segment
		(start 75.027028 10.437622)
		(end 74.45375 7.185152)
		(width 0.127)
		(layer "B.Cu")
		(net "P3E_CPU0_PE1_SS_C_RXP<1>")
	)
	(segment
		(start 92.845128 -0.509778)
		(end 93.858588 -1.218184)
		(width 0.127)
		(layer "B.Cu")
		(net "P3E_CPU0_PE1_SS_C_RXP<1>")
	)
	(segment
		(start 101.04882 -5.165344)
		(end 101.706172 -5.625592)
		(width 0.127)
		(layer "B.Cu")
		(net "P3E_CPU0_PE1_SS_C_RXP<1>")
	)
	(segment
		(start 101.706172 -5.625592)
		(end 104.298242 -6.240272)
		(width 0.127)
		(layer "B.Cu")
		(net "P3E_CPU0_PE1_SS_C_RXP<1>")
	)
	(segment
		(start 106.103674 -10.073894)
		(end 106.500676 -10.470896)
		(width 0.127)
		(layer "B.Cu")
		(net "P3E_CPU0_PE1_SS_C_RXP<1>")
	)
	(segment
		(start 74.779886 12.514072)
		(end 74.779886 11.018774)
		(width 0.127)
		(layer "B.Cu")
		(net "P3E_CPU0_PE1_SS_C_RXP<1>")
	)
	(segment
		(start 75.179174 4.950714)
		(end 75.63866 4.294378)
		(width 0.127)
		(layer "B.Cu")
		(net "P3E_CPU0_PE1_SS_C_RXP<1>")
	)
	(segment
		(start 108.454952 -13.024866)
		(end 108.209588 -13.516356)
		(width 0.127)
		(layer "B.Cu")
		(net "P3E_CPU0_PE1_SS_C_RXP<1>")
	)
	(segment
		(start 89.764616 0.76581)
		(end 92.845128 -0.509524)
		(width 0.127)
		(layer "B.Cu")
		(net "P3E_CPU0_PE1_SS_C_RXP<1>")
	)
	(segment
		(start 74.736198 5.583428)
		(end 75.179174 4.950714)
		(width 0.127)
		(layer "B.Cu")
		(net "P3E_CPU0_PE1_SS_C_RXP<1>")
	)
	(arc
		(start 105.73385 -8.65378)
		(mid 105.867781 -8.854222)
		(end 105.914698 -9.09066)
		(width 0.127)
		(layer "B.Cu")
		(net "P3E_CPU0_PE1_SS_C_RXP<1>")
	)
	(arc
		(start 74.779886 11.018774)
		(mid 74.812097 10.856836)
		(end 74.903838 10.719562)
		(width 0.127)
		(layer "B.Cu")
		(net "P3E_CPU0_PE1_SS_C_RXP<1>")
	)
	(arc
		(start 106.989626 -10.67308)
		(mid 107.654704 -10.948564)
		(end 107.930188 -11.613642)
		(width 0.127)
		(layer "B.Cu")
		(net "P3E_CPU0_PE1_SS_C_RXP<1>")
	)
	(arc
		(start 104.298242 -6.240272)
		(mid 104.794824 -6.582327)
		(end 104.930448 -7.169912)
		(width 0.127)
		(layer "B.Cu")
		(net "P3E_CPU0_PE1_SS_C_RXP<1>")
	)
	(arc
		(start 74.903838 10.719562)
		(mid 74.991994 10.590201)
		(end 75.027028 10.437622)
		(width 0.127)
		(layer "B.Cu")
		(net "P3E_CPU0_PE1_SS_C_RXP<1>")
	)
	(arc
		(start 108.398056 -12.854432)
		(mid 108.461819 -12.927885)
		(end 108.454952 -13.024866)
		(width 0.127)
		(layer "B.Cu")
		(net "P3E_CPU0_PE1_SS_C_RXP<1>")
	)
	(arc
		(start 104.930448 -7.169912)
		(mid 104.97908 -7.719332)
		(end 105.268776 -8.188706)
		(width 0.127)
		(layer "B.Cu")
		(net "P3E_CPU0_PE1_SS_C_RXP<1>")
	)
	(arc
		(start 106.500676 -10.470896)
		(mid 106.725052 -10.62057)
		(end 106.989626 -10.67308)
		(width 0.127)
		(layer "B.Cu")
		(net "P3E_CPU0_PE1_SS_C_RXP<1>")
	)
	(arc
		(start 107.930188 -12.07643)
		(mid 108.012235 -12.460812)
		(end 108.244386 -12.777978)
		(width 0.127)
		(layer "B.Cu")
		(net "P3E_CPU0_PE1_SS_C_RXP<1>")
	)
	(arc
		(start 105.914952 -9.616948)
		(mid 105.963837 -9.86421)
		(end 106.103674 -10.073894)
		(width 0.127)
		(layer "B.Cu")
		(net "P3E_CPU0_PE1_SS_C_RXP<1>")
	)
	(segment
		(start 98.673666 -3.134614)
		(end 93.801184 0.277114)
		(width 0.127)
		(layer "B.Cu")
		(net "P3E_CPU0_PE1_SS_C_RXP<0>")
	)
	(segment
		(start 108.773468 -6.456934)
		(end 108.194602 -6.171692)
		(width 0.127)
		(layer "B.Cu")
		(net "P3E_CPU0_PE1_SS_C_RXP<0>")
	)
	(segment
		(start 109.915452 -9.090406)
		(end 109.915198 -9.09066)
		(width 0.127)
		(layer "B.Cu")
		(net "P3E_CPU0_PE1_SS_C_RXP<0>")
	)
	(segment
		(start 76.014326 6.65226)
		(end 76.256388 8.025384)
		(width 0.127)
		(layer "B.Cu")
		(net "P3E_CPU0_PE1_SS_C_RXP<0>")
	)
	(segment
		(start 76.882244 4.92125)
		(end 76.13015 5.99567)
		(width 0.127)
		(layer "B.Cu")
		(net "P3E_CPU0_PE1_SS_C_RXP<0>")
	)
	(segment
		(start 101.65842 -3.946144)
		(end 99.218242 -3.515868)
		(width 0.127)
		(layer "B.Cu")
		(net "P3E_CPU0_PE1_SS_C_RXP<0>")
	)
	(segment
		(start 76.256388 8.025384)
		(end 77.361542 9.60374)
		(width 0.127)
		(layer "B.Cu")
		(net "P3E_CPU0_PE1_SS_C_RXP<0>")
	)
	(segment
		(start 109.73435 -8.65378)
		(end 109.269276 -8.188706)
		(width 0.127)
		(layer "B.Cu")
		(net "P3E_CPU0_PE1_SS_C_RXP<0>")
	)
	(segment
		(start 108.194602 -6.171692)
		(end 104.242362 -4.978146)
		(width 0.127)
		(layer "B.Cu")
		(net "P3E_CPU0_PE1_SS_C_RXP<0>")
	)
	(segment
		(start 112.398556 -12.854432)
		(end 112.398302 -12.854432)
		(width 0.127)
		(layer "B.Cu")
		(net "P3E_CPU0_PE1_SS_C_RXP<0>")
	)
	(segment
		(start 90.080338 1.919478)
		(end 90.075258 1.917446)
		(width 0.127)
		(layer "B.Cu")
		(net "P3E_CPU0_PE1_SS_C_RXP<0>")
	)
	(segment
		(start 108.864146 -6.637274)
		(end 108.773468 -6.456934)
		(width 0.127)
		(layer "B.Cu")
		(net "P3E_CPU0_PE1_SS_C_RXP<0>")
	)
	(segment
		(start 112.213136 -13.508482)
		(end 112.455452 -13.024866)
		(width 0.127)
		(layer "B.Cu")
		(net "P3E_CPU0_PE1_SS_C_RXP<0>")
	)
	(segment
		(start 90.075258 1.917446)
		(end 78.17993 4.012692)
		(width 0.127)
		(layer "B.Cu")
		(net "P3E_CPU0_PE1_SS_C_RXP<0>")
	)
	(segment
		(start 109.915452 -9.616948)
		(end 109.915452 -9.090406)
		(width 0.127)
		(layer "B.Cu")
		(net "P3E_CPU0_PE1_SS_C_RXP<0>")
	)
	(segment
		(start 108.9152 -7.333742)
		(end 108.9152 -6.855206)
		(width 0.127)
		(layer "B.Cu")
		(net "P3E_CPU0_PE1_SS_C_RXP<0>")
	)
	(segment
		(start 78.17993 4.012692)
		(end 76.882244 4.92125)
		(width 0.127)
		(layer "B.Cu")
		(net "P3E_CPU0_PE1_SS_C_RXP<0>")
	)
	(segment
		(start 104.242362 -4.978146)
		(end 102.291134 -4.389374)
		(width 0.127)
		(layer "B.Cu")
		(net "P3E_CPU0_PE1_SS_C_RXP<0>")
	)
	(segment
		(start 77.179932 10.92835)
		(end 77.179932 12.514072)
		(width 0.127)
		(layer "B.Cu")
		(net "P3E_CPU0_PE1_SS_C_RXP<0>")
	)
	(segment
		(start 111.930688 -12.07643)
		(end 111.930688 -11.613642)
		(width 0.127)
		(layer "B.Cu")
		(net "P3E_CPU0_PE1_SS_C_RXP<0>")
	)
	(segment
		(start 93.801184 0.277114)
		(end 93.44152 0.528574)
		(width 0.127)
		(layer "B.Cu")
		(net "P3E_CPU0_PE1_SS_C_RXP<0>")
	)
	(segment
		(start 77.361542 9.60374)
		(end 77.427582 9.977882)
		(width 0.127)
		(layer "B.Cu")
		(net "P3E_CPU0_PE1_SS_C_RXP<0>")
	)
	(segment
		(start 99.218242 -3.515868)
		(end 98.673666 -3.134614)
		(width 0.127)
		(layer "B.Cu")
		(net "P3E_CPU0_PE1_SS_C_RXP<0>")
	)
	(segment
		(start 77.427582 9.977882)
		(end 77.427582 10.383012)
		(width 0.127)
		(layer "B.Cu")
		(net "P3E_CPU0_PE1_SS_C_RXP<0>")
	)
	(segment
		(start 76.13015 5.99567)
		(end 76.014326 6.65226)
		(width 0.127)
		(layer "B.Cu")
		(net "P3E_CPU0_PE1_SS_C_RXP<0>")
	)
	(segment
		(start 102.291134 -4.389374)
		(end 101.65842 -3.946144)
		(width 0.127)
		(layer "B.Cu")
		(net "P3E_CPU0_PE1_SS_C_RXP<0>")
	)
	(segment
		(start 93.44152 0.528574)
		(end 90.080338 1.919478)
		(width 0.127)
		(layer "B.Cu")
		(net "P3E_CPU0_PE1_SS_C_RXP<0>")
	)
	(segment
		(start 112.398302 -12.854432)
		(end 112.244886 -12.777978)
		(width 0.127)
		(layer "B.Cu")
		(net "P3E_CPU0_PE1_SS_C_RXP<0>")
	)
	(segment
		(start 112.079532 -13.750036)
		(end 112.213136 -13.508482)
		(width 0.127)
		(layer "B.Cu")
		(net "P3E_CPU0_PE1_SS_C_RXP<0>")
	)
	(segment
		(start 110.501176 -10.470896)
		(end 110.104174 -10.073894)
		(width 0.127)
		(layer "B.Cu")
		(net "P3E_CPU0_PE1_SS_C_RXP<0>")
	)
	(segment
		(start 77.303884 10.681716)
		(end 77.2668 10.7188)
		(width 0.127)
		(layer "B.Cu")
		(net "P3E_CPU0_PE1_SS_C_RXP<0>")
	)
	(arc
		(start 109.915198 -9.09066)
		(mid 109.868176 -8.854266)
		(end 109.73435 -8.65378)
		(width 0.127)
		(layer "B.Cu")
		(net "P3E_CPU0_PE1_SS_C_RXP<0>")
	)
	(arc
		(start 110.104174 -10.073894)
		(mid 109.964394 -9.864186)
		(end 109.915452 -9.616948)
		(width 0.127)
		(layer "B.Cu")
		(net "P3E_CPU0_PE1_SS_C_RXP<0>")
	)
	(arc
		(start 112.455452 -13.024866)
		(mid 112.462211 -12.927921)
		(end 112.398556 -12.854432)
		(width 0.127)
		(layer "B.Cu")
		(net "P3E_CPU0_PE1_SS_C_RXP<0>")
	)
	(arc
		(start 77.2668 10.7188)
		(mid 77.202506 10.814928)
		(end 77.179932 10.92835)
		(width 0.127)
		(layer "B.Cu")
		(net "P3E_CPU0_PE1_SS_C_RXP<0>")
	)
	(arc
		(start 111.930688 -11.613642)
		(mid 111.655204 -10.948564)
		(end 110.990126 -10.67308)
		(width 0.127)
		(layer "B.Cu")
		(net "P3E_CPU0_PE1_SS_C_RXP<0>")
	)
	(arc
		(start 112.244886 -12.777978)
		(mid 112.012691 -12.460831)
		(end 111.930688 -12.07643)
		(width 0.127)
		(layer "B.Cu")
		(net "P3E_CPU0_PE1_SS_C_RXP<0>")
	)
	(arc
		(start 77.427582 10.383012)
		(mid 77.395429 10.544658)
		(end 77.303884 10.681716)
		(width 0.127)
		(layer "B.Cu")
		(net "P3E_CPU0_PE1_SS_C_RXP<0>")
	)
	(arc
		(start 109.269276 -8.188706)
		(mid 109.007229 -7.796431)
		(end 108.9152 -7.333742)
		(width 0.127)
		(layer "B.Cu")
		(net "P3E_CPU0_PE1_SS_C_RXP<0>")
	)
	(arc
		(start 108.9152 -6.855206)
		(mid 108.902679 -6.743193)
		(end 108.864146 -6.637274)
		(width 0.127)
		(layer "B.Cu")
		(net "P3E_CPU0_PE1_SS_C_RXP<0>")
	)
	(arc
		(start 110.990126 -10.67308)
		(mid 110.725519 -10.620652)
		(end 110.501176 -10.470896)
		(width 0.127)
		(layer "B.Cu")
		(net "P3E_CPU0_PE1_SS_C_RXP<0>")
	)
	(segment
		(start 61.391292 8.000746)
		(end 61.635386 7.95782)
		(width 0.127)
		(layer "B.Cu")
		(net "P3E_CPU0_PE1_SS_C_RXN<7>")
	)
	(segment
		(start 64.435482 3.653536)
		(end 74.982578 -3.630676)
		(width 0.127)
		(layer "B.Cu")
		(net "P3E_CPU0_PE1_SS_C_RXN<7>")
	)
	(segment
		(start 74.982578 -3.630676)
		(end 79.254604 -4.38404)
		(width 0.127)
		(layer "B.Cu")
		(net "P3E_CPU0_PE1_SS_C_RXN<7>")
	)
	(segment
		(start 62.449202 6.490208)
		(end 64.435482 3.653536)
		(width 0.127)
		(layer "B.Cu")
		(net "P3E_CPU0_PE1_SS_C_RXN<7>")
	)
	(segment
		(start 82.319114 -9.858248)
		(end 82.715862 -10.25525)
		(width 0.127)
		(layer "B.Cu")
		(net "P3E_CPU0_PE1_SS_C_RXN<7>")
	)
	(segment
		(start 61.179964 12.514072)
		(end 61.179964 11.063224)
		(width 0.127)
		(layer "B.Cu")
		(net "P3E_CPU0_PE1_SS_C_RXN<7>")
	)
	(segment
		(start 84.533994 -12.58189)
		(end 84.534248 -12.58189)
		(width 0.127)
		(layer "B.Cu")
		(net "P3E_CPU0_PE1_SS_C_RXN<7>")
	)
	(segment
		(start 61.85408 7.645654)
		(end 61.8109 7.40156)
		(width 0.127)
		(layer "B.Cu")
		(net "P3E_CPU0_PE1_SS_C_RXN<7>")
	)
	(segment
		(start 61.635386 7.95782)
		(end 61.85408 7.645654)
		(width 0.127)
		(layer "B.Cu")
		(net "P3E_CPU0_PE1_SS_C_RXN<7>")
	)
	(segment
		(start 62.029594 7.089394)
		(end 62.273688 7.046468)
		(width 0.127)
		(layer "B.Cu")
		(net "P3E_CPU0_PE1_SS_C_RXN<7>")
	)
	(segment
		(start 84.952078 -12.029694)
		(end 85.079332 -11.749786)
		(width 0.127)
		(layer "B.Cu")
		(net "P3E_CPU0_PE1_SS_C_RXN<7>")
	)
	(segment
		(start 82.219292 -9.09066)
		(end 82.219292 -9.617202)
		(width 0.127)
		(layer "B.Cu")
		(net "P3E_CPU0_PE1_SS_C_RXN<7>")
	)
	(segment
		(start 81.483962 -7.97306)
		(end 81.949036 -8.438134)
		(width 0.127)
		(layer "B.Cu")
		(net "P3E_CPU0_PE1_SS_C_RXN<7>")
	)
	(segment
		(start 62.273688 7.046468)
		(end 62.492128 6.734302)
		(width 0.127)
		(layer "B.Cu")
		(net "P3E_CPU0_PE1_SS_C_RXN<7>")
	)
	(segment
		(start 61.8109 7.40156)
		(end 62.029594 7.089394)
		(width 0.127)
		(layer "B.Cu")
		(net "P3E_CPU0_PE1_SS_C_RXN<7>")
	)
	(segment
		(start 79.254604 -4.38404)
		(end 79.294228 -4.368292)
		(width 0.127)
		(layer "B.Cu")
		(net "P3E_CPU0_PE1_SS_C_RXN<7>")
	)
	(segment
		(start 60.932314 10.465308)
		(end 60.932314 9.6774)
		(width 0.127)
		(layer "B.Cu")
		(net "P3E_CPU0_PE1_SS_C_RXN<7>")
	)
	(segment
		(start 79.294228 -4.368292)
		(end 79.529686 -4.465828)
		(width 0.127)
		(layer "B.Cu")
		(net "P3E_CPU0_PE1_SS_C_RXN<7>")
	)
	(segment
		(start 81.21904 -6.895592)
		(end 81.21904 -7.333488)
		(width 0.127)
		(layer "B.Cu")
		(net "P3E_CPU0_PE1_SS_C_RXN<7>")
	)
	(segment
		(start 62.492128 6.734302)
		(end 62.449202 6.490208)
		(width 0.127)
		(layer "B.Cu")
		(net "P3E_CPU0_PE1_SS_C_RXN<7>")
	)
	(segment
		(start 84.234528 -11.613642)
		(end 84.234528 -12.076684)
		(width 0.127)
		(layer "B.Cu")
		(net "P3E_CPU0_PE1_SS_C_RXN<7>")
	)
	(segment
		(start 84.420202 -12.524994)
		(end 84.533994 -12.58189)
		(width 0.127)
		(layer "B.Cu")
		(net "P3E_CPU0_PE1_SS_C_RXN<7>")
	)
	(segment
		(start 84.704682 -12.524994)
		(end 84.952078 -12.029694)
		(width 0.127)
		(layer "B.Cu")
		(net "P3E_CPU0_PE1_SS_C_RXN<7>")
	)
	(segment
		(start 61.172852 8.312912)
		(end 61.391292 8.000746)
		(width 0.127)
		(layer "B.Cu")
		(net "P3E_CPU0_PE1_SS_C_RXN<7>")
	)
	(segment
		(start 60.932314 9.6774)
		(end 61.172852 8.312912)
		(width 0.127)
		(layer "B.Cu")
		(net "P3E_CPU0_PE1_SS_C_RXN<7>")
	)
	(arc
		(start 82.219292 -9.617202)
		(mid 82.245239 -9.747647)
		(end 82.319114 -9.858248)
		(width 0.127)
		(layer "B.Cu")
		(net "P3E_CPU0_PE1_SS_C_RXN<7>")
	)
	(arc
		(start 81.949036 -8.438134)
		(mid 82.149076 -8.737515)
		(end 82.219292 -9.09066)
		(width 0.127)
		(layer "B.Cu")
		(net "P3E_CPU0_PE1_SS_C_RXN<7>")
	)
	(arc
		(start 79.529686 -4.465828)
		(mid 80.730877 -5.432832)
		(end 81.21904 -6.895592)
		(width 0.127)
		(layer "B.Cu")
		(net "P3E_CPU0_PE1_SS_C_RXN<7>")
	)
	(arc
		(start 61.056012 10.764012)
		(mid 60.96444 10.626965)
		(end 60.932314 10.465308)
		(width 0.127)
		(layer "B.Cu")
		(net "P3E_CPU0_PE1_SS_C_RXN<7>")
	)
	(arc
		(start 82.989166 -10.36828)
		(mid 83.86977 -10.733038)
		(end 84.234528 -11.613642)
		(width 0.127)
		(layer "B.Cu")
		(net "P3E_CPU0_PE1_SS_C_RXN<7>")
	)
	(arc
		(start 81.21904 -7.333488)
		(mid 81.287891 -7.679623)
		(end 81.483962 -7.97306)
		(width 0.127)
		(layer "B.Cu")
		(net "P3E_CPU0_PE1_SS_C_RXN<7>")
	)
	(arc
		(start 61.179964 11.063224)
		(mid 61.147753 10.901286)
		(end 61.056012 10.764012)
		(width 0.127)
		(layer "B.Cu")
		(net "P3E_CPU0_PE1_SS_C_RXN<7>")
	)
	(arc
		(start 84.534248 -12.58189)
		(mid 84.631304 -12.588831)
		(end 84.704682 -12.524994)
		(width 0.127)
		(layer "B.Cu")
		(net "P3E_CPU0_PE1_SS_C_RXN<7>")
	)
	(arc
		(start 82.715862 -10.25525)
		(mid 82.84127 -10.338952)
		(end 82.989166 -10.36828)
		(width 0.127)
		(layer "B.Cu")
		(net "P3E_CPU0_PE1_SS_C_RXN<7>")
	)
	(arc
		(start 84.234528 -12.076684)
		(mid 84.282787 -12.319299)
		(end 84.420202 -12.524994)
		(width 0.127)
		(layer "B.Cu")
		(net "P3E_CPU0_PE1_SS_C_RXN<7>")
	)
	(segment
		(start 88.534494 -12.58189)
		(end 88.534748 -12.58189)
		(width 0.127)
		(layer "B.Cu")
		(net "P3E_CPU0_PE1_SS_C_RXN<6>")
	)
	(segment
		(start 88.705182 -12.524994)
		(end 88.952578 -12.029694)
		(width 0.127)
		(layer "B.Cu")
		(net "P3E_CPU0_PE1_SS_C_RXN<6>")
	)
	(segment
		(start 75.443842 -2.505202)
		(end 82.21091 -3.647186)
		(width 0.127)
		(layer "B.Cu")
		(net "P3E_CPU0_PE1_SS_C_RXN<6>")
	)
	(segment
		(start 63.58001 12.514072)
		(end 63.58001 11.024616)
		(width 0.127)
		(layer "B.Cu")
		(net "P3E_CPU0_PE1_SS_C_RXN<6>")
	)
	(segment
		(start 64.390524 7.156704)
		(end 64.634618 7.113778)
		(width 0.127)
		(layer "B.Cu")
		(net "P3E_CPU0_PE1_SS_C_RXN<6>")
	)
	(segment
		(start 85.21954 -7.278116)
		(end 85.21954 -7.333488)
		(width 0.127)
		(layer "B.Cu")
		(net "P3E_CPU0_PE1_SS_C_RXN<6>")
	)
	(segment
		(start 63.33236 10.426954)
		(end 63.33236 9.523476)
		(width 0.127)
		(layer "B.Cu")
		(net "P3E_CPU0_PE1_SS_C_RXN<6>")
	)
	(segment
		(start 64.810132 6.557518)
		(end 67.030346 3.386328)
		(width 0.127)
		(layer "B.Cu")
		(net "P3E_CPU0_PE1_SS_C_RXN<6>")
	)
	(segment
		(start 63.99657 8.02513)
		(end 64.215264 7.712964)
		(width 0.127)
		(layer "B.Cu")
		(net "P3E_CPU0_PE1_SS_C_RXN<6>")
	)
	(segment
		(start 63.534036 8.380222)
		(end 63.752476 8.068056)
		(width 0.127)
		(layer "B.Cu")
		(net "P3E_CPU0_PE1_SS_C_RXN<6>")
	)
	(segment
		(start 88.420702 -12.524994)
		(end 88.534494 -12.58189)
		(width 0.127)
		(layer "B.Cu")
		(net "P3E_CPU0_PE1_SS_C_RXN<6>")
	)
	(segment
		(start 85.484462 -7.97306)
		(end 85.949536 -8.438134)
		(width 0.127)
		(layer "B.Cu")
		(net "P3E_CPU0_PE1_SS_C_RXN<6>")
	)
	(segment
		(start 88.235028 -11.613642)
		(end 88.235028 -12.076684)
		(width 0.127)
		(layer "B.Cu")
		(net "P3E_CPU0_PE1_SS_C_RXN<6>")
	)
	(segment
		(start 63.33236 9.523476)
		(end 63.534036 8.380222)
		(width 0.127)
		(layer "B.Cu")
		(net "P3E_CPU0_PE1_SS_C_RXN<6>")
	)
	(segment
		(start 64.172084 7.46887)
		(end 64.390524 7.156704)
		(width 0.127)
		(layer "B.Cu")
		(net "P3E_CPU0_PE1_SS_C_RXN<6>")
	)
	(segment
		(start 64.215264 7.712964)
		(end 64.172084 7.46887)
		(width 0.127)
		(layer "B.Cu")
		(net "P3E_CPU0_PE1_SS_C_RXN<6>")
	)
	(segment
		(start 86.319614 -9.858248)
		(end 86.716362 -10.25525)
		(width 0.127)
		(layer "B.Cu")
		(net "P3E_CPU0_PE1_SS_C_RXN<6>")
	)
	(segment
		(start 86.219792 -9.09066)
		(end 86.219792 -9.617202)
		(width 0.127)
		(layer "B.Cu")
		(net "P3E_CPU0_PE1_SS_C_RXN<6>")
	)
	(segment
		(start 64.634618 7.113778)
		(end 64.853312 6.801612)
		(width 0.127)
		(layer "B.Cu")
		(net "P3E_CPU0_PE1_SS_C_RXN<6>")
	)
	(segment
		(start 63.752476 8.068056)
		(end 63.99657 8.02513)
		(width 0.127)
		(layer "B.Cu")
		(net "P3E_CPU0_PE1_SS_C_RXN<6>")
	)
	(segment
		(start 67.030346 3.386328)
		(end 75.443842 -2.505202)
		(width 0.127)
		(layer "B.Cu")
		(net "P3E_CPU0_PE1_SS_C_RXN<6>")
	)
	(segment
		(start 64.853312 6.801612)
		(end 64.810132 6.557518)
		(width 0.127)
		(layer "B.Cu")
		(net "P3E_CPU0_PE1_SS_C_RXN<6>")
	)
	(segment
		(start 88.952578 -12.029694)
		(end 89.079832 -11.749786)
		(width 0.127)
		(layer "B.Cu")
		(net "P3E_CPU0_PE1_SS_C_RXN<6>")
	)
	(arc
		(start 86.989666 -10.36828)
		(mid 87.87027 -10.733038)
		(end 88.235028 -11.613642)
		(width 0.127)
		(layer "B.Cu")
		(net "P3E_CPU0_PE1_SS_C_RXN<6>")
	)
	(arc
		(start 85.21954 -7.333488)
		(mid 85.288391 -7.679623)
		(end 85.484462 -7.97306)
		(width 0.127)
		(layer "B.Cu")
		(net "P3E_CPU0_PE1_SS_C_RXN<6>")
	)
	(arc
		(start 88.534748 -12.58189)
		(mid 88.631804 -12.588831)
		(end 88.705182 -12.524994)
		(width 0.127)
		(layer "B.Cu")
		(net "P3E_CPU0_PE1_SS_C_RXN<6>")
	)
	(arc
		(start 85.217 -7.1882)
		(mid 85.218898 -7.23314)
		(end 85.21954 -7.278116)
		(width 0.127)
		(layer "B.Cu")
		(net "P3E_CPU0_PE1_SS_C_RXN<6>")
	)
	(arc
		(start 82.21091 -3.647186)
		(mid 82.997161 -3.873566)
		(end 83.71205 -4.271518)
		(width 0.127)
		(layer "B.Cu")
		(net "P3E_CPU0_PE1_SS_C_RXN<6>")
	)
	(arc
		(start 63.456312 10.725912)
		(mid 63.364555 10.588777)
		(end 63.33236 10.426954)
		(width 0.127)
		(layer "B.Cu")
		(net "P3E_CPU0_PE1_SS_C_RXN<6>")
	)
	(arc
		(start 85.949536 -8.438134)
		(mid 86.149576 -8.737515)
		(end 86.219792 -9.09066)
		(width 0.127)
		(layer "B.Cu")
		(net "P3E_CPU0_PE1_SS_C_RXN<6>")
	)
	(arc
		(start 86.716362 -10.25525)
		(mid 86.84177 -10.338952)
		(end 86.989666 -10.36828)
		(width 0.127)
		(layer "B.Cu")
		(net "P3E_CPU0_PE1_SS_C_RXN<6>")
	)
	(arc
		(start 86.219792 -9.617202)
		(mid 86.245739 -9.747647)
		(end 86.319614 -9.858248)
		(width 0.127)
		(layer "B.Cu")
		(net "P3E_CPU0_PE1_SS_C_RXN<6>")
	)
	(arc
		(start 88.235028 -12.076684)
		(mid 88.283287 -12.319299)
		(end 88.420702 -12.524994)
		(width 0.127)
		(layer "B.Cu")
		(net "P3E_CPU0_PE1_SS_C_RXN<6>")
	)
	(arc
		(start 63.58001 11.024616)
		(mid 63.547857 10.86297)
		(end 63.456312 10.725912)
		(width 0.127)
		(layer "B.Cu")
		(net "P3E_CPU0_PE1_SS_C_RXN<6>")
	)
	(arc
		(start 83.71205 -4.271518)
		(mid 84.815923 -5.548556)
		(end 85.217 -7.1882)
		(width 0.127)
		(layer "B.Cu")
		(net "P3E_CPU0_PE1_SS_C_RXN<6>")
	)
	(segment
		(start 69.54139 3.104388)
		(end 67.263772 6.357112)
		(width 0.127)
		(layer "B.Cu")
		(net "P3E_CPU0_PE1_SS_C_RXN<5>")
	)
	(segment
		(start 90.716862 -10.25525)
		(end 90.320114 -9.858248)
		(width 0.127)
		(layer "B.Cu")
		(net "P3E_CPU0_PE1_SS_C_RXN<5>")
	)
	(segment
		(start 67.088512 6.913372)
		(end 66.844418 6.956298)
		(width 0.127)
		(layer "B.Cu")
		(net "P3E_CPU0_PE1_SS_C_RXN<5>")
	)
	(segment
		(start 66.844418 6.956298)
		(end 66.625724 7.268464)
		(width 0.127)
		(layer "B.Cu")
		(net "P3E_CPU0_PE1_SS_C_RXN<5>")
	)
	(segment
		(start 90.220292 -9.617202)
		(end 90.220292 -9.09066)
		(width 0.127)
		(layer "B.Cu")
		(net "P3E_CPU0_PE1_SS_C_RXN<5>")
	)
	(segment
		(start 66.668904 7.512558)
		(end 66.45021 7.824724)
		(width 0.127)
		(layer "B.Cu")
		(net "P3E_CPU0_PE1_SS_C_RXN<5>")
	)
	(segment
		(start 67.306952 6.601206)
		(end 67.088512 6.913372)
		(width 0.127)
		(layer "B.Cu")
		(net "P3E_CPU0_PE1_SS_C_RXN<5>")
	)
	(segment
		(start 93.013784 -11.908028)
		(end 92.705682 -12.524994)
		(width 0.127)
		(layer "B.Cu")
		(net "P3E_CPU0_PE1_SS_C_RXN<5>")
	)
	(segment
		(start 66.45021 7.824724)
		(end 66.206116 7.86765)
		(width 0.127)
		(layer "B.Cu")
		(net "P3E_CPU0_PE1_SS_C_RXN<5>")
	)
	(segment
		(start 67.263772 6.357112)
		(end 67.306952 6.601206)
		(width 0.127)
		(layer "B.Cu")
		(net "P3E_CPU0_PE1_SS_C_RXN<5>")
	)
	(segment
		(start 93.080332 -11.749786)
		(end 93.013784 -11.908028)
		(width 0.127)
		(layer "B.Cu")
		(net "P3E_CPU0_PE1_SS_C_RXN<5>")
	)
	(segment
		(start 88.278716 -5.014214)
		(end 85.4075 -3.00355)
		(width 0.127)
		(layer "B.Cu")
		(net "P3E_CPU0_PE1_SS_C_RXN<5>")
	)
	(segment
		(start 89.092024 -6.175756)
		(end 88.278716 -5.014214)
		(width 0.127)
		(layer "B.Cu")
		(net "P3E_CPU0_PE1_SS_C_RXN<5>")
	)
	(segment
		(start 92.535248 -12.58189)
		(end 92.534994 -12.58189)
		(width 0.127)
		(layer "B.Cu")
		(net "P3E_CPU0_PE1_SS_C_RXN<5>")
	)
	(segment
		(start 75.871578 -1.32207)
		(end 70.324218 2.557018)
		(width 0.127)
		(layer "B.Cu")
		(net "P3E_CPU0_PE1_SS_C_RXN<5>")
	)
	(segment
		(start 70.324218 2.557018)
		(end 70.321932 2.558542)
		(width 0.127)
		(layer "B.Cu")
		(net "P3E_CPU0_PE1_SS_C_RXN<5>")
	)
	(segment
		(start 92.534994 -12.58189)
		(end 92.421202 -12.524994)
		(width 0.127)
		(layer "B.Cu")
		(net "P3E_CPU0_PE1_SS_C_RXN<5>")
	)
	(segment
		(start 89.950036 -8.438134)
		(end 89.484962 -7.97306)
		(width 0.127)
		(layer "B.Cu")
		(net "P3E_CPU0_PE1_SS_C_RXN<5>")
	)
	(segment
		(start 92.235528 -12.076684)
		(end 92.235528 -11.613642)
		(width 0.127)
		(layer "B.Cu")
		(net "P3E_CPU0_PE1_SS_C_RXN<5>")
	)
	(segment
		(start 81.004156 -2.227326)
		(end 81.003648 -2.227072)
		(width 0.127)
		(layer "B.Cu")
		(net "P3E_CPU0_PE1_SS_C_RXN<5>")
	)
	(segment
		(start 65.732406 9.62787)
		(end 65.732406 10.4648)
		(width 0.127)
		(layer "B.Cu")
		(net "P3E_CPU0_PE1_SS_C_RXN<5>")
	)
	(segment
		(start 65.979802 11.062208)
		(end 65.979802 12.514072)
		(width 0.127)
		(layer "B.Cu")
		(net "P3E_CPU0_PE1_SS_C_RXN<5>")
	)
	(segment
		(start 65.987676 8.179816)
		(end 65.732406 9.62787)
		(width 0.127)
		(layer "B.Cu")
		(net "P3E_CPU0_PE1_SS_C_RXN<5>")
	)
	(segment
		(start 66.206116 7.86765)
		(end 65.987676 8.179816)
		(width 0.127)
		(layer "B.Cu")
		(net "P3E_CPU0_PE1_SS_C_RXN<5>")
	)
	(segment
		(start 85.4075 -3.00355)
		(end 81.004156 -2.227326)
		(width 0.127)
		(layer "B.Cu")
		(net "P3E_CPU0_PE1_SS_C_RXN<5>")
	)
	(segment
		(start 66.625724 7.268464)
		(end 66.668904 7.512558)
		(width 0.127)
		(layer "B.Cu")
		(net "P3E_CPU0_PE1_SS_C_RXN<5>")
	)
	(segment
		(start 70.321932 2.558542)
		(end 69.54139 3.104388)
		(width 0.127)
		(layer "B.Cu")
		(net "P3E_CPU0_PE1_SS_C_RXN<5>")
	)
	(segment
		(start 89.22004 -6.901942)
		(end 89.092024 -6.175756)
		(width 0.127)
		(layer "B.Cu")
		(net "P3E_CPU0_PE1_SS_C_RXN<5>")
	)
	(segment
		(start 81.003648 -2.227072)
		(end 75.871578 -1.32207)
		(width 0.127)
		(layer "B.Cu")
		(net "P3E_CPU0_PE1_SS_C_RXN<5>")
	)
	(segment
		(start 89.22004 -7.333488)
		(end 89.22004 -6.901942)
		(width 0.127)
		(layer "B.Cu")
		(net "P3E_CPU0_PE1_SS_C_RXN<5>")
	)
	(arc
		(start 65.856104 10.763504)
		(mid 65.947676 10.900551)
		(end 65.979802 11.062208)
		(width 0.127)
		(layer "B.Cu")
		(net "P3E_CPU0_PE1_SS_C_RXN<5>")
	)
	(arc
		(start 90.220292 -9.09066)
		(mid 90.150049 -8.737527)
		(end 89.950036 -8.438134)
		(width 0.127)
		(layer "B.Cu")
		(net "P3E_CPU0_PE1_SS_C_RXN<5>")
	)
	(arc
		(start 92.421202 -12.524994)
		(mid 92.283767 -12.319308)
		(end 92.235528 -12.076684)
		(width 0.127)
		(layer "B.Cu")
		(net "P3E_CPU0_PE1_SS_C_RXN<5>")
	)
	(arc
		(start 89.484962 -7.97306)
		(mid 89.288893 -7.679622)
		(end 89.22004 -7.333488)
		(width 0.127)
		(layer "B.Cu")
		(net "P3E_CPU0_PE1_SS_C_RXN<5>")
	)
	(arc
		(start 92.235528 -11.613642)
		(mid 91.87077 -10.733038)
		(end 90.990166 -10.36828)
		(width 0.127)
		(layer "B.Cu")
		(net "P3E_CPU0_PE1_SS_C_RXN<5>")
	)
	(arc
		(start 92.705682 -12.524994)
		(mid 92.632268 -12.588723)
		(end 92.535248 -12.58189)
		(width 0.127)
		(layer "B.Cu")
		(net "P3E_CPU0_PE1_SS_C_RXN<5>")
	)
	(arc
		(start 90.320114 -9.858248)
		(mid 90.246218 -9.747655)
		(end 90.220292 -9.617202)
		(width 0.127)
		(layer "B.Cu")
		(net "P3E_CPU0_PE1_SS_C_RXN<5>")
	)
	(arc
		(start 90.990166 -10.36828)
		(mid 90.842269 -10.338955)
		(end 90.716862 -10.25525)
		(width 0.127)
		(layer "B.Cu")
		(net "P3E_CPU0_PE1_SS_C_RXN<5>")
	)
	(arc
		(start 65.732406 10.4648)
		(mid 65.764559 10.626446)
		(end 65.856104 10.763504)
		(width 0.127)
		(layer "B.Cu")
		(net "P3E_CPU0_PE1_SS_C_RXN<5>")
	)
	(segment
		(start 68.03517 9.573768)
		(end 68.132452 10.124948)
		(width 0.127)
		(layer "B.Cu")
		(net "P3E_CPU0_PE1_SS_C_RXN<4>")
	)
	(segment
		(start 93.169232 -6.640068)
		(end 92.914216 -6.276086)
		(width 0.127)
		(layer "B.Cu")
		(net "P3E_CPU0_PE1_SS_C_RXN<4>")
	)
	(segment
		(start 81.335626 -1.08077)
		(end 76.336398 -0.19939)
		(width 0.127)
		(layer "B.Cu")
		(net "P3E_CPU0_PE1_SS_C_RXN<4>")
	)
	(segment
		(start 70.338696 4.63296)
		(end 69.919088 5.2324)
		(width 0.127)
		(layer "B.Cu")
		(net "P3E_CPU0_PE1_SS_C_RXN<4>")
	)
	(segment
		(start 76.336398 -0.19939)
		(end 76.336144 -0.19939)
		(width 0.127)
		(layer "B.Cu")
		(net "P3E_CPU0_PE1_SS_C_RXN<4>")
	)
	(segment
		(start 81.336134 -1.081024)
		(end 81.335626 -1.08077)
		(width 0.127)
		(layer "B.Cu")
		(net "P3E_CPU0_PE1_SS_C_RXN<4>")
	)
	(segment
		(start 69.062346 6.455664)
		(end 69.105526 6.699758)
		(width 0.127)
		(layer "B.Cu")
		(net "P3E_CPU0_PE1_SS_C_RXN<4>")
	)
	(segment
		(start 92.914216 -6.276086)
		(end 86.895178 -2.06121)
		(width 0.127)
		(layer "B.Cu")
		(net "P3E_CPU0_PE1_SS_C_RXN<4>")
	)
	(segment
		(start 68.374006 7.65175)
		(end 68.03517 9.573768)
		(width 0.127)
		(layer "B.Cu")
		(net "P3E_CPU0_PE1_SS_C_RXN<4>")
	)
	(segment
		(start 93.949266 -8.438134)
		(end 93.484192 -7.97306)
		(width 0.127)
		(layer "B.Cu")
		(net "P3E_CPU0_PE1_SS_C_RXN<4>")
	)
	(segment
		(start 69.700648 5.544312)
		(end 69.743574 5.788406)
		(width 0.127)
		(layer "B.Cu")
		(net "P3E_CPU0_PE1_SS_C_RXN<4>")
	)
	(segment
		(start 68.886832 7.011924)
		(end 68.642738 7.05485)
		(width 0.127)
		(layer "B.Cu")
		(net "P3E_CPU0_PE1_SS_C_RXN<4>")
	)
	(segment
		(start 68.379848 11.125454)
		(end 68.379848 12.514072)
		(width 0.127)
		(layer "B.Cu")
		(net "P3E_CPU0_PE1_SS_C_RXN<4>")
	)
	(segment
		(start 96.534224 -12.58189)
		(end 96.420432 -12.524994)
		(width 0.127)
		(layer "B.Cu")
		(net "P3E_CPU0_PE1_SS_C_RXN<4>")
	)
	(segment
		(start 72.557386 2.443226)
		(end 72.37603 2.57429)
		(width 0.127)
		(layer "B.Cu")
		(net "P3E_CPU0_PE1_SS_C_RXN<4>")
	)
	(segment
		(start 69.28104 6.143498)
		(end 69.062346 6.455664)
		(width 0.127)
		(layer "B.Cu")
		(net "P3E_CPU0_PE1_SS_C_RXN<4>")
	)
	(segment
		(start 94.219522 -9.617202)
		(end 94.219522 -9.09066)
		(width 0.127)
		(layer "B.Cu")
		(net "P3E_CPU0_PE1_SS_C_RXN<4>")
	)
	(segment
		(start 96.534478 -12.58189)
		(end 96.534224 -12.58189)
		(width 0.127)
		(layer "B.Cu")
		(net "P3E_CPU0_PE1_SS_C_RXN<4>")
	)
	(segment
		(start 68.132452 10.124948)
		(end 68.132452 10.528046)
		(width 0.127)
		(layer "B.Cu")
		(net "P3E_CPU0_PE1_SS_C_RXN<4>")
	)
	(segment
		(start 69.743574 5.788406)
		(end 69.525134 6.100572)
		(width 0.127)
		(layer "B.Cu")
		(net "P3E_CPU0_PE1_SS_C_RXN<4>")
	)
	(segment
		(start 69.525134 6.100572)
		(end 69.28104 6.143498)
		(width 0.127)
		(layer "B.Cu")
		(net "P3E_CPU0_PE1_SS_C_RXN<4>")
	)
	(segment
		(start 68.424298 7.367016)
		(end 68.374006 7.65175)
		(width 0.127)
		(layer "B.Cu")
		(net "P3E_CPU0_PE1_SS_C_RXN<4>")
	)
	(segment
		(start 69.919088 5.2324)
		(end 69.700648 5.544312)
		(width 0.127)
		(layer "B.Cu")
		(net "P3E_CPU0_PE1_SS_C_RXN<4>")
	)
	(segment
		(start 86.895178 -2.06121)
		(end 85.805772 -1.869186)
		(width 0.127)
		(layer "B.Cu")
		(net "P3E_CPU0_PE1_SS_C_RXN<4>")
	)
	(segment
		(start 85.805772 -1.869186)
		(end 81.336134 -1.081024)
		(width 0.127)
		(layer "B.Cu")
		(net "P3E_CPU0_PE1_SS_C_RXN<4>")
	)
	(segment
		(start 93.204538 -6.956806)
		(end 93.204538 -6.956552)
		(width 0.127)
		(layer "B.Cu")
		(net "P3E_CPU0_PE1_SS_C_RXN<4>")
	)
	(segment
		(start 97.034096 -11.865864)
		(end 96.704912 -12.524994)
		(width 0.127)
		(layer "B.Cu")
		(net "P3E_CPU0_PE1_SS_C_RXN<4>")
	)
	(segment
		(start 70.648322 4.190746)
		(end 70.338696 4.63296)
		(width 0.127)
		(layer "B.Cu")
		(net "P3E_CPU0_PE1_SS_C_RXN<4>")
	)
	(segment
		(start 69.105526 6.699758)
		(end 68.886832 7.011924)
		(width 0.127)
		(layer "B.Cu")
		(net "P3E_CPU0_PE1_SS_C_RXN<4>")
	)
	(segment
		(start 96.234758 -12.076684)
		(end 96.234758 -11.613642)
		(width 0.127)
		(layer "B.Cu")
		(net "P3E_CPU0_PE1_SS_C_RXN<4>")
	)
	(segment
		(start 68.642738 7.05485)
		(end 68.424298 7.367016)
		(width 0.127)
		(layer "B.Cu")
		(net "P3E_CPU0_PE1_SS_C_RXN<4>")
	)
	(segment
		(start 97.079562 -11.749786)
		(end 97.034096 -11.865864)
		(width 0.127)
		(layer "B.Cu")
		(net "P3E_CPU0_PE1_SS_C_RXN<4>")
	)
	(segment
		(start 94.716092 -10.25525)
		(end 94.319344 -9.858248)
		(width 0.127)
		(layer "B.Cu")
		(net "P3E_CPU0_PE1_SS_C_RXN<4>")
	)
	(segment
		(start 72.37603 2.57429)
		(end 70.648322 4.190746)
		(width 0.127)
		(layer "B.Cu")
		(net "P3E_CPU0_PE1_SS_C_RXN<4>")
	)
	(segment
		(start 76.336144 -0.19939)
		(end 72.557386 2.443226)
		(width 0.127)
		(layer "B.Cu")
		(net "P3E_CPU0_PE1_SS_C_RXN<4>")
	)
	(arc
		(start 93.204538 -6.956552)
		(mid 93.189493 -6.798019)
		(end 93.169232 -6.640068)
		(width 0.127)
		(layer "B.Cu")
		(net "P3E_CPU0_PE1_SS_C_RXN<4>")
	)
	(arc
		(start 96.234758 -11.613642)
		(mid 95.87 -10.733038)
		(end 94.989396 -10.36828)
		(width 0.127)
		(layer "B.Cu")
		(net "P3E_CPU0_PE1_SS_C_RXN<4>")
	)
	(arc
		(start 96.704912 -12.524994)
		(mid 96.631498 -12.588723)
		(end 96.534478 -12.58189)
		(width 0.127)
		(layer "B.Cu")
		(net "P3E_CPU0_PE1_SS_C_RXN<4>")
	)
	(arc
		(start 94.219522 -9.09066)
		(mid 94.149279 -8.737527)
		(end 93.949266 -8.438134)
		(width 0.127)
		(layer "B.Cu")
		(net "P3E_CPU0_PE1_SS_C_RXN<4>")
	)
	(arc
		(start 68.132452 10.528046)
		(mid 68.164605 10.689692)
		(end 68.25615 10.82675)
		(width 0.127)
		(layer "B.Cu")
		(net "P3E_CPU0_PE1_SS_C_RXN<4>")
	)
	(arc
		(start 94.989396 -10.36828)
		(mid 94.841499 -10.338955)
		(end 94.716092 -10.25525)
		(width 0.127)
		(layer "B.Cu")
		(net "P3E_CPU0_PE1_SS_C_RXN<4>")
	)
	(arc
		(start 93.484192 -7.97306)
		(mid 93.288123 -7.679622)
		(end 93.21927 -7.333488)
		(width 0.127)
		(layer "B.Cu")
		(net "P3E_CPU0_PE1_SS_C_RXN<4>")
	)
	(arc
		(start 94.319344 -9.858248)
		(mid 94.245448 -9.747655)
		(end 94.219522 -9.617202)
		(width 0.127)
		(layer "B.Cu")
		(net "P3E_CPU0_PE1_SS_C_RXN<4>")
	)
	(arc
		(start 96.420432 -12.524994)
		(mid 96.282997 -12.319308)
		(end 96.234758 -12.076684)
		(width 0.127)
		(layer "B.Cu")
		(net "P3E_CPU0_PE1_SS_C_RXN<4>")
	)
	(arc
		(start 93.21927 -7.333488)
		(mid 93.215577 -7.145003)
		(end 93.204538 -6.956806)
		(width 0.127)
		(layer "B.Cu")
		(net "P3E_CPU0_PE1_SS_C_RXN<4>")
	)
	(arc
		(start 68.25615 10.82675)
		(mid 68.347722 10.963797)
		(end 68.379848 11.125454)
		(width 0.127)
		(layer "B.Cu")
		(net "P3E_CPU0_PE1_SS_C_RXN<4>")
	)
	(segment
		(start 100.534978 -12.58189)
		(end 100.534724 -12.58189)
		(width 0.127)
		(layer "B.Cu")
		(net "P3E_CPU0_PE1_SS_C_RXN<3>")
	)
	(segment
		(start 95.287084 -5.061712)
		(end 90.123518 -1.621282)
		(width 0.127)
		(layer "B.Cu")
		(net "P3E_CPU0_PE1_SS_C_RXN<3>")
	)
	(segment
		(start 90.123518 -1.621282)
		(end 89.491058 -1.359408)
		(width 0.127)
		(layer "B.Cu")
		(net "P3E_CPU0_PE1_SS_C_RXN<3>")
	)
	(segment
		(start 97.949766 -8.438134)
		(end 97.484692 -7.97306)
		(width 0.127)
		(layer "B.Cu")
		(net "P3E_CPU0_PE1_SS_C_RXN<3>")
	)
	(segment
		(start 70.779894 11.0363)
		(end 70.779894 12.514072)
		(width 0.127)
		(layer "B.Cu")
		(net "P3E_CPU0_PE1_SS_C_RXN<3>")
	)
	(segment
		(start 70.696074 7.91083)
		(end 70.6247 8.284972)
		(width 0.127)
		(layer "B.Cu")
		(net "P3E_CPU0_PE1_SS_C_RXN<3>")
	)
	(segment
		(start 75.005438 2.180844)
		(end 73.227184 3.425444)
		(width 0.127)
		(layer "B.Cu")
		(net "P3E_CPU0_PE1_SS_C_RXN<3>")
	)
	(segment
		(start 100.235258 -12.076684)
		(end 100.235258 -11.613642)
		(width 0.127)
		(layer "B.Cu")
		(net "P3E_CPU0_PE1_SS_C_RXN<3>")
	)
	(segment
		(start 76.801472 0.923544)
		(end 75.005438 2.180844)
		(width 0.127)
		(layer "B.Cu")
		(net "P3E_CPU0_PE1_SS_C_RXN<3>")
	)
	(segment
		(start 70.6247 8.284972)
		(end 70.764146 8.48995)
		(width 0.127)
		(layer "B.Cu")
		(net "P3E_CPU0_PE1_SS_C_RXN<3>")
	)
	(segment
		(start 73.227184 3.425444)
		(end 71.0057 6.2865)
		(width 0.127)
		(layer "B.Cu")
		(net "P3E_CPU0_PE1_SS_C_RXN<3>")
	)
	(segment
		(start 70.531482 10.437876)
		(end 70.532244 10.438638)
		(width 0.127)
		(layer "B.Cu")
		(net "P3E_CPU0_PE1_SS_C_RXN<3>")
	)
	(segment
		(start 100.534724 -12.58189)
		(end 100.420932 -12.524994)
		(width 0.127)
		(layer "B.Cu")
		(net "P3E_CPU0_PE1_SS_C_RXN<3>")
	)
	(segment
		(start 70.764146 8.48995)
		(end 70.692772 8.864346)
		(width 0.127)
		(layer "B.Cu")
		(net "P3E_CPU0_PE1_SS_C_RXN<3>")
	)
	(segment
		(start 98.716592 -10.25525)
		(end 98.319844 -9.858248)
		(width 0.127)
		(layer "B.Cu")
		(net "P3E_CPU0_PE1_SS_C_RXN<3>")
	)
	(segment
		(start 70.692772 8.864346)
		(end 70.487794 9.003792)
		(width 0.127)
		(layer "B.Cu")
		(net "P3E_CPU0_PE1_SS_C_RXN<3>")
	)
	(segment
		(start 70.529704 10.423652)
		(end 70.531482 10.437876)
		(width 0.127)
		(layer "B.Cu")
		(net "P3E_CPU0_PE1_SS_C_RXN<3>")
	)
	(segment
		(start 88.926924 -1.218692)
		(end 87.821008 -1.018794)
		(width 0.127)
		(layer "B.Cu")
		(net "P3E_CPU0_PE1_SS_C_RXN<3>")
	)
	(segment
		(start 97.21977 -7.307072)
		(end 97.071434 -6.465062)
		(width 0.127)
		(layer "B.Cu")
		(net "P3E_CPU0_PE1_SS_C_RXN<3>")
	)
	(segment
		(start 70.41642 9.377934)
		(end 70.527926 10.406634)
		(width 0.127)
		(layer "B.Cu")
		(net "P3E_CPU0_PE1_SS_C_RXN<3>")
	)
	(segment
		(start 98.220022 -9.617202)
		(end 98.220022 -9.09066)
		(width 0.127)
		(layer "B.Cu")
		(net "P3E_CPU0_PE1_SS_C_RXN<3>")
	)
	(segment
		(start 76.801472 0.92329)
		(end 76.801472 0.923544)
		(width 0.127)
		(layer "B.Cu")
		(net "P3E_CPU0_PE1_SS_C_RXN<3>")
	)
	(segment
		(start 87.059008 -0.884428)
		(end 76.801472 0.92329)
		(width 0.127)
		(layer "B.Cu")
		(net "P3E_CPU0_PE1_SS_C_RXN<3>")
	)
	(segment
		(start 97.220024 -7.333742)
		(end 97.21977 -7.307072)
		(width 0.127)
		(layer "B.Cu")
		(net "P3E_CPU0_PE1_SS_C_RXN<3>")
	)
	(segment
		(start 97.071434 -6.465062)
		(end 96.860106 -6.163056)
		(width 0.127)
		(layer "B.Cu")
		(net "P3E_CPU0_PE1_SS_C_RXN<3>")
	)
	(segment
		(start 70.529958 10.423652)
		(end 70.529704 10.423652)
		(width 0.127)
		(layer "B.Cu")
		(net "P3E_CPU0_PE1_SS_C_RXN<3>")
	)
	(segment
		(start 87.821008 -1.018794)
		(end 87.059008 -0.884428)
		(width 0.127)
		(layer "B.Cu")
		(net "P3E_CPU0_PE1_SS_C_RXN<3>")
	)
	(segment
		(start 70.487794 9.003792)
		(end 70.41642 9.377934)
		(width 0.127)
		(layer "B.Cu")
		(net "P3E_CPU0_PE1_SS_C_RXN<3>")
	)
	(segment
		(start 70.972426 7.397242)
		(end 70.901052 7.771384)
		(width 0.127)
		(layer "B.Cu")
		(net "P3E_CPU0_PE1_SS_C_RXN<3>")
	)
	(segment
		(start 89.491058 -1.359408)
		(end 88.926924 -1.218692)
		(width 0.127)
		(layer "B.Cu")
		(net "P3E_CPU0_PE1_SS_C_RXN<3>")
	)
	(segment
		(start 101.014276 -11.90625)
		(end 100.705412 -12.524994)
		(width 0.127)
		(layer "B.Cu")
		(net "P3E_CPU0_PE1_SS_C_RXN<3>")
	)
	(segment
		(start 71.0057 6.2865)
		(end 70.83298 7.192264)
		(width 0.127)
		(layer "B.Cu")
		(net "P3E_CPU0_PE1_SS_C_RXN<3>")
	)
	(segment
		(start 101.080062 -11.749786)
		(end 101.014276 -11.90625)
		(width 0.127)
		(layer "B.Cu")
		(net "P3E_CPU0_PE1_SS_C_RXN<3>")
	)
	(segment
		(start 70.83298 7.192264)
		(end 70.972426 7.397242)
		(width 0.127)
		(layer "B.Cu")
		(net "P3E_CPU0_PE1_SS_C_RXN<3>")
	)
	(segment
		(start 70.901052 7.771384)
		(end 70.696074 7.91083)
		(width 0.127)
		(layer "B.Cu")
		(net "P3E_CPU0_PE1_SS_C_RXN<3>")
	)
	(segment
		(start 96.860106 -6.163056)
		(end 95.287084 -5.061712)
		(width 0.127)
		(layer "B.Cu")
		(net "P3E_CPU0_PE1_SS_C_RXN<3>")
	)
	(arc
		(start 98.989896 -10.36828)
		(mid 98.841999 -10.338955)
		(end 98.716592 -10.25525)
		(width 0.127)
		(layer "B.Cu")
		(net "P3E_CPU0_PE1_SS_C_RXN<3>")
	)
	(arc
		(start 70.656196 10.737596)
		(mid 70.747768 10.874643)
		(end 70.779894 11.0363)
		(width 0.127)
		(layer "B.Cu")
		(net "P3E_CPU0_PE1_SS_C_RXN<3>")
	)
	(arc
		(start 70.532244 10.438638)
		(mid 70.564466 10.60045)
		(end 70.656196 10.737596)
		(width 0.127)
		(layer "B.Cu")
		(net "P3E_CPU0_PE1_SS_C_RXN<3>")
	)
	(arc
		(start 100.235258 -11.613642)
		(mid 99.8705 -10.733038)
		(end 98.989896 -10.36828)
		(width 0.127)
		(layer "B.Cu")
		(net "P3E_CPU0_PE1_SS_C_RXN<3>")
	)
	(arc
		(start 97.484692 -7.97306)
		(mid 97.288808 -7.67971)
		(end 97.220024 -7.333742)
		(width 0.127)
		(layer "B.Cu")
		(net "P3E_CPU0_PE1_SS_C_RXN<3>")
	)
	(arc
		(start 70.527926 10.406634)
		(mid 70.529002 10.415136)
		(end 70.529958 10.423652)
		(width 0.127)
		(layer "B.Cu")
		(net "P3E_CPU0_PE1_SS_C_RXN<3>")
	)
	(arc
		(start 98.220022 -9.09066)
		(mid 98.149779 -8.737527)
		(end 97.949766 -8.438134)
		(width 0.127)
		(layer "B.Cu")
		(net "P3E_CPU0_PE1_SS_C_RXN<3>")
	)
	(arc
		(start 98.319844 -9.858248)
		(mid 98.245948 -9.747655)
		(end 98.220022 -9.617202)
		(width 0.127)
		(layer "B.Cu")
		(net "P3E_CPU0_PE1_SS_C_RXN<3>")
	)
	(arc
		(start 100.705412 -12.524994)
		(mid 100.631998 -12.588723)
		(end 100.534978 -12.58189)
		(width 0.127)
		(layer "B.Cu")
		(net "P3E_CPU0_PE1_SS_C_RXN<3>")
	)
	(arc
		(start 100.420932 -12.524994)
		(mid 100.283497 -12.319308)
		(end 100.235258 -12.076684)
		(width 0.127)
		(layer "B.Cu")
		(net "P3E_CPU0_PE1_SS_C_RXN<3>")
	)
	(segment
		(start 102.219252 -9.617202)
		(end 102.219252 -9.09066)
		(width 0.127)
		(layer "B.Cu")
		(net "P3E_CPU0_PE1_SS_C_RXN<2>")
	)
	(segment
		(start 89.863676 -0.229616)
		(end 88.764872 0.044704)
		(width 0.127)
		(layer "B.Cu")
		(net "P3E_CPU0_PE1_SS_C_RXN<2>")
	)
	(segment
		(start 101.219 -7.333488)
		(end 101.219 -6.90118)
		(width 0.127)
		(layer "B.Cu")
		(net "P3E_CPU0_PE1_SS_C_RXN<2>")
	)
	(segment
		(start 74.082148 4.644136)
		(end 74.073512 4.656328)
		(width 0.127)
		(layer "B.Cu")
		(net "P3E_CPU0_PE1_SS_C_RXN<2>")
	)
	(segment
		(start 95.803212 -3.808476)
		(end 94.855284 -3.138932)
		(width 0.127)
		(layer "B.Cu")
		(net "P3E_CPU0_PE1_SS_C_RXN<2>")
	)
	(segment
		(start 77.350366 2.07264)
		(end 74.562716 3.957574)
		(width 0.127)
		(layer "B.Cu")
		(net "P3E_CPU0_PE1_SS_C_RXN<2>")
	)
	(segment
		(start 105.079292 -11.749786)
		(end 104.903778 -12.126214)
		(width 0.127)
		(layer "B.Cu")
		(net "P3E_CPU0_PE1_SS_C_RXN<2>")
	)
	(segment
		(start 77.64018 2.008124)
		(end 77.60843 2.008124)
		(width 0.127)
		(layer "B.Cu")
		(net "P3E_CPU0_PE1_SS_C_RXN<2>")
	)
	(segment
		(start 94.855284 -3.138932)
		(end 94.260924 -2.719324)
		(width 0.127)
		(layer "B.Cu")
		(net "P3E_CPU0_PE1_SS_C_RXN<2>")
	)
	(segment
		(start 102.715822 -10.25525)
		(end 102.319074 -9.858248)
		(width 0.127)
		(layer "B.Cu")
		(net "P3E_CPU0_PE1_SS_C_RXN<2>")
	)
	(segment
		(start 73.435464 5.56768)
		(end 73.478644 5.811774)
		(width 0.127)
		(layer "B.Cu")
		(net "P3E_CPU0_PE1_SS_C_RXN<2>")
	)
	(segment
		(start 95.82912 -3.82651)
		(end 95.827596 -3.825494)
		(width 0.127)
		(layer "B.Cu")
		(net "P3E_CPU0_PE1_SS_C_RXN<2>")
	)
	(segment
		(start 72.530716 7.991602)
		(end 72.9107 10.1473)
		(width 0.127)
		(layer "B.Cu")
		(net "P3E_CPU0_PE1_SS_C_RXN<2>")
	)
	(segment
		(start 74.116692 4.900422)
		(end 73.897998 5.212588)
		(width 0.127)
		(layer "B.Cu")
		(net "P3E_CPU0_PE1_SS_C_RXN<2>")
	)
	(segment
		(start 77.60843 2.008124)
		(end 77.350366 2.07264)
		(width 0.127)
		(layer "B.Cu")
		(net "P3E_CPU0_PE1_SS_C_RXN<2>")
	)
	(segment
		(start 88.764872 0.044704)
		(end 88.081104 0.165354)
		(width 0.127)
		(layer "B.Cu")
		(net "P3E_CPU0_PE1_SS_C_RXN<2>")
	)
	(segment
		(start 104.534208 -12.58189)
		(end 104.533954 -12.58189)
		(width 0.127)
		(layer "B.Cu")
		(net "P3E_CPU0_PE1_SS_C_RXN<2>")
	)
	(segment
		(start 101.948996 -8.438134)
		(end 101.483922 -7.97306)
		(width 0.127)
		(layer "B.Cu")
		(net "P3E_CPU0_PE1_SS_C_RXN<2>")
	)
	(segment
		(start 73.897998 5.212588)
		(end 73.653904 5.255514)
		(width 0.127)
		(layer "B.Cu")
		(net "P3E_CPU0_PE1_SS_C_RXN<2>")
	)
	(segment
		(start 104.533954 -12.58189)
		(end 104.420162 -12.524994)
		(width 0.127)
		(layer "B.Cu")
		(net "P3E_CPU0_PE1_SS_C_RXN<2>")
	)
	(segment
		(start 73.17994 10.9982)
		(end 73.17994 12.514072)
		(width 0.127)
		(layer "B.Cu")
		(net "P3E_CPU0_PE1_SS_C_RXN<2>")
	)
	(segment
		(start 95.833692 -3.829812)
		(end 95.82912 -3.82651)
		(width 0.127)
		(layer "B.Cu")
		(net "P3E_CPU0_PE1_SS_C_RXN<2>")
	)
	(segment
		(start 104.234488 -12.076684)
		(end 104.234488 -11.613642)
		(width 0.127)
		(layer "B.Cu")
		(net "P3E_CPU0_PE1_SS_C_RXN<2>")
	)
	(segment
		(start 91.970352 -1.101598)
		(end 89.863676 -0.229616)
		(width 0.127)
		(layer "B.Cu")
		(net "P3E_CPU0_PE1_SS_C_RXN<2>")
	)
	(segment
		(start 94.260924 -2.719324)
		(end 91.970352 -1.101598)
		(width 0.127)
		(layer "B.Cu")
		(net "P3E_CPU0_PE1_SS_C_RXN<2>")
	)
	(segment
		(start 104.903778 -12.126214)
		(end 104.704642 -12.524994)
		(width 0.127)
		(layer "B.Cu")
		(net "P3E_CPU0_PE1_SS_C_RXN<2>")
	)
	(segment
		(start 72.5424 7.9248)
		(end 72.530716 7.991602)
		(width 0.127)
		(layer "B.Cu")
		(net "P3E_CPU0_PE1_SS_C_RXN<2>")
	)
	(segment
		(start 95.827596 -3.825494)
		(end 95.803212 -3.808476)
		(width 0.127)
		(layer "B.Cu")
		(net "P3E_CPU0_PE1_SS_C_RXN<2>")
	)
	(segment
		(start 74.073512 4.656328)
		(end 74.116692 4.900422)
		(width 0.127)
		(layer "B.Cu")
		(net "P3E_CPU0_PE1_SS_C_RXN<2>")
	)
	(segment
		(start 100.457 -6.0452)
		(end 98.706178 -5.840984)
		(width 0.127)
		(layer "B.Cu")
		(net "P3E_CPU0_PE1_SS_C_RXN<2>")
	)
	(segment
		(start 73.478644 5.811774)
		(end 73.25995 6.12394)
		(width 0.127)
		(layer "B.Cu")
		(net "P3E_CPU0_PE1_SS_C_RXN<2>")
	)
	(segment
		(start 74.562716 3.957574)
		(end 74.082148 4.644136)
		(width 0.127)
		(layer "B.Cu")
		(net "P3E_CPU0_PE1_SS_C_RXN<2>")
	)
	(segment
		(start 98.706178 -5.840984)
		(end 95.833692 -3.829812)
		(width 0.127)
		(layer "B.Cu")
		(net "P3E_CPU0_PE1_SS_C_RXN<2>")
	)
	(segment
		(start 72.9107 10.1473)
		(end 72.93229 10.400284)
		(width 0.127)
		(layer "B.Cu")
		(net "P3E_CPU0_PE1_SS_C_RXN<2>")
	)
	(segment
		(start 72.797416 6.479032)
		(end 72.5424 7.9248)
		(width 0.127)
		(layer "B.Cu")
		(net "P3E_CPU0_PE1_SS_C_RXN<2>")
	)
	(segment
		(start 73.25995 6.12394)
		(end 73.015856 6.166866)
		(width 0.127)
		(layer "B.Cu")
		(net "P3E_CPU0_PE1_SS_C_RXN<2>")
	)
	(segment
		(start 73.015856 6.166866)
		(end 72.797416 6.479032)
		(width 0.127)
		(layer "B.Cu")
		(net "P3E_CPU0_PE1_SS_C_RXN<2>")
	)
	(segment
		(start 88.081104 0.165354)
		(end 77.64018 2.008124)
		(width 0.127)
		(layer "B.Cu")
		(net "P3E_CPU0_PE1_SS_C_RXN<2>")
	)
	(segment
		(start 73.653904 5.255514)
		(end 73.435464 5.56768)
		(width 0.127)
		(layer "B.Cu")
		(net "P3E_CPU0_PE1_SS_C_RXN<2>")
	)
	(arc
		(start 104.234488 -11.613642)
		(mid 103.86973 -10.733038)
		(end 102.989126 -10.36828)
		(width 0.127)
		(layer "B.Cu")
		(net "P3E_CPU0_PE1_SS_C_RXN<2>")
	)
	(arc
		(start 102.989126 -10.36828)
		(mid 102.841229 -10.338955)
		(end 102.715822 -10.25525)
		(width 0.127)
		(layer "B.Cu")
		(net "P3E_CPU0_PE1_SS_C_RXN<2>")
	)
	(arc
		(start 73.055988 10.698988)
		(mid 73.147715 10.836268)
		(end 73.17994 10.9982)
		(width 0.127)
		(layer "B.Cu")
		(net "P3E_CPU0_PE1_SS_C_RXN<2>")
	)
	(arc
		(start 72.93229 10.400284)
		(mid 72.964443 10.56193)
		(end 73.055988 10.698988)
		(width 0.127)
		(layer "B.Cu")
		(net "P3E_CPU0_PE1_SS_C_RXN<2>")
	)
	(arc
		(start 104.420162 -12.524994)
		(mid 104.282727 -12.319308)
		(end 104.234488 -12.076684)
		(width 0.127)
		(layer "B.Cu")
		(net "P3E_CPU0_PE1_SS_C_RXN<2>")
	)
	(arc
		(start 102.219252 -9.09066)
		(mid 102.149009 -8.737527)
		(end 101.948996 -8.438134)
		(width 0.127)
		(layer "B.Cu")
		(net "P3E_CPU0_PE1_SS_C_RXN<2>")
	)
	(arc
		(start 101.219 -6.90118)
		(mid 101.000905 -6.32816)
		(end 100.457 -6.0452)
		(width 0.127)
		(layer "B.Cu")
		(net "P3E_CPU0_PE1_SS_C_RXN<2>")
	)
	(arc
		(start 101.483922 -7.97306)
		(mid 101.287853 -7.679622)
		(end 101.219 -7.333488)
		(width 0.127)
		(layer "B.Cu")
		(net "P3E_CPU0_PE1_SS_C_RXN<2>")
	)
	(arc
		(start 104.704642 -12.524994)
		(mid 104.631228 -12.588723)
		(end 104.534208 -12.58189)
		(width 0.127)
		(layer "B.Cu")
		(net "P3E_CPU0_PE1_SS_C_RXN<2>")
	)
	(arc
		(start 102.319074 -9.858248)
		(mid 102.245178 -9.747655)
		(end 102.219252 -9.617202)
		(width 0.127)
		(layer "B.Cu")
		(net "P3E_CPU0_PE1_SS_C_RXN<2>")
	)
	(segment
		(start 106.219752 -9.09066)
		(end 106.219752 -9.617202)
		(width 0.127)
		(layer "B.Cu")
		(net "P3E_CPU0_PE1_SS_C_RXN<1>")
	)
	(segment
		(start 99.104958 -4.512818)
		(end 99.475544 -4.578096)
		(width 0.127)
		(layer "B.Cu")
		(net "P3E_CPU0_PE1_SS_C_RXN<1>")
	)
	(segment
		(start 75.02271 8.656066)
		(end 74.956416 8.280654)
		(width 0.127)
		(layer "B.Cu")
		(net "P3E_CPU0_PE1_SS_C_RXN<1>")
	)
	(segment
		(start 74.763376 7.185152)
		(end 75.024742 5.702808)
		(width 0.127)
		(layer "B.Cu")
		(net "P3E_CPU0_PE1_SS_C_RXN<1>")
	)
	(segment
		(start 75.856084 4.515358)
		(end 77.735938 3.244088)
		(width 0.127)
		(layer "B.Cu")
		(net "P3E_CPU0_PE1_SS_C_RXN<1>")
	)
	(segment
		(start 92.961714 -0.227584)
		(end 92.991686 -0.24003)
		(width 0.127)
		(layer "B.Cu")
		(net "P3E_CPU0_PE1_SS_C_RXN<1>")
	)
	(segment
		(start 108.234988 -11.613642)
		(end 108.234988 -12.076684)
		(width 0.127)
		(layer "B.Cu")
		(net "P3E_CPU0_PE1_SS_C_RXN<1>")
	)
	(segment
		(start 75.032616 7.70255)
		(end 74.829416 7.56031)
		(width 0.127)
		(layer "B.Cu")
		(net "P3E_CPU0_PE1_SS_C_RXN<1>")
	)
	(segment
		(start 75.225656 8.798052)
		(end 75.02271 8.656066)
		(width 0.127)
		(layer "B.Cu")
		(net "P3E_CPU0_PE1_SS_C_RXN<1>")
	)
	(segment
		(start 105.484422 -7.97306)
		(end 105.949496 -8.438134)
		(width 0.127)
		(layer "B.Cu")
		(net "P3E_CPU0_PE1_SS_C_RXN<1>")
	)
	(segment
		(start 101.1682 -4.8768)
		(end 101.833172 -5.342382)
		(width 0.127)
		(layer "B.Cu")
		(net "P3E_CPU0_PE1_SS_C_RXN<1>")
	)
	(segment
		(start 77.996796 3.149854)
		(end 89.850468 1.060196)
		(width 0.127)
		(layer "B.Cu")
		(net "P3E_CPU0_PE1_SS_C_RXN<1>")
	)
	(segment
		(start 77.832204 3.17881)
		(end 77.996796 3.149854)
		(width 0.127)
		(layer "B.Cu")
		(net "P3E_CPU0_PE1_SS_C_RXN<1>")
	)
	(segment
		(start 108.705142 -12.524994)
		(end 108.963714 -12.007342)
		(width 0.127)
		(layer "B.Cu")
		(net "P3E_CPU0_PE1_SS_C_RXN<1>")
	)
	(segment
		(start 106.319574 -9.858248)
		(end 106.716322 -10.25525)
		(width 0.127)
		(layer "B.Cu")
		(net "P3E_CPU0_PE1_SS_C_RXN<1>")
	)
	(segment
		(start 75.098656 8.077708)
		(end 75.032616 7.70255)
		(width 0.127)
		(layer "B.Cu")
		(net "P3E_CPU0_PE1_SS_C_RXN<1>")
	)
	(segment
		(start 75.14971 9.37641)
		(end 75.29195 9.173464)
		(width 0.127)
		(layer "B.Cu")
		(net "P3E_CPU0_PE1_SS_C_RXN<1>")
	)
	(segment
		(start 101.833172 -5.342382)
		(end 104.3686 -5.9436)
		(width 0.127)
		(layer "B.Cu")
		(net "P3E_CPU0_PE1_SS_C_RXN<1>")
	)
	(segment
		(start 75.29195 9.173464)
		(end 75.225656 8.798052)
		(width 0.127)
		(layer "B.Cu")
		(net "P3E_CPU0_PE1_SS_C_RXN<1>")
	)
	(segment
		(start 89.850468 1.060196)
		(end 92.961714 -0.227584)
		(width 0.127)
		(layer "B.Cu")
		(net "P3E_CPU0_PE1_SS_C_RXN<1>")
	)
	(segment
		(start 74.956416 8.280654)
		(end 75.098656 8.077708)
		(width 0.127)
		(layer "B.Cu")
		(net "P3E_CPU0_PE1_SS_C_RXN<1>")
	)
	(segment
		(start 92.991686 -0.24003)
		(end 99.104958 -4.512818)
		(width 0.127)
		(layer "B.Cu")
		(net "P3E_CPU0_PE1_SS_C_RXN<1>")
	)
	(segment
		(start 108.963714 -12.007342)
		(end 109.079792 -11.749786)
		(width 0.127)
		(layer "B.Cu")
		(net "P3E_CPU0_PE1_SS_C_RXN<1>")
	)
	(segment
		(start 77.735938 3.244088)
		(end 77.832204 3.17881)
		(width 0.127)
		(layer "B.Cu")
		(net "P3E_CPU0_PE1_SS_C_RXN<1>")
	)
	(segment
		(start 75.332336 10.412476)
		(end 75.14971 9.37641)
		(width 0.127)
		(layer "B.Cu")
		(net "P3E_CPU0_PE1_SS_C_RXN<1>")
	)
	(segment
		(start 74.829416 7.56031)
		(end 74.763376 7.185152)
		(width 0.127)
		(layer "B.Cu")
		(net "P3E_CPU0_PE1_SS_C_RXN<1>")
	)
	(segment
		(start 75.024742 5.702808)
		(end 75.42911 5.12572)
		(width 0.127)
		(layer "B.Cu")
		(net "P3E_CPU0_PE1_SS_C_RXN<1>")
	)
	(segment
		(start 75.42911 5.12572)
		(end 75.856084 4.515358)
		(width 0.127)
		(layer "B.Cu")
		(net "P3E_CPU0_PE1_SS_C_RXN<1>")
	)
	(segment
		(start 75.579986 12.514072)
		(end 75.579986 11.010392)
		(width 0.127)
		(layer "B.Cu")
		(net "P3E_CPU0_PE1_SS_C_RXN<1>")
	)
	(segment
		(start 108.534454 -12.58189)
		(end 108.534708 -12.58189)
		(width 0.127)
		(layer "B.Cu")
		(net "P3E_CPU0_PE1_SS_C_RXN<1>")
	)
	(segment
		(start 99.475544 -4.578096)
		(end 101.1682 -4.8768)
		(width 0.127)
		(layer "B.Cu")
		(net "P3E_CPU0_PE1_SS_C_RXN<1>")
	)
	(segment
		(start 108.420662 -12.524994)
		(end 108.534454 -12.58189)
		(width 0.127)
		(layer "B.Cu")
		(net "P3E_CPU0_PE1_SS_C_RXN<1>")
	)
	(arc
		(start 104.3686 -5.9436)
		(mid 105.046971 -6.410902)
		(end 105.2322 -7.2136)
		(width 0.127)
		(layer "B.Cu")
		(net "P3E_CPU0_PE1_SS_C_RXN<1>")
	)
	(arc
		(start 75.579986 11.010392)
		(mid 75.547833 10.848746)
		(end 75.456288 10.711688)
		(width 0.127)
		(layer "B.Cu")
		(net "P3E_CPU0_PE1_SS_C_RXN<1>")
	)
	(arc
		(start 106.219752 -9.617202)
		(mid 106.245699 -9.747647)
		(end 106.319574 -9.858248)
		(width 0.127)
		(layer "B.Cu")
		(net "P3E_CPU0_PE1_SS_C_RXN<1>")
	)
	(arc
		(start 75.456288 10.711688)
		(mid 75.364561 10.574408)
		(end 75.332336 10.412476)
		(width 0.127)
		(layer "B.Cu")
		(net "P3E_CPU0_PE1_SS_C_RXN<1>")
	)
	(arc
		(start 108.534708 -12.58189)
		(mid 108.631764 -12.588831)
		(end 108.705142 -12.524994)
		(width 0.127)
		(layer "B.Cu")
		(net "P3E_CPU0_PE1_SS_C_RXN<1>")
	)
	(arc
		(start 108.234988 -12.076684)
		(mid 108.283247 -12.319299)
		(end 108.420662 -12.524994)
		(width 0.127)
		(layer "B.Cu")
		(net "P3E_CPU0_PE1_SS_C_RXN<1>")
	)
	(arc
		(start 106.716322 -10.25525)
		(mid 106.84173 -10.338952)
		(end 106.989626 -10.36828)
		(width 0.127)
		(layer "B.Cu")
		(net "P3E_CPU0_PE1_SS_C_RXN<1>")
	)
	(arc
		(start 105.2322 -7.2136)
		(mid 105.268422 -7.623187)
		(end 105.484422 -7.97306)
		(width 0.127)
		(layer "B.Cu")
		(net "P3E_CPU0_PE1_SS_C_RXN<1>")
	)
	(arc
		(start 105.949496 -8.438134)
		(mid 106.149536 -8.737515)
		(end 106.219752 -9.09066)
		(width 0.127)
		(layer "B.Cu")
		(net "P3E_CPU0_PE1_SS_C_RXN<1>")
	)
	(arc
		(start 106.989626 -10.36828)
		(mid 107.87023 -10.733038)
		(end 108.234988 -11.613642)
		(width 0.127)
		(layer "B.Cu")
		(net "P3E_CPU0_PE1_SS_C_RXN<1>")
	)
	(segment
		(start 77.732382 10.401554)
		(end 77.732382 9.951212)
		(width 0.127)
		(layer "B.Cu")
		(net "P3E_CPU0_PE1_SS_C_RXN<0>")
	)
	(segment
		(start 109.484922 -7.97306)
		(end 109.949996 -8.438134)
		(width 0.127)
		(layer "B.Cu")
		(net "P3E_CPU0_PE1_SS_C_RXN<0>")
	)
	(segment
		(start 80.633062 4.068318)
		(end 81.008474 4.002278)
		(width 0.127)
		(layer "B.Cu")
		(net "P3E_CPU0_PE1_SS_C_RXN<0>")
	)
	(segment
		(start 76.418694 6.11505)
		(end 77.101192 5.140198)
		(width 0.127)
		(layer "B.Cu")
		(net "P3E_CPU0_PE1_SS_C_RXN<0>")
	)
	(segment
		(start 81.525872 3.733038)
		(end 81.728818 3.875278)
		(width 0.127)
		(layer "B.Cu")
		(net "P3E_CPU0_PE1_SS_C_RXN<0>")
	)
	(segment
		(start 93.558868 0.81026)
		(end 93.58884 0.79756)
		(width 0.127)
		(layer "B.Cu")
		(net "P3E_CPU0_PE1_SS_C_RXN<0>")
	)
	(segment
		(start 80.430116 3.926078)
		(end 80.633062 4.068318)
		(width 0.127)
		(layer "B.Cu")
		(net "P3E_CPU0_PE1_SS_C_RXN<0>")
	)
	(segment
		(start 112.534954 -12.58189)
		(end 112.535208 -12.58189)
		(width 0.127)
		(layer "B.Cu")
		(net "P3E_CPU0_PE1_SS_C_RXN<0>")
	)
	(segment
		(start 77.650086 9.48436)
		(end 76.544932 7.906004)
		(width 0.127)
		(layer "B.Cu")
		(net "P3E_CPU0_PE1_SS_C_RXN<0>")
	)
	(segment
		(start 102.426008 -4.111498)
		(end 104.3305 -4.6863)
		(width 0.127)
		(layer "B.Cu")
		(net "P3E_CPU0_PE1_SS_C_RXN<0>")
	)
	(segment
		(start 90.196924 2.201164)
		(end 91.93276 1.483106)
		(width 0.127)
		(layer "B.Cu")
		(net "P3E_CPU0_PE1_SS_C_RXN<0>")
	)
	(segment
		(start 109.000036 -6.228588)
		(end 109.136434 -6.500114)
		(width 0.127)
		(layer "B.Cu")
		(net "P3E_CPU0_PE1_SS_C_RXN<0>")
	)
	(segment
		(start 112.956086 -12.02309)
		(end 113.080292 -11.749786)
		(width 0.127)
		(layer "B.Cu")
		(net "P3E_CPU0_PE1_SS_C_RXN<0>")
	)
	(segment
		(start 81.008474 4.002278)
		(end 81.150714 3.799078)
		(width 0.127)
		(layer "B.Cu")
		(net "P3E_CPU0_PE1_SS_C_RXN<0>")
	)
	(segment
		(start 82.103976 3.809238)
		(end 82.246216 3.606292)
		(width 0.127)
		(layer "B.Cu")
		(net "P3E_CPU0_PE1_SS_C_RXN<0>")
	)
	(segment
		(start 77.85608 10.64768)
		(end 77.818996 10.610596)
		(width 0.127)
		(layer "B.Cu")
		(net "P3E_CPU0_PE1_SS_C_RXN<0>")
	)
	(segment
		(start 93.558106 0.81026)
		(end 93.558868 0.81026)
		(width 0.127)
		(layer "B.Cu")
		(net "P3E_CPU0_PE1_SS_C_RXN<0>")
	)
	(segment
		(start 108.30687 -5.886958)
		(end 109.000036 -6.228588)
		(width 0.127)
		(layer "B.Cu")
		(net "P3E_CPU0_PE1_SS_C_RXN<0>")
	)
	(segment
		(start 90.194638 2.20599)
		(end 90.196924 2.201164)
		(width 0.127)
		(layer "B.Cu")
		(net "P3E_CPU0_PE1_SS_C_RXN<0>")
	)
	(segment
		(start 76.544932 7.906004)
		(end 76.323952 6.65226)
		(width 0.127)
		(layer "B.Cu")
		(net "P3E_CPU0_PE1_SS_C_RXN<0>")
	)
	(segment
		(start 78.29931 4.301236)
		(end 80.430116 3.926078)
		(width 0.127)
		(layer "B.Cu")
		(net "P3E_CPU0_PE1_SS_C_RXN<0>")
	)
	(segment
		(start 112.421162 -12.524994)
		(end 112.534954 -12.58189)
		(width 0.127)
		(layer "B.Cu")
		(net "P3E_CPU0_PE1_SS_C_RXN<0>")
	)
	(segment
		(start 93.97619 0.52705)
		(end 98.848672 -2.884678)
		(width 0.127)
		(layer "B.Cu")
		(net "P3E_CPU0_PE1_SS_C_RXN<0>")
	)
	(segment
		(start 98.848672 -2.884678)
		(end 99.337622 -3.227324)
		(width 0.127)
		(layer "B.Cu")
		(net "P3E_CPU0_PE1_SS_C_RXN<0>")
	)
	(segment
		(start 77.979778 12.514072)
		(end 77.979778 10.946384)
		(width 0.127)
		(layer "B.Cu")
		(net "P3E_CPU0_PE1_SS_C_RXN<0>")
	)
	(segment
		(start 99.337622 -3.227324)
		(end 101.7778 -3.6576)
		(width 0.127)
		(layer "B.Cu")
		(net "P3E_CPU0_PE1_SS_C_RXN<0>")
	)
	(segment
		(start 82.246216 3.606292)
		(end 90.194638 2.20599)
		(width 0.127)
		(layer "B.Cu")
		(net "P3E_CPU0_PE1_SS_C_RXN<0>")
	)
	(segment
		(start 112.705642 -12.524994)
		(end 112.956086 -12.02309)
		(width 0.127)
		(layer "B.Cu")
		(net "P3E_CPU0_PE1_SS_C_RXN<0>")
	)
	(segment
		(start 112.235488 -11.613642)
		(end 112.235488 -12.076684)
		(width 0.127)
		(layer "B.Cu")
		(net "P3E_CPU0_PE1_SS_C_RXN<0>")
	)
	(segment
		(start 91.93276 1.483106)
		(end 93.558106 0.81026)
		(width 0.127)
		(layer "B.Cu")
		(net "P3E_CPU0_PE1_SS_C_RXN<0>")
	)
	(segment
		(start 110.220252 -9.09066)
		(end 110.220252 -9.617202)
		(width 0.127)
		(layer "B.Cu")
		(net "P3E_CPU0_PE1_SS_C_RXN<0>")
	)
	(segment
		(start 81.728818 3.875278)
		(end 82.103976 3.809238)
		(width 0.127)
		(layer "B.Cu")
		(net "P3E_CPU0_PE1_SS_C_RXN<0>")
	)
	(segment
		(start 109.22 -6.855968)
		(end 109.22 -7.333488)
		(width 0.127)
		(layer "B.Cu")
		(net "P3E_CPU0_PE1_SS_C_RXN<0>")
	)
	(segment
		(start 110.320074 -9.858248)
		(end 110.716822 -10.25525)
		(width 0.127)
		(layer "B.Cu")
		(net "P3E_CPU0_PE1_SS_C_RXN<0>")
	)
	(segment
		(start 81.150714 3.799078)
		(end 81.525872 3.733038)
		(width 0.127)
		(layer "B.Cu")
		(net "P3E_CPU0_PE1_SS_C_RXN<0>")
	)
	(segment
		(start 76.323952 6.65226)
		(end 76.418694 6.11505)
		(width 0.127)
		(layer "B.Cu")
		(net "P3E_CPU0_PE1_SS_C_RXN<0>")
	)
	(segment
		(start 108.28274 -5.879846)
		(end 108.30687 -5.886958)
		(width 0.127)
		(layer "B.Cu")
		(net "P3E_CPU0_PE1_SS_C_RXN<0>")
	)
	(segment
		(start 77.101192 5.140198)
		(end 78.29931 4.301236)
		(width 0.127)
		(layer "B.Cu")
		(net "P3E_CPU0_PE1_SS_C_RXN<0>")
	)
	(segment
		(start 77.732382 9.951212)
		(end 77.650086 9.48436)
		(width 0.127)
		(layer "B.Cu")
		(net "P3E_CPU0_PE1_SS_C_RXN<0>")
	)
	(segment
		(start 104.3305 -4.6863)
		(end 108.28274 -5.879846)
		(width 0.127)
		(layer "B.Cu")
		(net "P3E_CPU0_PE1_SS_C_RXN<0>")
	)
	(segment
		(start 93.58884 0.79756)
		(end 93.97619 0.52705)
		(width 0.127)
		(layer "B.Cu")
		(net "P3E_CPU0_PE1_SS_C_RXN<0>")
	)
	(segment
		(start 101.7778 -3.6576)
		(end 102.426008 -4.111498)
		(width 0.127)
		(layer "B.Cu")
		(net "P3E_CPU0_PE1_SS_C_RXN<0>")
	)
	(arc
		(start 110.990126 -10.36828)
		(mid 111.87073 -10.733038)
		(end 112.235488 -11.613642)
		(width 0.127)
		(layer "B.Cu")
		(net "P3E_CPU0_PE1_SS_C_RXN<0>")
	)
	(arc
		(start 110.220252 -9.617202)
		(mid 110.246199 -9.747647)
		(end 110.320074 -9.858248)
		(width 0.127)
		(layer "B.Cu")
		(net "P3E_CPU0_PE1_SS_C_RXN<0>")
	)
	(arc
		(start 112.235488 -12.076684)
		(mid 112.283747 -12.319299)
		(end 112.421162 -12.524994)
		(width 0.127)
		(layer "B.Cu")
		(net "P3E_CPU0_PE1_SS_C_RXN<0>")
	)
	(arc
		(start 109.136434 -6.500114)
		(mid 109.199333 -6.67308)
		(end 109.22 -6.855968)
		(width 0.127)
		(layer "B.Cu")
		(net "P3E_CPU0_PE1_SS_C_RXN<0>")
	)
	(arc
		(start 112.535208 -12.58189)
		(mid 112.545076 -12.586247)
		(end 112.555274 -12.589764)
		(width 0.127)
		(layer "B.Cu")
		(net "P3E_CPU0_PE1_SS_C_RXN<0>")
	)
	(arc
		(start 109.949996 -8.438134)
		(mid 110.150036 -8.737515)
		(end 110.220252 -9.09066)
		(width 0.127)
		(layer "B.Cu")
		(net "P3E_CPU0_PE1_SS_C_RXN<0>")
	)
	(arc
		(start 110.716822 -10.25525)
		(mid 110.84223 -10.338952)
		(end 110.990126 -10.36828)
		(width 0.127)
		(layer "B.Cu")
		(net "P3E_CPU0_PE1_SS_C_RXN<0>")
	)
	(arc
		(start 77.818996 10.610596)
		(mid 77.754911 10.514687)
		(end 77.732382 10.401554)
		(width 0.127)
		(layer "B.Cu")
		(net "P3E_CPU0_PE1_SS_C_RXN<0>")
	)
	(arc
		(start 112.555274 -12.589764)
		(mid 112.6423 -12.584875)
		(end 112.705642 -12.524994)
		(width 0.127)
		(layer "B.Cu")
		(net "P3E_CPU0_PE1_SS_C_RXN<0>")
	)
	(arc
		(start 77.979778 10.946384)
		(mid 77.947625 10.784738)
		(end 77.85608 10.64768)
		(width 0.127)
		(layer "B.Cu")
		(net "P3E_CPU0_PE1_SS_C_RXN<0>")
	)
	(arc
		(start 109.22 -7.333488)
		(mid 109.288851 -7.679623)
		(end 109.484922 -7.97306)
		(width 0.127)
		(layer "B.Cu")
		(net "P3E_CPU0_PE1_SS_C_RXN<0>")
	)
	(segment
		(start 54.779926 12.133072)
		(end 54.779926 11.02868)
		(width 0.127)
		(layer "F.Cu")
		(net "P3E_CPU0_PE1_PCH_CON_TXP<9>")
	)
	(segment
		(start 73.455276 -8.524748)
		(end 73.259696 -8.916162)
		(width 0.127)
		(layer "F.Cu")
		(net "P3E_CPU0_PE1_PCH_CON_TXP<9>")
	)
	(segment
		(start 73.398126 -8.354314)
		(end 73.39838 -8.354314)
		(width 0.127)
		(layer "F.Cu")
		(net "P3E_CPU0_PE1_PCH_CON_TXP<9>")
	)
	(segment
		(start 55.027576 10.431018)
		(end 55.027576 10.155174)
		(width 0.127)
		(layer "F.Cu")
		(net "P3E_CPU0_PE1_PCH_CON_TXP<9>")
	)
	(segment
		(start 55.027576 10.155174)
		(end 55.259478 8.868664)
		(width 0.127)
		(layer "F.Cu")
		(net "P3E_CPU0_PE1_PCH_CON_TXP<9>")
	)
	(segment
		(start 59.870594 2.28346)
		(end 72.62622 -6.647688)
		(width 0.127)
		(layer "F.Cu")
		(net "P3E_CPU0_PE1_PCH_CON_TXP<9>")
	)
	(segment
		(start 72.880728 -7.011162)
		(end 72.921368 -7.448042)
		(width 0.127)
		(layer "F.Cu")
		(net "P3E_CPU0_PE1_PCH_CON_TXP<9>")
	)
	(segment
		(start 73.259696 -8.916162)
		(end 73.080372 -9.250426)
		(width 0.127)
		(layer "F.Cu")
		(net "P3E_CPU0_PE1_PCH_CON_TXP<9>")
	)
	(segment
		(start 55.259478 8.868664)
		(end 59.870594 2.28346)
		(width 0.127)
		(layer "F.Cu")
		(net "P3E_CPU0_PE1_PCH_CON_TXP<9>")
	)
	(segment
		(start 72.62622 -6.647688)
		(end 72.880728 -7.011162)
		(width 0.127)
		(layer "F.Cu")
		(net "P3E_CPU0_PE1_PCH_CON_TXP<9>")
	)
	(segment
		(start 73.284842 -8.297926)
		(end 73.398126 -8.354314)
		(width 0.127)
		(layer "F.Cu")
		(net "P3E_CPU0_PE1_PCH_CON_TXP<9>")
	)
	(arc
		(start 73.39838 -8.354314)
		(mid 73.462143 -8.427767)
		(end 73.455276 -8.524748)
		(width 0.127)
		(layer "F.Cu")
		(net "P3E_CPU0_PE1_PCH_CON_TXP<9>")
	)
	(arc
		(start 54.779926 11.02868)
		(mid 54.812148 10.866868)
		(end 54.903878 10.729722)
		(width 0.127)
		(layer "F.Cu")
		(net "P3E_CPU0_PE1_PCH_CON_TXP<9>")
	)
	(arc
		(start 72.921368 -7.448042)
		(mid 73.021049 -7.908086)
		(end 73.284842 -8.297926)
		(width 0.127)
		(layer "F.Cu")
		(net "P3E_CPU0_PE1_PCH_CON_TXP<9>")
	)
	(arc
		(start 54.903878 10.729722)
		(mid 54.99545 10.592675)
		(end 55.027576 10.431018)
		(width 0.127)
		(layer "F.Cu")
		(net "P3E_CPU0_PE1_PCH_CON_TXP<9>")
	)
	(segment
		(start 77.343508 -8.356092)
		(end 77.285342 -8.297926)
		(width 0.127)
		(layer "F.Cu")
		(net "P3E_CPU0_PE1_PCH_CON_TXP<8>")
	)
	(segment
		(start 76.885038 -6.80593)
		(end 76.72959 -6.583934)
		(width 0.127)
		(layer "F.Cu")
		(net "P3E_CPU0_PE1_PCH_CON_TXP<8>")
	)
	(segment
		(start 57.609486 9.122664)
		(end 57.427368 10.155682)
		(width 0.127)
		(layer "F.Cu")
		(net "P3E_CPU0_PE1_PCH_CON_TXP<8>")
	)
	(segment
		(start 77.079602 -9.250426)
		(end 77.079602 -9.275318)
		(width 0.127)
		(layer "F.Cu")
		(net "P3E_CPU0_PE1_PCH_CON_TXP<8>")
	)
	(segment
		(start 76.72959 -6.583934)
		(end 76.51496 -6.433566)
		(width 0.127)
		(layer "F.Cu")
		(net "P3E_CPU0_PE1_PCH_CON_TXP<8>")
	)
	(segment
		(start 62.024006 2.238248)
		(end 62.023498 2.238756)
		(width 0.127)
		(layer "F.Cu")
		(net "P3E_CPU0_PE1_PCH_CON_TXP<8>")
	)
	(segment
		(start 77.079602 -9.275318)
		(end 77.391514 -8.652764)
		(width 0.127)
		(layer "F.Cu")
		(net "P3E_CPU0_PE1_PCH_CON_TXP<8>")
	)
	(segment
		(start 61.913008 2.35204)
		(end 57.756552 8.288528)
		(width 0.127)
		(layer "F.Cu")
		(net "P3E_CPU0_PE1_PCH_CON_TXP<8>")
	)
	(segment
		(start 73.602342 -5.867908)
		(end 62.024006 2.238248)
		(width 0.127)
		(layer "F.Cu")
		(net "P3E_CPU0_PE1_PCH_CON_TXP<8>")
	)
	(segment
		(start 62.023498 2.241804)
		(end 61.913008 2.35204)
		(width 0.127)
		(layer "F.Cu")
		(net "P3E_CPU0_PE1_PCH_CON_TXP<8>")
	)
	(segment
		(start 57.179972 11.041634)
		(end 57.179972 12.133072)
		(width 0.127)
		(layer "F.Cu")
		(net "P3E_CPU0_PE1_PCH_CON_TXP<8>")
	)
	(segment
		(start 76.921614 -7.013194)
		(end 76.885038 -6.80593)
		(width 0.127)
		(layer "F.Cu")
		(net "P3E_CPU0_PE1_PCH_CON_TXP<8>")
	)
	(segment
		(start 57.609994 9.121902)
		(end 57.609486 9.122664)
		(width 0.127)
		(layer "F.Cu")
		(net "P3E_CPU0_PE1_PCH_CON_TXP<8>")
	)
	(segment
		(start 57.756552 8.288528)
		(end 57.609994 9.121902)
		(width 0.127)
		(layer "F.Cu")
		(net "P3E_CPU0_PE1_PCH_CON_TXP<8>")
	)
	(segment
		(start 76.400406 -6.385814)
		(end 76.398882 -6.38175)
		(width 0.127)
		(layer "F.Cu")
		(net "P3E_CPU0_PE1_PCH_CON_TXP<8>")
	)
	(segment
		(start 76.921614 -7.419848)
		(end 76.921614 -7.013194)
		(width 0.127)
		(layer "F.Cu")
		(net "P3E_CPU0_PE1_PCH_CON_TXP<8>")
	)
	(segment
		(start 76.51496 -6.433566)
		(end 76.400406 -6.385814)
		(width 0.127)
		(layer "F.Cu")
		(net "P3E_CPU0_PE1_PCH_CON_TXP<8>")
	)
	(segment
		(start 76.312522 -6.345936)
		(end 73.602342 -5.867908)
		(width 0.127)
		(layer "F.Cu")
		(net "P3E_CPU0_PE1_PCH_CON_TXP<8>")
	)
	(segment
		(start 62.023498 2.238756)
		(end 62.023498 2.241804)
		(width 0.127)
		(layer "F.Cu")
		(net "P3E_CPU0_PE1_PCH_CON_TXP<8>")
	)
	(segment
		(start 57.427368 10.155682)
		(end 57.427368 10.444226)
		(width 0.127)
		(layer "F.Cu")
		(net "P3E_CPU0_PE1_PCH_CON_TXP<8>")
	)
	(segment
		(start 76.398882 -6.38175)
		(end 76.312522 -6.345936)
		(width 0.127)
		(layer "F.Cu")
		(net "P3E_CPU0_PE1_PCH_CON_TXP<8>")
	)
	(arc
		(start 77.285342 -8.297926)
		(mid 77.263856 -8.275965)
		(end 77.242924 -8.253476)
		(width 0.127)
		(layer "F.Cu")
		(net "P3E_CPU0_PE1_PCH_CON_TXP<8>")
	)
	(arc
		(start 77.242924 -8.253476)
		(mid 77.004673 -7.866563)
		(end 76.921614 -7.419848)
		(width 0.127)
		(layer "F.Cu")
		(net "P3E_CPU0_PE1_PCH_CON_TXP<8>")
	)
	(arc
		(start 57.427368 10.444226)
		(mid 57.395215 10.605872)
		(end 57.30367 10.74293)
		(width 0.127)
		(layer "F.Cu")
		(net "P3E_CPU0_PE1_PCH_CON_TXP<8>")
	)
	(arc
		(start 77.391514 -8.652764)
		(mid 77.415432 -8.496674)
		(end 77.343508 -8.356092)
		(width 0.127)
		(layer "F.Cu")
		(net "P3E_CPU0_PE1_PCH_CON_TXP<8>")
	)
	(arc
		(start 57.30367 10.74293)
		(mid 57.212098 10.879977)
		(end 57.179972 11.041634)
		(width 0.127)
		(layer "F.Cu")
		(net "P3E_CPU0_PE1_PCH_CON_TXP<8>")
	)
	(segment
		(start 48.2854 -5.183124)
		(end 48.563276 -4.922266)
		(width 0.127)
		(layer "F.Cu")
		(net "P3E_CPU0_PE1_PCH_CON_TXP<15>")
	)
	(segment
		(start 49.877726 -1.743456)
		(end 49.755298 -1.090168)
		(width 0.127)
		(layer "F.Cu")
		(net "P3E_CPU0_PE1_PCH_CON_TXP<15>")
	)
	(segment
		(start 47.999904 -5.691378)
		(end 48.277526 -5.430774)
		(width 0.127)
		(layer "F.Cu")
		(net "P3E_CPU0_PE1_PCH_CON_TXP<15>")
	)
	(segment
		(start 45.564044 4.636262)
		(end 45.562774 4.637278)
		(width 0.127)
		(layer "F.Cu")
		(net "P3E_CPU0_PE1_PCH_CON_TXP<15>")
	)
	(segment
		(start 36.50615 8.780526)
		(end 35.867086 9.692894)
		(width 0.127)
		(layer "F.Cu")
		(net "P3E_CPU0_PE1_PCH_CON_TXP<15>")
	)
	(segment
		(start 48.277526 -5.430774)
		(end 48.2854 -5.183124)
		(width 0.127)
		(layer "F.Cu")
		(net "P3E_CPU0_PE1_PCH_CON_TXP<15>")
	)
	(segment
		(start 46.9519 -6.994652)
		(end 47.057056 -6.764528)
		(width 0.127)
		(layer "F.Cu")
		(net "P3E_CPU0_PE1_PCH_CON_TXP<15>")
	)
	(segment
		(start 47.057056 -6.764528)
		(end 47.05985 -6.758686)
		(width 0.127)
		(layer "F.Cu")
		(net "P3E_CPU0_PE1_PCH_CON_TXP<15>")
	)
	(segment
		(start 48.810926 -4.93014)
		(end 49.420018 -4.358386)
		(width 0.127)
		(layer "F.Cu")
		(net "P3E_CPU0_PE1_PCH_CON_TXP<15>")
	)
	(segment
		(start 48.563276 -4.922266)
		(end 48.810926 -4.93014)
		(width 0.127)
		(layer "F.Cu")
		(net "P3E_CPU0_PE1_PCH_CON_TXP<15>")
	)
	(segment
		(start 45.564806 4.635754)
		(end 45.564044 4.636262)
		(width 0.127)
		(layer "F.Cu")
		(net "P3E_CPU0_PE1_PCH_CON_TXP<15>")
	)
	(segment
		(start 49.87798 -1.743456)
		(end 49.877726 -1.743456)
		(width 0.127)
		(layer "F.Cu")
		(net "P3E_CPU0_PE1_PCH_CON_TXP<15>")
	)
	(segment
		(start 35.867086 9.692894)
		(end 35.827462 9.917938)
		(width 0.127)
		(layer "F.Cu")
		(net "P3E_CPU0_PE1_PCH_CON_TXP<15>")
	)
	(segment
		(start 40.650922 5.878068)
		(end 36.50615 8.780526)
		(width 0.127)
		(layer "F.Cu")
		(net "P3E_CPU0_PE1_PCH_CON_TXP<15>")
	)
	(segment
		(start 46.080172 -7.250176)
		(end 46.454568 -7.999984)
		(width 0.127)
		(layer "F.Cu")
		(net "P3E_CPU0_PE1_PCH_CON_TXP<15>")
	)
	(segment
		(start 47.09795 -6.668262)
		(end 47.164244 -6.528562)
		(width 0.127)
		(layer "F.Cu")
		(net "P3E_CPU0_PE1_PCH_CON_TXP<15>")
	)
	(segment
		(start 49.967388 -2.763266)
		(end 50.000916 -2.397252)
		(width 0.127)
		(layer "F.Cu")
		(net "P3E_CPU0_PE1_PCH_CON_TXP<15>")
	)
	(segment
		(start 49.755298 -1.090168)
		(end 49.737772 -1.06172)
		(width 0.127)
		(layer "F.Cu")
		(net "P3E_CPU0_PE1_PCH_CON_TXP<15>")
	)
	(segment
		(start 50.000916 -2.397252)
		(end 49.87798 -1.743456)
		(width 0.127)
		(layer "F.Cu")
		(net "P3E_CPU0_PE1_PCH_CON_TXP<15>")
	)
	(segment
		(start 47.164244 -6.528562)
		(end 47.16399 -6.528562)
		(width 0.127)
		(layer "F.Cu")
		(net "P3E_CPU0_PE1_PCH_CON_TXP<15>")
	)
	(segment
		(start 46.9519 -7.351776)
		(end 46.9519 -6.994652)
		(width 0.127)
		(layer "F.Cu")
		(net "P3E_CPU0_PE1_PCH_CON_TXP<15>")
	)
	(segment
		(start 47.05985 -6.758686)
		(end 47.09795 -6.668262)
		(width 0.127)
		(layer "F.Cu")
		(net "P3E_CPU0_PE1_PCH_CON_TXP<15>")
	)
	(segment
		(start 46.625002 -8.05688)
		(end 46.625256 -8.05688)
		(width 0.127)
		(layer "F.Cu")
		(net "P3E_CPU0_PE1_PCH_CON_TXP<15>")
	)
	(segment
		(start 47.474378 -5.944362)
		(end 47.752 -5.683758)
		(width 0.127)
		(layer "F.Cu")
		(net "P3E_CPU0_PE1_PCH_CON_TXP<15>")
	)
	(segment
		(start 47.466504 -6.192012)
		(end 47.474378 -5.944362)
		(width 0.127)
		(layer "F.Cu")
		(net "P3E_CPU0_PE1_PCH_CON_TXP<15>")
	)
	(segment
		(start 46.626272 -8.056372)
		(end 46.69155 -8.023606)
		(width 0.127)
		(layer "F.Cu")
		(net "P3E_CPU0_PE1_PCH_CON_TXP<15>")
	)
	(segment
		(start 43.393868 5.456682)
		(end 40.650922 5.878068)
		(width 0.127)
		(layer "F.Cu")
		(net "P3E_CPU0_PE1_PCH_CON_TXP<15>")
	)
	(segment
		(start 35.579812 11.039856)
		(end 35.579812 12.133072)
		(width 0.127)
		(layer "F.Cu")
		(net "P3E_CPU0_PE1_PCH_CON_TXP<15>")
	)
	(segment
		(start 45.553376 4.636008)
		(end 43.393868 5.456682)
		(width 0.127)
		(layer "F.Cu")
		(net "P3E_CPU0_PE1_PCH_CON_TXP<15>")
	)
	(segment
		(start 35.827462 9.917938)
		(end 35.827462 10.442194)
		(width 0.127)
		(layer "F.Cu")
		(net "P3E_CPU0_PE1_PCH_CON_TXP<15>")
	)
	(segment
		(start 49.737772 -1.06172)
		(end 45.869606 4.404868)
		(width 0.127)
		(layer "F.Cu")
		(net "P3E_CPU0_PE1_PCH_CON_TXP<15>")
	)
	(segment
		(start 45.574966 4.628134)
		(end 45.564806 4.635754)
		(width 0.127)
		(layer "F.Cu")
		(net "P3E_CPU0_PE1_PCH_CON_TXP<15>")
	)
	(segment
		(start 47.752 -5.683758)
		(end 47.999904 -5.691378)
		(width 0.127)
		(layer "F.Cu")
		(net "P3E_CPU0_PE1_PCH_CON_TXP<15>")
	)
	(segment
		(start 46.625256 -8.05688)
		(end 46.626272 -8.056372)
		(width 0.127)
		(layer "F.Cu")
		(net "P3E_CPU0_PE1_PCH_CON_TXP<15>")
	)
	(segment
		(start 47.466504 -6.192266)
		(end 47.466504 -6.192012)
		(width 0.127)
		(layer "F.Cu")
		(net "P3E_CPU0_PE1_PCH_CON_TXP<15>")
	)
	(segment
		(start 47.209202 -6.43382)
		(end 47.466504 -6.192266)
		(width 0.127)
		(layer "F.Cu")
		(net "P3E_CPU0_PE1_PCH_CON_TXP<15>")
	)
	(segment
		(start 49.95926 -2.801366)
		(end 49.967388 -2.763266)
		(width 0.127)
		(layer "F.Cu")
		(net "P3E_CPU0_PE1_PCH_CON_TXP<15>")
	)
	(segment
		(start 45.562774 4.637278)
		(end 45.553376 4.636008)
		(width 0.127)
		(layer "F.Cu")
		(net "P3E_CPU0_PE1_PCH_CON_TXP<15>")
	)
	(segment
		(start 47.16399 -6.528562)
		(end 47.209202 -6.43382)
		(width 0.127)
		(layer "F.Cu")
		(net "P3E_CPU0_PE1_PCH_CON_TXP<15>")
	)
	(segment
		(start 49.958244 -2.803652)
		(end 49.95926 -2.801366)
		(width 0.127)
		(layer "F.Cu")
		(net "P3E_CPU0_PE1_PCH_CON_TXP<15>")
	)
	(segment
		(start 45.869606 4.404868)
		(end 45.574966 4.628134)
		(width 0.127)
		(layer "F.Cu")
		(net "P3E_CPU0_PE1_PCH_CON_TXP<15>")
	)
	(segment
		(start 49.420018 -4.358386)
		(end 49.958244 -2.803652)
		(width 0.127)
		(layer "F.Cu")
		(net "P3E_CPU0_PE1_PCH_CON_TXP<15>")
	)
	(arc
		(start 35.703764 10.740898)
		(mid 35.612007 10.878033)
		(end 35.579812 11.039856)
		(width 0.127)
		(layer "F.Cu")
		(net "P3E_CPU0_PE1_PCH_CON_TXP<15>")
	)
	(arc
		(start 35.827462 10.442194)
		(mid 35.795309 10.60384)
		(end 35.703764 10.740898)
		(width 0.127)
		(layer "F.Cu")
		(net "P3E_CPU0_PE1_PCH_CON_TXP<15>")
	)
	(arc
		(start 46.454568 -7.999984)
		(mid 46.527982 -8.063713)
		(end 46.625002 -8.05688)
		(width 0.127)
		(layer "F.Cu")
		(net "P3E_CPU0_PE1_PCH_CON_TXP<15>")
	)
	(arc
		(start 46.69155 -8.023606)
		(mid 46.88453 -7.712024)
		(end 46.9519 -7.351776)
		(width 0.127)
		(layer "F.Cu")
		(net "P3E_CPU0_PE1_PCH_CON_TXP<15>")
	)
	(segment
		(start 51.181762 -5.793994)
		(end 50.921412 -7.392924)
		(width 0.127)
		(layer "F.Cu")
		(net "P3E_CPU0_PE1_PCH_CON_TXP<14>")
	)
	(segment
		(start 38.227508 9.93013)
		(end 38.277292 9.647174)
		(width 0.127)
		(layer "F.Cu")
		(net "P3E_CPU0_PE1_PCH_CON_TXP<14>")
	)
	(segment
		(start 38.227508 10.49401)
		(end 38.227508 9.93013)
		(width 0.127)
		(layer "F.Cu")
		(net "P3E_CPU0_PE1_PCH_CON_TXP<14>")
	)
	(segment
		(start 38.95217 8.688324)
		(end 39.066216 8.574024)
		(width 0.127)
		(layer "F.Cu")
		(net "P3E_CPU0_PE1_PCH_CON_TXP<14>")
	)
	(segment
		(start 51.564032 -3.45059)
		(end 51.43881 -4.218178)
		(width 0.127)
		(layer "F.Cu")
		(net "P3E_CPU0_PE1_PCH_CON_TXP<14>")
	)
	(segment
		(start 46.535086 5.548122)
		(end 51.14544 -0.849122)
		(width 0.127)
		(layer "F.Cu")
		(net "P3E_CPU0_PE1_PCH_CON_TXP<14>")
	)
	(segment
		(start 44.252642 6.604762)
		(end 44.66082 6.415786)
		(width 0.127)
		(layer "F.Cu")
		(net "P3E_CPU0_PE1_PCH_CON_TXP<14>")
	)
	(segment
		(start 45.393864 6.076188)
		(end 46.535086 5.548122)
		(width 0.127)
		(layer "F.Cu")
		(net "P3E_CPU0_PE1_PCH_CON_TXP<14>")
	)
	(segment
		(start 51.43881 -4.218178)
		(end 51.181762 -5.793994)
		(width 0.127)
		(layer "F.Cu")
		(net "P3E_CPU0_PE1_PCH_CON_TXP<14>")
	)
	(segment
		(start 41.534588 6.971284)
		(end 43.01236 6.77164)
		(width 0.127)
		(layer "F.Cu")
		(net "P3E_CPU0_PE1_PCH_CON_TXP<14>")
	)
	(segment
		(start 51.564032 -2.99212)
		(end 51.564032 -3.45059)
		(width 0.127)
		(layer "F.Cu")
		(net "P3E_CPU0_PE1_PCH_CON_TXP<14>")
	)
	(segment
		(start 44.66082 6.415786)
		(end 45.393864 6.076188)
		(width 0.127)
		(layer "F.Cu")
		(net "P3E_CPU0_PE1_PCH_CON_TXP<14>")
	)
	(segment
		(start 38.277292 9.647174)
		(end 38.94836 8.688578)
		(width 0.127)
		(layer "F.Cu")
		(net "P3E_CPU0_PE1_PCH_CON_TXP<14>")
	)
	(segment
		(start 39.066216 8.574024)
		(end 41.534588 6.971284)
		(width 0.127)
		(layer "F.Cu")
		(net "P3E_CPU0_PE1_PCH_CON_TXP<14>")
	)
	(segment
		(start 51.543712 -2.588006)
		(end 51.564032 -2.99212)
		(width 0.127)
		(layer "F.Cu")
		(net "P3E_CPU0_PE1_PCH_CON_TXP<14>")
	)
	(segment
		(start 51.455066 -8.524748)
		(end 51.252628 -8.929878)
		(width 0.127)
		(layer "F.Cu")
		(net "P3E_CPU0_PE1_PCH_CON_TXP<14>")
	)
	(segment
		(start 51.14544 -0.849122)
		(end 51.532536 -2.57683)
		(width 0.127)
		(layer "F.Cu")
		(net "P3E_CPU0_PE1_PCH_CON_TXP<14>")
	)
	(segment
		(start 37.979858 12.133072)
		(end 37.979858 11.039348)
		(width 0.127)
		(layer "F.Cu")
		(net "P3E_CPU0_PE1_PCH_CON_TXP<14>")
	)
	(segment
		(start 51.284632 -8.297926)
		(end 51.397916 -8.354314)
		(width 0.127)
		(layer "F.Cu")
		(net "P3E_CPU0_PE1_PCH_CON_TXP<14>")
	)
	(segment
		(start 51.397916 -8.354314)
		(end 51.39817 -8.354314)
		(width 0.127)
		(layer "F.Cu")
		(net "P3E_CPU0_PE1_PCH_CON_TXP<14>")
	)
	(segment
		(start 38.94836 8.688578)
		(end 38.948614 8.688324)
		(width 0.127)
		(layer "F.Cu")
		(net "P3E_CPU0_PE1_PCH_CON_TXP<14>")
	)
	(segment
		(start 43.01236 6.77164)
		(end 44.252642 6.604762)
		(width 0.127)
		(layer "F.Cu")
		(net "P3E_CPU0_PE1_PCH_CON_TXP<14>")
	)
	(segment
		(start 38.948614 8.688324)
		(end 38.95217 8.688324)
		(width 0.127)
		(layer "F.Cu")
		(net "P3E_CPU0_PE1_PCH_CON_TXP<14>")
	)
	(segment
		(start 51.532536 -2.57683)
		(end 51.543712 -2.588006)
		(width 0.127)
		(layer "F.Cu")
		(net "P3E_CPU0_PE1_PCH_CON_TXP<14>")
	)
	(segment
		(start 51.252628 -8.929878)
		(end 51.080162 -9.250426)
		(width 0.127)
		(layer "F.Cu")
		(net "P3E_CPU0_PE1_PCH_CON_TXP<14>")
	)
	(segment
		(start 38.103556 10.74039)
		(end 38.14064 10.703306)
		(width 0.127)
		(layer "F.Cu")
		(net "P3E_CPU0_PE1_PCH_CON_TXP<14>")
	)
	(arc
		(start 38.14064 10.703306)
		(mid 38.20491 10.607309)
		(end 38.227508 10.49401)
		(width 0.127)
		(layer "F.Cu")
		(net "P3E_CPU0_PE1_PCH_CON_TXP<14>")
	)
	(arc
		(start 50.920904 -7.41934)
		(mid 51.015334 -7.894832)
		(end 51.284632 -8.297926)
		(width 0.127)
		(layer "F.Cu")
		(net "P3E_CPU0_PE1_PCH_CON_TXP<14>")
	)
	(arc
		(start 37.979858 11.039348)
		(mid 38.012001 10.877576)
		(end 38.103556 10.74039)
		(width 0.127)
		(layer "F.Cu")
		(net "P3E_CPU0_PE1_PCH_CON_TXP<14>")
	)
	(arc
		(start 51.39817 -8.354314)
		(mid 51.461933 -8.427767)
		(end 51.455066 -8.524748)
		(width 0.127)
		(layer "F.Cu")
		(net "P3E_CPU0_PE1_PCH_CON_TXP<14>")
	)
	(arc
		(start 50.921412 -7.392924)
		(mid 50.921088 -7.406131)
		(end 50.920904 -7.41934)
		(width 0.127)
		(layer "F.Cu")
		(net "P3E_CPU0_PE1_PCH_CON_TXP<14>")
	)
	(segment
		(start 45.427392 10.155682)
		(end 45.578522 9.298686)
		(width 0.127)
		(layer "F.Cu")
		(net "P3E_CPU0_PE1_PCH_CON_TXP<13>")
	)
	(segment
		(start 53.028342 -1.340104)
		(end 53.663342 -2.246884)
		(width 0.127)
		(layer "F.Cu")
		(net "P3E_CPU0_PE1_PCH_CON_TXP<13>")
	)
	(segment
		(start 45.578522 9.298686)
		(end 53.028342 -1.340104)
		(width 0.127)
		(layer "F.Cu")
		(net "P3E_CPU0_PE1_PCH_CON_TXP<13>")
	)
	(segment
		(start 54.707282 -5.800852)
		(end 54.921404 -7.01421)
		(width 0.127)
		(layer "F.Cu")
		(net "P3E_CPU0_PE1_PCH_CON_TXP<13>")
	)
	(segment
		(start 55.325518 -8.784082)
		(end 55.079392 -9.250426)
		(width 0.127)
		(layer "F.Cu")
		(net "P3E_CPU0_PE1_PCH_CON_TXP<13>")
	)
	(segment
		(start 45.427392 10.430002)
		(end 45.427392 10.155682)
		(width 0.127)
		(layer "F.Cu")
		(net "P3E_CPU0_PE1_PCH_CON_TXP<13>")
	)
	(segment
		(start 53.663088 -2.247138)
		(end 53.70195 -2.30251)
		(width 0.127)
		(layer "F.Cu")
		(net "P3E_CPU0_PE1_PCH_CON_TXP<13>")
	)
	(segment
		(start 54.22138 -3.043936)
		(end 54.228238 -3.083814)
		(width 0.127)
		(layer "F.Cu")
		(net "P3E_CPU0_PE1_PCH_CON_TXP<13>")
	)
	(segment
		(start 45.179996 12.133072)
		(end 45.179996 11.02741)
		(width 0.127)
		(layer "F.Cu")
		(net "P3E_CPU0_PE1_PCH_CON_TXP<13>")
	)
	(segment
		(start 53.663342 -2.246884)
		(end 53.663088 -2.247138)
		(width 0.127)
		(layer "F.Cu")
		(net "P3E_CPU0_PE1_PCH_CON_TXP<13>")
	)
	(segment
		(start 54.921404 -7.01421)
		(end 54.921404 -7.41934)
		(width 0.127)
		(layer "F.Cu")
		(net "P3E_CPU0_PE1_PCH_CON_TXP<13>")
	)
	(segment
		(start 53.70195 -2.30251)
		(end 54.22138 -3.043936)
		(width 0.127)
		(layer "F.Cu")
		(net "P3E_CPU0_PE1_PCH_CON_TXP<13>")
	)
	(segment
		(start 54.228238 -3.083814)
		(end 54.228492 -3.083814)
		(width 0.127)
		(layer "F.Cu")
		(net "P3E_CPU0_PE1_PCH_CON_TXP<13>")
	)
	(segment
		(start 55.398416 -8.354314)
		(end 55.39867 -8.354314)
		(width 0.127)
		(layer "F.Cu")
		(net "P3E_CPU0_PE1_PCH_CON_TXP<13>")
	)
	(segment
		(start 54.228492 -3.083814)
		(end 54.707282 -5.800852)
		(width 0.127)
		(layer "F.Cu")
		(net "P3E_CPU0_PE1_PCH_CON_TXP<13>")
	)
	(segment
		(start 55.285132 -8.297926)
		(end 55.398416 -8.354314)
		(width 0.127)
		(layer "F.Cu")
		(net "P3E_CPU0_PE1_PCH_CON_TXP<13>")
	)
	(segment
		(start 55.455566 -8.524748)
		(end 55.325518 -8.784082)
		(width 0.127)
		(layer "F.Cu")
		(net "P3E_CPU0_PE1_PCH_CON_TXP<13>")
	)
	(arc
		(start 55.39867 -8.354314)
		(mid 55.462433 -8.427767)
		(end 55.455566 -8.524748)
		(width 0.127)
		(layer "F.Cu")
		(net "P3E_CPU0_PE1_PCH_CON_TXP<13>")
	)
	(arc
		(start 45.179996 11.02741)
		(mid 45.212149 10.865764)
		(end 45.303694 10.728706)
		(width 0.127)
		(layer "F.Cu")
		(net "P3E_CPU0_PE1_PCH_CON_TXP<13>")
	)
	(arc
		(start 45.303694 10.728706)
		(mid 45.395266 10.591659)
		(end 45.427392 10.430002)
		(width 0.127)
		(layer "F.Cu")
		(net "P3E_CPU0_PE1_PCH_CON_TXP<13>")
	)
	(arc
		(start 54.921404 -7.41934)
		(mid 55.015834 -7.894832)
		(end 55.285132 -8.297926)
		(width 0.127)
		(layer "F.Cu")
		(net "P3E_CPU0_PE1_PCH_CON_TXP<13>")
	)
	(segment
		(start 47.827438 10.155936)
		(end 47.827438 10.467594)
		(width 0.127)
		(layer "F.Cu")
		(net "P3E_CPU0_PE1_PCH_CON_TXP<12>")
	)
	(segment
		(start 48.053244 9.104884)
		(end 47.990252 9.256776)
		(width 0.127)
		(layer "F.Cu")
		(net "P3E_CPU0_PE1_PCH_CON_TXP<12>")
	)
	(segment
		(start 47.985426 9.258808)
		(end 47.827438 10.155936)
		(width 0.127)
		(layer "F.Cu")
		(net "P3E_CPU0_PE1_PCH_CON_TXP<12>")
	)
	(segment
		(start 58.78195 -6.217412)
		(end 58.781696 -6.217158)
		(width 0.127)
		(layer "F.Cu")
		(net "P3E_CPU0_PE1_PCH_CON_TXP<12>")
	)
	(segment
		(start 59.397646 -8.354314)
		(end 59.284362 -8.297926)
		(width 0.127)
		(layer "F.Cu")
		(net "P3E_CPU0_PE1_PCH_CON_TXP<12>")
	)
	(segment
		(start 58.781696 -6.217158)
		(end 48.053244 9.104884)
		(width 0.127)
		(layer "F.Cu")
		(net "P3E_CPU0_PE1_PCH_CON_TXP<12>")
	)
	(segment
		(start 47.990506 9.256776)
		(end 47.985426 9.258808)
		(width 0.127)
		(layer "F.Cu")
		(net "P3E_CPU0_PE1_PCH_CON_TXP<12>")
	)
	(segment
		(start 47.990252 9.256776)
		(end 47.990506 9.256776)
		(width 0.127)
		(layer "F.Cu")
		(net "P3E_CPU0_PE1_PCH_CON_TXP<12>")
	)
	(segment
		(start 59.20486 -9.025128)
		(end 59.454796 -8.524748)
		(width 0.127)
		(layer "F.Cu")
		(net "P3E_CPU0_PE1_PCH_CON_TXP<12>")
	)
	(segment
		(start 58.920634 -7.004304)
		(end 58.78195 -6.217412)
		(width 0.127)
		(layer "F.Cu")
		(net "P3E_CPU0_PE1_PCH_CON_TXP<12>")
	)
	(segment
		(start 59.079892 -9.250426)
		(end 59.20486 -9.025128)
		(width 0.127)
		(layer "F.Cu")
		(net "P3E_CPU0_PE1_PCH_CON_TXP<12>")
	)
	(segment
		(start 58.920634 -7.419848)
		(end 58.920634 -7.004304)
		(width 0.127)
		(layer "F.Cu")
		(net "P3E_CPU0_PE1_PCH_CON_TXP<12>")
	)
	(segment
		(start 47.579788 11.065256)
		(end 47.579788 12.133072)
		(width 0.127)
		(layer "F.Cu")
		(net "P3E_CPU0_PE1_PCH_CON_TXP<12>")
	)
	(segment
		(start 59.3979 -8.354314)
		(end 59.397646 -8.354314)
		(width 0.127)
		(layer "F.Cu")
		(net "P3E_CPU0_PE1_PCH_CON_TXP<12>")
	)
	(arc
		(start 59.284362 -8.297926)
		(mid 59.015176 -7.89506)
		(end 58.920634 -7.419848)
		(width 0.127)
		(layer "F.Cu")
		(net "P3E_CPU0_PE1_PCH_CON_TXP<12>")
	)
	(arc
		(start 47.70374 10.766298)
		(mid 47.611983 10.903433)
		(end 47.579788 11.065256)
		(width 0.127)
		(layer "F.Cu")
		(net "P3E_CPU0_PE1_PCH_CON_TXP<12>")
	)
	(arc
		(start 47.827438 10.467594)
		(mid 47.795285 10.62924)
		(end 47.70374 10.766298)
		(width 0.127)
		(layer "F.Cu")
		(net "P3E_CPU0_PE1_PCH_CON_TXP<12>")
	)
	(arc
		(start 59.454796 -8.524748)
		(mid 59.461555 -8.427803)
		(end 59.3979 -8.354314)
		(width 0.127)
		(layer "F.Cu")
		(net "P3E_CPU0_PE1_PCH_CON_TXP<12>")
	)
	(segment
		(start 49.979834 11.028172)
		(end 49.979834 12.133072)
		(width 0.127)
		(layer "F.Cu")
		(net "P3E_CPU0_PE1_PCH_CON_TXP<11>")
	)
	(segment
		(start 65.171828 -9.09066)
		(end 65.455546 -8.524748)
		(width 0.127)
		(layer "F.Cu")
		(net "P3E_CPU0_PE1_PCH_CON_TXP<11>")
	)
	(segment
		(start 64.921384 -7.419848)
		(end 64.921384 -5.950966)
		(width 0.127)
		(layer "F.Cu")
		(net "P3E_CPU0_PE1_PCH_CON_TXP<11>")
	)
	(segment
		(start 50.227484 10.155936)
		(end 50.227484 10.482834)
		(width 0.127)
		(layer "F.Cu")
		(net "P3E_CPU0_PE1_PCH_CON_TXP<11>")
	)
	(segment
		(start 50.39741 9.190482)
		(end 50.287682 9.814052)
		(width 0.127)
		(layer "F.Cu")
		(net "P3E_CPU0_PE1_PCH_CON_TXP<11>")
	)
	(segment
		(start 65.39865 -8.354314)
		(end 65.398396 -8.354314)
		(width 0.127)
		(layer "F.Cu")
		(net "P3E_CPU0_PE1_PCH_CON_TXP<11>")
	)
	(segment
		(start 63.8048 -3.510026)
		(end 54.948328 2.69113)
		(width 0.127)
		(layer "F.Cu")
		(net "P3E_CPU0_PE1_PCH_CON_TXP<11>")
	)
	(segment
		(start 65.398396 -8.354314)
		(end 65.285112 -8.297926)
		(width 0.127)
		(layer "F.Cu")
		(net "P3E_CPU0_PE1_PCH_CON_TXP<11>")
	)
	(segment
		(start 50.140616 10.69213)
		(end 50.103532 10.729214)
		(width 0.127)
		(layer "F.Cu")
		(net "P3E_CPU0_PE1_PCH_CON_TXP<11>")
	)
	(segment
		(start 64.921384 -5.950966)
		(end 64.72174 -4.819396)
		(width 0.127)
		(layer "F.Cu")
		(net "P3E_CPU0_PE1_PCH_CON_TXP<11>")
	)
	(segment
		(start 50.287682 9.814052)
		(end 50.227484 10.155936)
		(width 0.127)
		(layer "F.Cu")
		(net "P3E_CPU0_PE1_PCH_CON_TXP<11>")
	)
	(segment
		(start 65.079372 -9.250426)
		(end 65.171828 -9.09066)
		(width 0.127)
		(layer "F.Cu")
		(net "P3E_CPU0_PE1_PCH_CON_TXP<11>")
	)
	(segment
		(start 54.948328 2.69113)
		(end 50.39741 9.190482)
		(width 0.127)
		(layer "F.Cu")
		(net "P3E_CPU0_PE1_PCH_CON_TXP<11>")
	)
	(segment
		(start 64.72174 -4.819396)
		(end 63.8048 -3.510026)
		(width 0.127)
		(layer "F.Cu")
		(net "P3E_CPU0_PE1_PCH_CON_TXP<11>")
	)
	(arc
		(start 50.227484 10.482834)
		(mid 50.20491 10.596143)
		(end 50.140616 10.69213)
		(width 0.127)
		(layer "F.Cu")
		(net "P3E_CPU0_PE1_PCH_CON_TXP<11>")
	)
	(arc
		(start 65.285112 -8.297926)
		(mid 65.015926 -7.89506)
		(end 64.921384 -7.419848)
		(width 0.127)
		(layer "F.Cu")
		(net "P3E_CPU0_PE1_PCH_CON_TXP<11>")
	)
	(arc
		(start 50.103532 10.729214)
		(mid 50.01199 10.866406)
		(end 49.979834 11.028172)
		(width 0.127)
		(layer "F.Cu")
		(net "P3E_CPU0_PE1_PCH_CON_TXP<11>")
	)
	(arc
		(start 65.455546 -8.524748)
		(mid 65.462305 -8.427803)
		(end 65.39865 -8.354314)
		(width 0.127)
		(layer "F.Cu")
		(net "P3E_CPU0_PE1_PCH_CON_TXP<11>")
	)
	(segment
		(start 69.407024 -8.502142)
		(end 69.407024 -8.597646)
		(width 0.127)
		(layer "F.Cu")
		(net "P3E_CPU0_PE1_PCH_CON_TXP<10>")
	)
	(segment
		(start 68.751704 -6.01472)
		(end 68.920614 -6.972046)
		(width 0.127)
		(layer "F.Cu")
		(net "P3E_CPU0_PE1_PCH_CON_TXP<10>")
	)
	(segment
		(start 69.139562 -9.155684)
		(end 69.079872 -9.250426)
		(width 0.127)
		(layer "F.Cu")
		(net "P3E_CPU0_PE1_PCH_CON_TXP<10>")
	)
	(segment
		(start 52.503832 10.791952)
		(end 52.504086 10.791698)
		(width 0.127)
		(layer "F.Cu")
		(net "P3E_CPU0_PE1_PCH_CON_TXP<10>")
	)
	(segment
		(start 57.50179 2.406904)
		(end 67.839844 -4.832096)
		(width 0.127)
		(layer "F.Cu")
		(net "P3E_CPU0_PE1_PCH_CON_TXP<10>")
	)
	(segment
		(start 68.126864 -5.122418)
		(end 68.751704 -6.01472)
		(width 0.127)
		(layer "F.Cu")
		(net "P3E_CPU0_PE1_PCH_CON_TXP<10>")
	)
	(segment
		(start 52.62753 10.493248)
		(end 52.62753 10.155682)
		(width 0.127)
		(layer "F.Cu")
		(net "P3E_CPU0_PE1_PCH_CON_TXP<10>")
	)
	(segment
		(start 52.62753 10.155682)
		(end 52.81295 9.10336)
		(width 0.127)
		(layer "F.Cu")
		(net "P3E_CPU0_PE1_PCH_CON_TXP<10>")
	)
	(segment
		(start 52.37988 12.133072)
		(end 52.37988 11.090656)
		(width 0.127)
		(layer "F.Cu")
		(net "P3E_CPU0_PE1_PCH_CON_TXP<10>")
	)
	(segment
		(start 68.12661 -5.118608)
		(end 68.12661 -5.122164)
		(width 0.127)
		(layer "F.Cu")
		(net "P3E_CPU0_PE1_PCH_CON_TXP<10>")
	)
	(segment
		(start 69.284342 -8.297926)
		(end 69.353176 -8.372094)
		(width 0.127)
		(layer "F.Cu")
		(net "P3E_CPU0_PE1_PCH_CON_TXP<10>")
	)
	(segment
		(start 67.839844 -4.832096)
		(end 68.12661 -5.118608)
		(width 0.127)
		(layer "F.Cu")
		(net "P3E_CPU0_PE1_PCH_CON_TXP<10>")
	)
	(segment
		(start 68.12661 -5.122164)
		(end 68.126864 -5.122418)
		(width 0.127)
		(layer "F.Cu")
		(net "P3E_CPU0_PE1_PCH_CON_TXP<10>")
	)
	(segment
		(start 52.81295 9.10336)
		(end 57.50179 2.406904)
		(width 0.127)
		(layer "F.Cu")
		(net "P3E_CPU0_PE1_PCH_CON_TXP<10>")
	)
	(segment
		(start 69.379846 -8.674862)
		(end 69.139562 -9.155684)
		(width 0.127)
		(layer "F.Cu")
		(net "P3E_CPU0_PE1_PCH_CON_TXP<10>")
	)
	(segment
		(start 68.920614 -6.972046)
		(end 68.920614 -7.419848)
		(width 0.127)
		(layer "F.Cu")
		(net "P3E_CPU0_PE1_PCH_CON_TXP<10>")
	)
	(arc
		(start 69.407024 -8.597646)
		(mid 69.395818 -8.637093)
		(end 69.379846 -8.674862)
		(width 0.127)
		(layer "F.Cu")
		(net "P3E_CPU0_PE1_PCH_CON_TXP<10>")
	)
	(arc
		(start 52.37988 11.090656)
		(mid 52.412136 10.928966)
		(end 52.503832 10.791952)
		(width 0.127)
		(layer "F.Cu")
		(net "P3E_CPU0_PE1_PCH_CON_TXP<10>")
	)
	(arc
		(start 52.504086 10.791698)
		(mid 52.595472 10.65474)
		(end 52.62753 10.493248)
		(width 0.127)
		(layer "F.Cu")
		(net "P3E_CPU0_PE1_PCH_CON_TXP<10>")
	)
	(arc
		(start 69.353176 -8.372094)
		(mid 69.393044 -8.431761)
		(end 69.407024 -8.502142)
		(width 0.127)
		(layer "F.Cu")
		(net "P3E_CPU0_PE1_PCH_CON_TXP<10>")
	)
	(arc
		(start 69.241924 -8.253222)
		(mid 69.262855 -8.275838)
		(end 69.284342 -8.297926)
		(width 0.127)
		(layer "F.Cu")
		(net "P3E_CPU0_PE1_PCH_CON_TXP<10>")
	)
	(arc
		(start 69.138546 -8.122412)
		(mid 69.188042 -8.18955)
		(end 69.241924 -8.253222)
		(width 0.127)
		(layer "F.Cu")
		(net "P3E_CPU0_PE1_PCH_CON_TXP<10>")
	)
	(arc
		(start 68.920614 -7.419848)
		(mid 68.976343 -7.787646)
		(end 69.138546 -8.122412)
		(width 0.127)
		(layer "F.Cu")
		(net "P3E_CPU0_PE1_PCH_CON_TXP<10>")
	)
	(segment
		(start 56.867044 7.410196)
		(end 56.648604 7.722362)
		(width 0.127)
		(layer "F.Cu")
		(net "P3E_CPU0_PE1_PCH_CON_TXN<9>")
	)
	(segment
		(start 74.079862 -7.275068)
		(end 73.705466 -8.024876)
		(width 0.127)
		(layer "F.Cu")
		(net "P3E_CPU0_PE1_PCH_CON_TXN<9>")
	)
	(segment
		(start 60.089542 2.502408)
		(end 56.824118 7.166102)
		(width 0.127)
		(layer "F.Cu")
		(net "P3E_CPU0_PE1_PCH_CON_TXN<9>")
	)
	(segment
		(start 55.332376 10.182606)
		(end 55.332376 10.47877)
		(width 0.127)
		(layer "F.Cu")
		(net "P3E_CPU0_PE1_PCH_CON_TXN<9>")
	)
	(segment
		(start 56.010302 8.633714)
		(end 55.766208 8.67664)
		(width 0.127)
		(layer "F.Cu")
		(net "P3E_CPU0_PE1_PCH_CON_TXN<9>")
	)
	(segment
		(start 56.824118 7.166102)
		(end 56.867044 7.410196)
		(width 0.127)
		(layer "F.Cu")
		(net "P3E_CPU0_PE1_PCH_CON_TXN<9>")
	)
	(segment
		(start 55.766208 8.67664)
		(end 55.547768 8.988806)
		(width 0.127)
		(layer "F.Cu")
		(net "P3E_CPU0_PE1_PCH_CON_TXN<9>")
	)
	(segment
		(start 73.534778 -8.081772)
		(end 73.532492 -8.080502)
		(width 0.127)
		(layer "F.Cu")
		(net "P3E_CPU0_PE1_PCH_CON_TXN<9>")
	)
	(segment
		(start 73.176892 -6.902196)
		(end 72.845168 -6.42874)
		(width 0.127)
		(layer "F.Cu")
		(net "P3E_CPU0_PE1_PCH_CON_TXN<9>")
	)
	(segment
		(start 55.580026 11.076432)
		(end 55.580026 12.133072)
		(width 0.127)
		(layer "F.Cu")
		(net "P3E_CPU0_PE1_PCH_CON_TXN<9>")
	)
	(segment
		(start 56.185816 8.077454)
		(end 56.228996 8.321548)
		(width 0.127)
		(layer "F.Cu")
		(net "P3E_CPU0_PE1_PCH_CON_TXN<9>")
	)
	(segment
		(start 56.40451 7.765288)
		(end 56.185816 8.077454)
		(width 0.127)
		(layer "F.Cu")
		(net "P3E_CPU0_PE1_PCH_CON_TXN<9>")
	)
	(segment
		(start 55.547768 8.988806)
		(end 55.332376 10.182606)
		(width 0.127)
		(layer "F.Cu")
		(net "P3E_CPU0_PE1_PCH_CON_TXN<9>")
	)
	(segment
		(start 56.648604 7.722362)
		(end 56.40451 7.765288)
		(width 0.127)
		(layer "F.Cu")
		(net "P3E_CPU0_PE1_PCH_CON_TXN<9>")
	)
	(segment
		(start 73.532492 -8.080502)
		(end 73.468484 -8.048752)
		(width 0.127)
		(layer "F.Cu")
		(net "P3E_CPU0_PE1_PCH_CON_TXN<9>")
	)
	(segment
		(start 72.845168 -6.42874)
		(end 60.089542 2.502408)
		(width 0.127)
		(layer "F.Cu")
		(net "P3E_CPU0_PE1_PCH_CON_TXN<9>")
	)
	(segment
		(start 73.225914 -7.419594)
		(end 73.176892 -6.902196)
		(width 0.127)
		(layer "F.Cu")
		(net "P3E_CPU0_PE1_PCH_CON_TXN<9>")
	)
	(segment
		(start 56.228996 8.321548)
		(end 56.010302 8.633714)
		(width 0.127)
		(layer "F.Cu")
		(net "P3E_CPU0_PE1_PCH_CON_TXN<9>")
	)
	(segment
		(start 74.079862 -7.250176)
		(end 74.079862 -7.275068)
		(width 0.127)
		(layer "F.Cu")
		(net "P3E_CPU0_PE1_PCH_CON_TXN<9>")
	)
	(segment
		(start 73.535032 -8.081772)
		(end 73.534778 -8.081772)
		(width 0.127)
		(layer "F.Cu")
		(net "P3E_CPU0_PE1_PCH_CON_TXN<9>")
	)
	(arc
		(start 73.468484 -8.048752)
		(mid 73.288618 -7.756754)
		(end 73.225914 -7.419594)
		(width 0.127)
		(layer "F.Cu")
		(net "P3E_CPU0_PE1_PCH_CON_TXN<9>")
	)
	(arc
		(start 55.456328 10.777728)
		(mid 55.5479 10.914775)
		(end 55.580026 11.076432)
		(width 0.127)
		(layer "F.Cu")
		(net "P3E_CPU0_PE1_PCH_CON_TXN<9>")
	)
	(arc
		(start 55.332376 10.47877)
		(mid 55.364598 10.640582)
		(end 55.456328 10.777728)
		(width 0.127)
		(layer "F.Cu")
		(net "P3E_CPU0_PE1_PCH_CON_TXN<9>")
	)
	(arc
		(start 73.705466 -8.024876)
		(mid 73.632052 -8.088605)
		(end 73.535032 -8.081772)
		(width 0.127)
		(layer "F.Cu")
		(net "P3E_CPU0_PE1_PCH_CON_TXN<9>")
	)
	(segment
		(start 77.542644 -8.092694)
		(end 77.54239 -8.092694)
		(width 0.127)
		(layer "F.Cu")
		(net "P3E_CPU0_PE1_PCH_CON_TXN<8>")
	)
	(segment
		(start 76.515722 -6.09981)
		(end 76.398374 -6.051296)
		(width 0.127)
		(layer "F.Cu")
		(net "P3E_CPU0_PE1_PCH_CON_TXN<8>")
	)
	(segment
		(start 76.398374 -6.051296)
		(end 73.721722 -5.579364)
		(width 0.127)
		(layer "F.Cu")
		(net "P3E_CPU0_PE1_PCH_CON_TXN<8>")
	)
	(segment
		(start 57.979818 11.038078)
		(end 57.979818 12.133072)
		(width 0.127)
		(layer "F.Cu")
		(net "P3E_CPU0_PE1_PCH_CON_TXN<8>")
	)
	(segment
		(start 58.901838 7.18439)
		(end 58.683144 7.496556)
		(width 0.127)
		(layer "F.Cu")
		(net "P3E_CPU0_PE1_PCH_CON_TXN<8>")
	)
	(segment
		(start 59.145932 7.141464)
		(end 58.901838 7.18439)
		(width 0.127)
		(layer "F.Cu")
		(net "P3E_CPU0_PE1_PCH_CON_TXN<8>")
	)
	(segment
		(start 76.634594 -6.145022)
		(end 76.520548 -6.097524)
		(width 0.127)
		(layer "F.Cu")
		(net "P3E_CPU0_PE1_PCH_CON_TXN<8>")
	)
	(segment
		(start 78.080362 -7.250176)
		(end 78.001622 -7.432802)
		(width 0.127)
		(layer "F.Cu")
		(net "P3E_CPU0_PE1_PCH_CON_TXN<8>")
	)
	(segment
		(start 77.226414 -7.419594)
		(end 77.226414 -6.98627)
		(width 0.127)
		(layer "F.Cu")
		(net "P3E_CPU0_PE1_PCH_CON_TXN<8>")
	)
	(segment
		(start 58.683144 7.496556)
		(end 58.726324 7.74065)
		(width 0.127)
		(layer "F.Cu")
		(net "P3E_CPU0_PE1_PCH_CON_TXN<8>")
	)
	(segment
		(start 62.2427 2.45745)
		(end 62.239144 2.45745)
		(width 0.127)
		(layer "F.Cu")
		(net "P3E_CPU0_PE1_PCH_CON_TXN<8>")
	)
	(segment
		(start 77.226414 -6.98627)
		(end 77.173582 -6.68655)
		(width 0.127)
		(layer "F.Cu")
		(net "P3E_CPU0_PE1_PCH_CON_TXN<8>")
	)
	(segment
		(start 62.242954 2.457196)
		(end 62.2427 2.45745)
		(width 0.127)
		(layer "F.Cu")
		(net "P3E_CPU0_PE1_PCH_CON_TXN<8>")
	)
	(segment
		(start 58.726324 7.74065)
		(end 58.50763 8.052816)
		(width 0.127)
		(layer "F.Cu")
		(net "P3E_CPU0_PE1_PCH_CON_TXN<8>")
	)
	(segment
		(start 76.948538 -6.364986)
		(end 76.634594 -6.145022)
		(width 0.127)
		(layer "F.Cu")
		(net "P3E_CPU0_PE1_PCH_CON_TXN<8>")
	)
	(segment
		(start 59.321446 6.585204)
		(end 59.364372 6.829298)
		(width 0.127)
		(layer "F.Cu")
		(net "P3E_CPU0_PE1_PCH_CON_TXN<8>")
	)
	(segment
		(start 77.173582 -6.68655)
		(end 76.948538 -6.364986)
		(width 0.127)
		(layer "F.Cu")
		(net "P3E_CPU0_PE1_PCH_CON_TXN<8>")
	)
	(segment
		(start 76.520548 -6.097524)
		(end 76.515722 -6.09981)
		(width 0.127)
		(layer "F.Cu")
		(net "P3E_CPU0_PE1_PCH_CON_TXN<8>")
	)
	(segment
		(start 73.721722 -5.579364)
		(end 62.242954 2.457196)
		(width 0.127)
		(layer "F.Cu")
		(net "P3E_CPU0_PE1_PCH_CON_TXN<8>")
	)
	(segment
		(start 78.001622 -7.432802)
		(end 77.705966 -8.024876)
		(width 0.127)
		(layer "F.Cu")
		(net "P3E_CPU0_PE1_PCH_CON_TXN<8>")
	)
	(segment
		(start 62.239144 2.45745)
		(end 62.147704 2.54889)
		(width 0.127)
		(layer "F.Cu")
		(net "P3E_CPU0_PE1_PCH_CON_TXN<8>")
	)
	(segment
		(start 58.50763 8.052816)
		(end 58.263536 8.095742)
		(width 0.127)
		(layer "F.Cu")
		(net "P3E_CPU0_PE1_PCH_CON_TXN<8>")
	)
	(segment
		(start 62.147704 2.54889)
		(end 59.321446 6.585204)
		(width 0.127)
		(layer "F.Cu")
		(net "P3E_CPU0_PE1_PCH_CON_TXN<8>")
	)
	(segment
		(start 58.045096 8.407908)
		(end 57.904126 9.21131)
		(width 0.127)
		(layer "F.Cu")
		(net "P3E_CPU0_PE1_PCH_CON_TXN<8>")
	)
	(segment
		(start 57.732168 10.182606)
		(end 57.732168 10.440162)
		(width 0.127)
		(layer "F.Cu")
		(net "P3E_CPU0_PE1_PCH_CON_TXN<8>")
	)
	(segment
		(start 58.263536 8.095742)
		(end 58.045096 8.407908)
		(width 0.127)
		(layer "F.Cu")
		(net "P3E_CPU0_PE1_PCH_CON_TXN<8>")
	)
	(segment
		(start 59.364372 6.829298)
		(end 59.145932 7.141464)
		(width 0.127)
		(layer "F.Cu")
		(net "P3E_CPU0_PE1_PCH_CON_TXN<8>")
	)
	(segment
		(start 57.904126 9.21131)
		(end 57.732168 10.182606)
		(width 0.127)
		(layer "F.Cu")
		(net "P3E_CPU0_PE1_PCH_CON_TXN<8>")
	)
	(arc
		(start 77.54239 -8.092694)
		(mid 77.541118 -8.092319)
		(end 77.53985 -8.091932)
		(width 0.127)
		(layer "F.Cu")
		(net "P3E_CPU0_PE1_PCH_CON_TXN<8>")
	)
	(arc
		(start 57.855866 10.738866)
		(mid 57.947593 10.876146)
		(end 57.979818 11.038078)
		(width 0.127)
		(layer "F.Cu")
		(net "P3E_CPU0_PE1_PCH_CON_TXN<8>")
	)
	(arc
		(start 57.732168 10.440162)
		(mid 57.764321 10.601808)
		(end 57.855866 10.738866)
		(width 0.127)
		(layer "F.Cu")
		(net "P3E_CPU0_PE1_PCH_CON_TXN<8>")
	)
	(arc
		(start 77.468984 -8.048752)
		(mid 77.289118 -7.756754)
		(end 77.226414 -7.419594)
		(width 0.127)
		(layer "F.Cu")
		(net "P3E_CPU0_PE1_PCH_CON_TXN<8>")
	)
	(arc
		(start 77.705966 -8.024876)
		(mid 77.63555 -8.085904)
		(end 77.542644 -8.092694)
		(width 0.127)
		(layer "F.Cu")
		(net "P3E_CPU0_PE1_PCH_CON_TXN<8>")
	)
	(arc
		(start 77.53985 -8.091932)
		(mid 77.501319 -8.075425)
		(end 77.468984 -8.048752)
		(width 0.127)
		(layer "F.Cu")
		(net "P3E_CPU0_PE1_PCH_CON_TXN<8>")
	)
	(segment
		(start 47.079662 -9.250426)
		(end 46.704758 -8.499856)
		(width 0.127)
		(layer "F.Cu")
		(net "P3E_CPU0_PE1_PCH_CON_TXN<15>")
	)
	(segment
		(start 50.044604 -0.978408)
		(end 49.99228 -0.893572)
		(width 0.127)
		(layer "F.Cu")
		(net "P3E_CPU0_PE1_PCH_CON_TXN<15>")
	)
	(segment
		(start 47.2567 -7.35203)
		(end 47.2567 -7.060946)
		(width 0.127)
		(layer "F.Cu")
		(net "P3E_CPU0_PE1_PCH_CON_TXN<15>")
	)
	(segment
		(start 46.761654 -8.329422)
		(end 46.761908 -8.329422)
		(width 0.127)
		(layer "F.Cu")
		(net "P3E_CPU0_PE1_PCH_CON_TXN<15>")
	)
	(segment
		(start 46.091348 4.619498)
		(end 45.758608 4.87172)
		(width 0.127)
		(layer "F.Cu")
		(net "P3E_CPU0_PE1_PCH_CON_TXN<15>")
	)
	(segment
		(start 47.2567 -7.060946)
		(end 47.338996 -6.881368)
		(width 0.127)
		(layer "F.Cu")
		(net "P3E_CPU0_PE1_PCH_CON_TXN<15>")
	)
	(segment
		(start 45.746924 4.880356)
		(end 45.7454 4.8895)
		(width 0.127)
		(layer "F.Cu")
		(net "P3E_CPU0_PE1_PCH_CON_TXN<15>")
	)
	(segment
		(start 49.68367 -4.529328)
		(end 50.253646 -2.883154)
		(width 0.127)
		(layer "F.Cu")
		(net "P3E_CPU0_PE1_PCH_CON_TXN<15>")
	)
	(segment
		(start 46.761908 -8.329422)
		(end 46.875192 -8.273034)
		(width 0.127)
		(layer "F.Cu")
		(net "P3E_CPU0_PE1_PCH_CON_TXN<15>")
	)
	(segment
		(start 50.269394 -2.808986)
		(end 50.30851 -2.382774)
		(width 0.127)
		(layer "F.Cu")
		(net "P3E_CPU0_PE1_PCH_CON_TXN<15>")
	)
	(segment
		(start 36.132262 9.944862)
		(end 36.132262 10.430256)
		(width 0.127)
		(layer "F.Cu")
		(net "P3E_CPU0_PE1_PCH_CON_TXN<15>")
	)
	(segment
		(start 50.30851 -2.382774)
		(end 50.044604 -0.978408)
		(width 0.127)
		(layer "F.Cu")
		(net "P3E_CPU0_PE1_PCH_CON_TXN<15>")
	)
	(segment
		(start 47.376334 -6.792722)
		(end 47.4599 -6.6167)
		(width 0.127)
		(layer "F.Cu")
		(net "P3E_CPU0_PE1_PCH_CON_TXN<15>")
	)
	(segment
		(start 49.4157 -4.781042)
		(end 49.68367 -4.529328)
		(width 0.127)
		(layer "F.Cu")
		(net "P3E_CPU0_PE1_PCH_CON_TXN<15>")
	)
	(segment
		(start 49.99228 -0.893572)
		(end 46.091348 4.619498)
		(width 0.127)
		(layer "F.Cu")
		(net "P3E_CPU0_PE1_PCH_CON_TXN<15>")
	)
	(segment
		(start 36.379912 10.975594)
		(end 36.379912 12.133072)
		(width 0.127)
		(layer "F.Cu")
		(net "P3E_CPU0_PE1_PCH_CON_TXN<15>")
	)
	(segment
		(start 49.290732 -4.898136)
		(end 49.4157 -4.781042)
		(width 0.127)
		(layer "F.Cu")
		(net "P3E_CPU0_PE1_PCH_CON_TXN<15>")
	)
	(segment
		(start 40.767508 6.168644)
		(end 36.725098 8.999474)
		(width 0.127)
		(layer "F.Cu")
		(net "P3E_CPU0_PE1_PCH_CON_TXN<15>")
	)
	(segment
		(start 36.15563 9.812528)
		(end 36.132262 9.944862)
		(width 0.127)
		(layer "F.Cu")
		(net "P3E_CPU0_PE1_PCH_CON_TXN<15>")
	)
	(segment
		(start 45.758608 4.87172)
		(end 45.746924 4.880356)
		(width 0.127)
		(layer "F.Cu")
		(net "P3E_CPU0_PE1_PCH_CON_TXN<15>")
	)
	(segment
		(start 43.4721 5.7531)
		(end 40.767508 6.168644)
		(width 0.127)
		(layer "F.Cu")
		(net "P3E_CPU0_PE1_PCH_CON_TXN<15>")
	)
	(segment
		(start 50.253646 -2.883154)
		(end 50.269394 -2.808986)
		(width 0.127)
		(layer "F.Cu")
		(net "P3E_CPU0_PE1_PCH_CON_TXN<15>")
	)
	(segment
		(start 47.4599 -6.6167)
		(end 49.290732 -4.898136)
		(width 0.127)
		(layer "F.Cu")
		(net "P3E_CPU0_PE1_PCH_CON_TXN<15>")
	)
	(segment
		(start 45.7454 4.8895)
		(end 43.4721 5.7531)
		(width 0.127)
		(layer "F.Cu")
		(net "P3E_CPU0_PE1_PCH_CON_TXN<15>")
	)
	(segment
		(start 47.338996 -6.881368)
		(end 47.376334 -6.792722)
		(width 0.127)
		(layer "F.Cu")
		(net "P3E_CPU0_PE1_PCH_CON_TXN<15>")
	)
	(segment
		(start 36.25596 10.729214)
		(end 36.293044 10.766298)
		(width 0.127)
		(layer "F.Cu")
		(net "P3E_CPU0_PE1_PCH_CON_TXN<15>")
	)
	(segment
		(start 36.725098 8.999474)
		(end 36.15563 9.812528)
		(width 0.127)
		(layer "F.Cu")
		(net "P3E_CPU0_PE1_PCH_CON_TXN<15>")
	)
	(arc
		(start 36.293044 10.766298)
		(mid 36.357314 10.862295)
		(end 36.379912 10.975594)
		(width 0.127)
		(layer "F.Cu")
		(net "P3E_CPU0_PE1_PCH_CON_TXN<15>")
	)
	(arc
		(start 36.132262 10.430256)
		(mid 36.164405 10.592028)
		(end 36.25596 10.729214)
		(width 0.127)
		(layer "F.Cu")
		(net "P3E_CPU0_PE1_PCH_CON_TXN<15>")
	)
	(arc
		(start 46.704758 -8.499856)
		(mid 46.697999 -8.402911)
		(end 46.761654 -8.329422)
		(width 0.127)
		(layer "F.Cu")
		(net "P3E_CPU0_PE1_PCH_CON_TXN<15>")
	)
	(arc
		(start 46.875192 -8.273034)
		(mid 47.157538 -7.850474)
		(end 47.2567 -7.35203)
		(width 0.127)
		(layer "F.Cu")
		(net "P3E_CPU0_PE1_PCH_CON_TXN<15>")
	)
	(segment
		(start 51.868832 -2.9845)
		(end 51.84267 -2.455418)
		(width 0.127)
		(layer "F.Cu")
		(net "P3E_CPU0_PE1_PCH_CON_TXN<14>")
	)
	(segment
		(start 39.167816 8.90397)
		(end 39.167816 8.907018)
		(width 0.127)
		(layer "F.Cu")
		(net "P3E_CPU0_PE1_PCH_CON_TXN<14>")
	)
	(segment
		(start 51.381914 -6.463284)
		(end 51.583082 -6.318504)
		(width 0.127)
		(layer "F.Cu")
		(net "P3E_CPU0_PE1_PCH_CON_TXN<14>")
	)
	(segment
		(start 51.532282 -8.080502)
		(end 51.468274 -8.048752)
		(width 0.127)
		(layer "F.Cu")
		(net "P3E_CPU0_PE1_PCH_CON_TXN<14>")
	)
	(segment
		(start 44.339002 6.900926)
		(end 43.053 7.0739)
		(width 0.127)
		(layer "F.Cu")
		(net "P3E_CPU0_PE1_PCH_CON_TXN<14>")
	)
	(segment
		(start 38.532308 9.9568)
		(end 38.532308 10.468102)
		(width 0.127)
		(layer "F.Cu")
		(net "P3E_CPU0_PE1_PCH_CON_TXN<14>")
	)
	(segment
		(start 51.823366 -4.844288)
		(end 51.678586 -4.64312)
		(width 0.127)
		(layer "F.Cu")
		(net "P3E_CPU0_PE1_PCH_CON_TXN<14>")
	)
	(segment
		(start 51.225958 -7.41934)
		(end 51.381914 -6.463284)
		(width 0.127)
		(layer "F.Cu")
		(net "P3E_CPU0_PE1_PCH_CON_TXN<14>")
	)
	(segment
		(start 46.735746 5.7912)
		(end 44.339002 6.900926)
		(width 0.127)
		(layer "F.Cu")
		(net "P3E_CPU0_PE1_PCH_CON_TXN<14>")
	)
	(segment
		(start 39.259256 8.81253)
		(end 39.167816 8.90397)
		(width 0.127)
		(layer "F.Cu")
		(net "P3E_CPU0_PE1_PCH_CON_TXN<14>")
	)
	(segment
		(start 51.644296 -5.94233)
		(end 51.499516 -5.741162)
		(width 0.127)
		(layer "F.Cu")
		(net "P3E_CPU0_PE1_PCH_CON_TXN<14>")
	)
	(segment
		(start 51.534568 -8.081772)
		(end 51.532282 -8.080502)
		(width 0.127)
		(layer "F.Cu")
		(net "P3E_CPU0_PE1_PCH_CON_TXN<14>")
	)
	(segment
		(start 51.868832 -3.475482)
		(end 51.868832 -2.9845)
		(width 0.127)
		(layer "F.Cu")
		(net "P3E_CPU0_PE1_PCH_CON_TXN<14>")
	)
	(segment
		(start 51.56073 -5.365242)
		(end 51.761898 -5.220462)
		(width 0.127)
		(layer "F.Cu")
		(net "P3E_CPU0_PE1_PCH_CON_TXN<14>")
	)
	(segment
		(start 51.534822 -8.081772)
		(end 51.534568 -8.081772)
		(width 0.127)
		(layer "F.Cu")
		(net "P3E_CPU0_PE1_PCH_CON_TXN<14>")
	)
	(segment
		(start 51.84521 -7.74446)
		(end 51.705256 -8.024876)
		(width 0.127)
		(layer "F.Cu")
		(net "P3E_CPU0_PE1_PCH_CON_TXN<14>")
	)
	(segment
		(start 41.6433 7.2644)
		(end 39.259256 8.81253)
		(width 0.127)
		(layer "F.Cu")
		(net "P3E_CPU0_PE1_PCH_CON_TXN<14>")
	)
	(segment
		(start 51.583082 -6.318504)
		(end 51.644296 -5.94233)
		(width 0.127)
		(layer "F.Cu")
		(net "P3E_CPU0_PE1_PCH_CON_TXN<14>")
	)
	(segment
		(start 51.678586 -4.64312)
		(end 51.7398 -4.2672)
		(width 0.127)
		(layer "F.Cu")
		(net "P3E_CPU0_PE1_PCH_CON_TXN<14>")
	)
	(segment
		(start 38.565836 9.766554)
		(end 38.532308 9.9568)
		(width 0.127)
		(layer "F.Cu")
		(net "P3E_CPU0_PE1_PCH_CON_TXN<14>")
	)
	(segment
		(start 51.429412 -0.72136)
		(end 46.735746 5.7912)
		(width 0.127)
		(layer "F.Cu")
		(net "P3E_CPU0_PE1_PCH_CON_TXN<14>")
	)
	(segment
		(start 52.079652 -7.250176)
		(end 51.84521 -7.74446)
		(width 0.127)
		(layer "F.Cu")
		(net "P3E_CPU0_PE1_PCH_CON_TXN<14>")
	)
	(segment
		(start 39.167308 8.907526)
		(end 38.565836 9.766554)
		(width 0.127)
		(layer "F.Cu")
		(net "P3E_CPU0_PE1_PCH_CON_TXN<14>")
	)
	(segment
		(start 38.779958 11.065764)
		(end 38.779958 12.133072)
		(width 0.127)
		(layer "F.Cu")
		(net "P3E_CPU0_PE1_PCH_CON_TXN<14>")
	)
	(segment
		(start 51.499516 -5.741162)
		(end 51.56073 -5.365242)
		(width 0.127)
		(layer "F.Cu")
		(net "P3E_CPU0_PE1_PCH_CON_TXN<14>")
	)
	(segment
		(start 51.761898 -5.220462)
		(end 51.823366 -4.844288)
		(width 0.127)
		(layer "F.Cu")
		(net "P3E_CPU0_PE1_PCH_CON_TXN<14>")
	)
	(segment
		(start 51.7398 -4.2672)
		(end 51.868832 -3.475482)
		(width 0.127)
		(layer "F.Cu")
		(net "P3E_CPU0_PE1_PCH_CON_TXN<14>")
	)
	(segment
		(start 51.81092 -2.423668)
		(end 51.429412 -0.72136)
		(width 0.127)
		(layer "F.Cu")
		(net "P3E_CPU0_PE1_PCH_CON_TXN<14>")
	)
	(segment
		(start 43.053 7.0739)
		(end 41.6433 7.2644)
		(width 0.127)
		(layer "F.Cu")
		(net "P3E_CPU0_PE1_PCH_CON_TXN<14>")
	)
	(segment
		(start 51.84267 -2.455418)
		(end 51.81092 -2.423668)
		(width 0.127)
		(layer "F.Cu")
		(net "P3E_CPU0_PE1_PCH_CON_TXN<14>")
	)
	(segment
		(start 39.167816 8.907018)
		(end 39.167308 8.907526)
		(width 0.127)
		(layer "F.Cu")
		(net "P3E_CPU0_PE1_PCH_CON_TXN<14>")
	)
	(arc
		(start 38.65626 10.76706)
		(mid 38.747832 10.904107)
		(end 38.779958 11.065764)
		(width 0.127)
		(layer "F.Cu")
		(net "P3E_CPU0_PE1_PCH_CON_TXN<14>")
	)
	(arc
		(start 38.532308 10.468102)
		(mid 38.56453 10.629914)
		(end 38.65626 10.76706)
		(width 0.127)
		(layer "F.Cu")
		(net "P3E_CPU0_PE1_PCH_CON_TXN<14>")
	)
	(arc
		(start 51.705256 -8.024876)
		(mid 51.631842 -8.088605)
		(end 51.534822 -8.081772)
		(width 0.127)
		(layer "F.Cu")
		(net "P3E_CPU0_PE1_PCH_CON_TXN<14>")
	)
	(arc
		(start 51.468274 -8.048752)
		(mid 51.288569 -7.756596)
		(end 51.225958 -7.41934)
		(width 0.127)
		(layer "F.Cu")
		(net "P3E_CPU0_PE1_PCH_CON_TXN<14>")
	)
	(segment
		(start 50.476912 2.835148)
		(end 53.775102 -1.875028)
		(width 0.127)
		(layer "F.Cu")
		(net "P3E_CPU0_PE1_PCH_CON_TXN<13>")
	)
	(segment
		(start 55.846218 -7.743698)
		(end 56.080152 -7.250176)
		(width 0.127)
		(layer "F.Cu")
		(net "P3E_CPU0_PE1_PCH_CON_TXN<13>")
	)
	(segment
		(start 55.468774 -8.048752)
		(end 55.532782 -8.080502)
		(width 0.127)
		(layer "F.Cu")
		(net "P3E_CPU0_PE1_PCH_CON_TXN<13>")
	)
	(segment
		(start 53.775102 -1.875028)
		(end 53.951886 -2.127504)
		(width 0.127)
		(layer "F.Cu")
		(net "P3E_CPU0_PE1_PCH_CON_TXN<13>")
	)
	(segment
		(start 45.732192 10.505186)
		(end 45.732192 10.182606)
		(width 0.127)
		(layer "F.Cu")
		(net "P3E_CPU0_PE1_PCH_CON_TXN<13>")
	)
	(segment
		(start 46.085506 9.1059)
		(end 46.3296 9.062974)
		(width 0.127)
		(layer "F.Cu")
		(net "P3E_CPU0_PE1_PCH_CON_TXN<13>")
	)
	(segment
		(start 46.548294 8.750808)
		(end 46.505114 8.506714)
		(width 0.127)
		(layer "F.Cu")
		(net "P3E_CPU0_PE1_PCH_CON_TXN<13>")
	)
	(segment
		(start 46.967902 8.151622)
		(end 47.186342 7.839456)
		(width 0.127)
		(layer "F.Cu")
		(net "P3E_CPU0_PE1_PCH_CON_TXN<13>")
	)
	(segment
		(start 53.951886 -2.127504)
		(end 54.509924 -2.924556)
		(width 0.127)
		(layer "F.Cu")
		(net "P3E_CPU0_PE1_PCH_CON_TXN<13>")
	)
	(segment
		(start 55.535068 -8.081772)
		(end 55.535322 -8.081772)
		(width 0.127)
		(layer "F.Cu")
		(net "P3E_CPU0_PE1_PCH_CON_TXN<13>")
	)
	(segment
		(start 55.226204 -6.98754)
		(end 55.226204 -7.419594)
		(width 0.127)
		(layer "F.Cu")
		(net "P3E_CPU0_PE1_PCH_CON_TXN<13>")
	)
	(segment
		(start 45.979842 12.133072)
		(end 45.979842 11.102848)
		(width 0.127)
		(layer "F.Cu")
		(net "P3E_CPU0_PE1_PCH_CON_TXN<13>")
	)
	(segment
		(start 55.705756 -8.024876)
		(end 55.846218 -7.743698)
		(width 0.127)
		(layer "F.Cu")
		(net "P3E_CPU0_PE1_PCH_CON_TXN<13>")
	)
	(segment
		(start 50.057304 3.434334)
		(end 50.476912 2.835148)
		(width 0.127)
		(layer "F.Cu")
		(net "P3E_CPU0_PE1_PCH_CON_TXN<13>")
	)
	(segment
		(start 47.186342 7.839456)
		(end 47.143416 7.595362)
		(width 0.127)
		(layer "F.Cu")
		(net "P3E_CPU0_PE1_PCH_CON_TXN<13>")
	)
	(segment
		(start 55.532782 -8.080502)
		(end 55.535068 -8.081772)
		(width 0.127)
		(layer "F.Cu")
		(net "P3E_CPU0_PE1_PCH_CON_TXN<13>")
	)
	(segment
		(start 54.509924 -2.924556)
		(end 55.226204 -6.98754)
		(width 0.127)
		(layer "F.Cu")
		(net "P3E_CPU0_PE1_PCH_CON_TXN<13>")
	)
	(segment
		(start 45.732192 10.182606)
		(end 45.867066 9.418066)
		(width 0.127)
		(layer "F.Cu")
		(net "P3E_CPU0_PE1_PCH_CON_TXN<13>")
	)
	(segment
		(start 45.867066 9.418066)
		(end 46.085506 9.1059)
		(width 0.127)
		(layer "F.Cu")
		(net "P3E_CPU0_PE1_PCH_CON_TXN<13>")
	)
	(segment
		(start 47.143416 7.595362)
		(end 50.057304 3.434334)
		(width 0.127)
		(layer "F.Cu")
		(net "P3E_CPU0_PE1_PCH_CON_TXN<13>")
	)
	(segment
		(start 46.505114 8.506714)
		(end 46.723808 8.194802)
		(width 0.127)
		(layer "F.Cu")
		(net "P3E_CPU0_PE1_PCH_CON_TXN<13>")
	)
	(segment
		(start 46.3296 9.062974)
		(end 46.548294 8.750808)
		(width 0.127)
		(layer "F.Cu")
		(net "P3E_CPU0_PE1_PCH_CON_TXN<13>")
	)
	(segment
		(start 46.723808 8.194802)
		(end 46.967902 8.151622)
		(width 0.127)
		(layer "F.Cu")
		(net "P3E_CPU0_PE1_PCH_CON_TXN<13>")
	)
	(arc
		(start 45.979842 11.102848)
		(mid 45.947689 10.941202)
		(end 45.856144 10.804144)
		(width 0.127)
		(layer "F.Cu")
		(net "P3E_CPU0_PE1_PCH_CON_TXN<13>")
	)
	(arc
		(start 55.535322 -8.081772)
		(mid 55.632378 -8.088713)
		(end 55.705756 -8.024876)
		(width 0.127)
		(layer "F.Cu")
		(net "P3E_CPU0_PE1_PCH_CON_TXN<13>")
	)
	(arc
		(start 45.856144 10.804144)
		(mid 45.764387 10.667009)
		(end 45.732192 10.505186)
		(width 0.127)
		(layer "F.Cu")
		(net "P3E_CPU0_PE1_PCH_CON_TXN<13>")
	)
	(arc
		(start 55.226204 -7.419594)
		(mid 55.288958 -7.756734)
		(end 55.468774 -8.048752)
		(width 0.127)
		(layer "F.Cu")
		(net "P3E_CPU0_PE1_PCH_CON_TXN<13>")
	)
	(segment
		(start 48.960278 8.341106)
		(end 49.178972 8.02894)
		(width 0.127)
		(layer "F.Cu")
		(net "P3E_CPU0_PE1_PCH_CON_TXN<12>")
	)
	(segment
		(start 59.468004 -8.048752)
		(end 59.532012 -8.080502)
		(width 0.127)
		(layer "F.Cu")
		(net "P3E_CPU0_PE1_PCH_CON_TXN<12>")
	)
	(segment
		(start 49.59858 7.429754)
		(end 52.512214 3.268472)
		(width 0.127)
		(layer "F.Cu")
		(net "P3E_CPU0_PE1_PCH_CON_TXN<12>")
	)
	(segment
		(start 48.32223 9.252458)
		(end 48.54067 8.940292)
		(width 0.127)
		(layer "F.Cu")
		(net "P3E_CPU0_PE1_PCH_CON_TXN<12>")
	)
	(segment
		(start 48.379888 12.133072)
		(end 48.379888 11.090148)
		(width 0.127)
		(layer "F.Cu")
		(net "P3E_CPU0_PE1_PCH_CON_TXN<12>")
	)
	(segment
		(start 59.065668 -6.069838)
		(end 59.225434 -6.977634)
		(width 0.127)
		(layer "F.Cu")
		(net "P3E_CPU0_PE1_PCH_CON_TXN<12>")
	)
	(segment
		(start 59.532012 -8.080502)
		(end 59.534298 -8.081772)
		(width 0.127)
		(layer "F.Cu")
		(net "P3E_CPU0_PE1_PCH_CON_TXN<12>")
	)
	(segment
		(start 48.54067 8.940292)
		(end 48.784764 8.897366)
		(width 0.127)
		(layer "F.Cu")
		(net "P3E_CPU0_PE1_PCH_CON_TXN<12>")
	)
	(segment
		(start 49.641506 7.673848)
		(end 49.59858 7.429754)
		(width 0.127)
		(layer "F.Cu")
		(net "P3E_CPU0_PE1_PCH_CON_TXN<12>")
	)
	(segment
		(start 59.534298 -8.081772)
		(end 59.534552 -8.081772)
		(width 0.127)
		(layer "F.Cu")
		(net "P3E_CPU0_PE1_PCH_CON_TXN<12>")
	)
	(segment
		(start 48.272192 9.373362)
		(end 48.32223 9.252458)
		(width 0.127)
		(layer "F.Cu")
		(net "P3E_CPU0_PE1_PCH_CON_TXN<12>")
	)
	(segment
		(start 48.784764 8.897366)
		(end 49.003458 8.5852)
		(width 0.127)
		(layer "F.Cu")
		(net "P3E_CPU0_PE1_PCH_CON_TXN<12>")
	)
	(segment
		(start 52.931822 2.669286)
		(end 59.016392 -6.020308)
		(width 0.127)
		(layer "F.Cu")
		(net "P3E_CPU0_PE1_PCH_CON_TXN<12>")
	)
	(segment
		(start 48.27397 9.378188)
		(end 48.272192 9.373362)
		(width 0.127)
		(layer "F.Cu")
		(net "P3E_CPU0_PE1_PCH_CON_TXN<12>")
	)
	(segment
		(start 49.423066 7.986014)
		(end 49.641506 7.673848)
		(width 0.127)
		(layer "F.Cu")
		(net "P3E_CPU0_PE1_PCH_CON_TXN<12>")
	)
	(segment
		(start 48.132238 10.182606)
		(end 48.27397 9.378188)
		(width 0.127)
		(layer "F.Cu")
		(net "P3E_CPU0_PE1_PCH_CON_TXN<12>")
	)
	(segment
		(start 59.892184 -7.649972)
		(end 60.079382 -7.250176)
		(width 0.127)
		(layer "F.Cu")
		(net "P3E_CPU0_PE1_PCH_CON_TXN<12>")
	)
	(segment
		(start 49.003458 8.5852)
		(end 48.960278 8.341106)
		(width 0.127)
		(layer "F.Cu")
		(net "P3E_CPU0_PE1_PCH_CON_TXN<12>")
	)
	(segment
		(start 52.512214 3.268472)
		(end 52.931822 2.669286)
		(width 0.127)
		(layer "F.Cu")
		(net "P3E_CPU0_PE1_PCH_CON_TXN<12>")
	)
	(segment
		(start 49.178972 8.02894)
		(end 49.423066 7.986014)
		(width 0.127)
		(layer "F.Cu")
		(net "P3E_CPU0_PE1_PCH_CON_TXN<12>")
	)
	(segment
		(start 59.016392 -6.020308)
		(end 59.065668 -6.069838)
		(width 0.127)
		(layer "F.Cu")
		(net "P3E_CPU0_PE1_PCH_CON_TXN<12>")
	)
	(segment
		(start 59.225434 -6.977634)
		(end 59.225434 -7.419594)
		(width 0.127)
		(layer "F.Cu")
		(net "P3E_CPU0_PE1_PCH_CON_TXN<12>")
	)
	(segment
		(start 48.132238 10.492232)
		(end 48.132238 10.182606)
		(width 0.127)
		(layer "F.Cu")
		(net "P3E_CPU0_PE1_PCH_CON_TXN<12>")
	)
	(segment
		(start 59.704986 -8.024876)
		(end 59.892184 -7.649972)
		(width 0.127)
		(layer "F.Cu")
		(net "P3E_CPU0_PE1_PCH_CON_TXN<12>")
	)
	(arc
		(start 59.534552 -8.081772)
		(mid 59.631608 -8.088713)
		(end 59.704986 -8.024876)
		(width 0.127)
		(layer "F.Cu")
		(net "P3E_CPU0_PE1_PCH_CON_TXN<12>")
	)
	(arc
		(start 59.225434 -7.419594)
		(mid 59.288188 -7.756734)
		(end 59.468004 -8.048752)
		(width 0.127)
		(layer "F.Cu")
		(net "P3E_CPU0_PE1_PCH_CON_TXN<12>")
	)
	(arc
		(start 48.379888 11.090148)
		(mid 48.347677 10.92821)
		(end 48.255936 10.790936)
		(width 0.127)
		(layer "F.Cu")
		(net "P3E_CPU0_PE1_PCH_CON_TXN<12>")
	)
	(arc
		(start 48.255936 10.790936)
		(mid 48.164364 10.653889)
		(end 48.132238 10.492232)
		(width 0.127)
		(layer "F.Cu")
		(net "P3E_CPU0_PE1_PCH_CON_TXN<12>")
	)
	(segment
		(start 65.535302 -8.081772)
		(end 65.535048 -8.081772)
		(width 0.127)
		(layer "F.Cu")
		(net "P3E_CPU0_PE1_PCH_CON_TXN<11>")
	)
	(segment
		(start 65.532762 -8.080502)
		(end 65.468754 -8.048752)
		(width 0.127)
		(layer "F.Cu")
		(net "P3E_CPU0_PE1_PCH_CON_TXN<11>")
	)
	(segment
		(start 52.00523 7.731252)
		(end 51.78679 8.043418)
		(width 0.127)
		(layer "F.Cu")
		(net "P3E_CPU0_PE1_PCH_CON_TXN<11>")
	)
	(segment
		(start 51.542696 8.086344)
		(end 51.324002 8.39851)
		(width 0.127)
		(layer "F.Cu")
		(net "P3E_CPU0_PE1_PCH_CON_TXN<11>")
	)
	(segment
		(start 51.324002 8.39851)
		(end 51.367182 8.642604)
		(width 0.127)
		(layer "F.Cu")
		(net "P3E_CPU0_PE1_PCH_CON_TXN<11>")
	)
	(segment
		(start 51.962304 7.487158)
		(end 52.00523 7.731252)
		(width 0.127)
		(layer "F.Cu")
		(net "P3E_CPU0_PE1_PCH_CON_TXN<11>")
	)
	(segment
		(start 64.023748 -3.291078)
		(end 55.167276 2.910078)
		(width 0.127)
		(layer "F.Cu")
		(net "P3E_CPU0_PE1_PCH_CON_TXN<11>")
	)
	(segment
		(start 65.535048 -8.081772)
		(end 65.532762 -8.080502)
		(width 0.127)
		(layer "F.Cu")
		(net "P3E_CPU0_PE1_PCH_CON_TXN<11>")
	)
	(segment
		(start 50.656236 10.747248)
		(end 50.65649 10.747502)
		(width 0.127)
		(layer "F.Cu")
		(net "P3E_CPU0_PE1_PCH_CON_TXN<11>")
	)
	(segment
		(start 65.226184 -5.924042)
		(end 65.010284 -4.700016)
		(width 0.127)
		(layer "F.Cu")
		(net "P3E_CPU0_PE1_PCH_CON_TXN<11>")
	)
	(segment
		(start 55.167276 2.910078)
		(end 51.962304 7.487158)
		(width 0.127)
		(layer "F.Cu")
		(net "P3E_CPU0_PE1_PCH_CON_TXN<11>")
	)
	(segment
		(start 65.010284 -4.700016)
		(end 64.023748 -3.291078)
		(width 0.127)
		(layer "F.Cu")
		(net "P3E_CPU0_PE1_PCH_CON_TXN<11>")
	)
	(segment
		(start 51.148488 8.95477)
		(end 50.904394 8.997696)
		(width 0.127)
		(layer "F.Cu")
		(net "P3E_CPU0_PE1_PCH_CON_TXN<11>")
	)
	(segment
		(start 65.991232 -7.453122)
		(end 65.705736 -8.024876)
		(width 0.127)
		(layer "F.Cu")
		(net "P3E_CPU0_PE1_PCH_CON_TXN<11>")
	)
	(segment
		(start 51.367182 8.642604)
		(end 51.148488 8.95477)
		(width 0.127)
		(layer "F.Cu")
		(net "P3E_CPU0_PE1_PCH_CON_TXN<11>")
	)
	(segment
		(start 50.532284 10.182606)
		(end 50.532284 10.448544)
		(width 0.127)
		(layer "F.Cu")
		(net "P3E_CPU0_PE1_PCH_CON_TXN<11>")
	)
	(segment
		(start 50.904394 8.997696)
		(end 50.685954 9.309862)
		(width 0.127)
		(layer "F.Cu")
		(net "P3E_CPU0_PE1_PCH_CON_TXN<11>")
	)
	(segment
		(start 65.226184 -7.419594)
		(end 65.226184 -5.924042)
		(width 0.127)
		(layer "F.Cu")
		(net "P3E_CPU0_PE1_PCH_CON_TXN<11>")
	)
	(segment
		(start 51.78679 8.043418)
		(end 51.542696 8.086344)
		(width 0.127)
		(layer "F.Cu")
		(net "P3E_CPU0_PE1_PCH_CON_TXN<11>")
	)
	(segment
		(start 50.685954 9.309862)
		(end 50.532284 10.182606)
		(width 0.127)
		(layer "F.Cu")
		(net "P3E_CPU0_PE1_PCH_CON_TXN<11>")
	)
	(segment
		(start 50.779934 11.045952)
		(end 50.779934 12.133072)
		(width 0.127)
		(layer "F.Cu")
		(net "P3E_CPU0_PE1_PCH_CON_TXN<11>")
	)
	(segment
		(start 66.080132 -7.250176)
		(end 65.991232 -7.453122)
		(width 0.127)
		(layer "F.Cu")
		(net "P3E_CPU0_PE1_PCH_CON_TXN<11>")
	)
	(arc
		(start 50.65649 10.747502)
		(mid 50.747876 10.88446)
		(end 50.779934 11.045952)
		(width 0.127)
		(layer "F.Cu")
		(net "P3E_CPU0_PE1_PCH_CON_TXN<11>")
	)
	(arc
		(start 50.532284 10.448544)
		(mid 50.56454 10.610234)
		(end 50.656236 10.747248)
		(width 0.127)
		(layer "F.Cu")
		(net "P3E_CPU0_PE1_PCH_CON_TXN<11>")
	)
	(arc
		(start 65.468754 -8.048752)
		(mid 65.288888 -7.756754)
		(end 65.226184 -7.419594)
		(width 0.127)
		(layer "F.Cu")
		(net "P3E_CPU0_PE1_PCH_CON_TXN<11>")
	)
	(arc
		(start 65.705736 -8.024876)
		(mid 65.632322 -8.088605)
		(end 65.535302 -8.081772)
		(width 0.127)
		(layer "F.Cu")
		(net "P3E_CPU0_PE1_PCH_CON_TXN<11>")
	)
	(segment
		(start 54.42077 7.64413)
		(end 54.20233 7.956296)
		(width 0.127)
		(layer "F.Cu")
		(net "P3E_CPU0_PE1_PCH_CON_TXN<10>")
	)
	(segment
		(start 53.564028 8.867648)
		(end 53.319934 8.910574)
		(width 0.127)
		(layer "F.Cu")
		(net "P3E_CPU0_PE1_PCH_CON_TXN<10>")
	)
	(segment
		(start 53.319934 8.910574)
		(end 53.101494 9.22274)
		(width 0.127)
		(layer "F.Cu")
		(net "P3E_CPU0_PE1_PCH_CON_TXN<10>")
	)
	(segment
		(start 69.747892 -7.939024)
		(end 69.70776 -7.979156)
		(width 0.127)
		(layer "F.Cu")
		(net "P3E_CPU0_PE1_PCH_CON_TXN<10>")
	)
	(segment
		(start 53.782722 8.555482)
		(end 53.564028 8.867648)
		(width 0.127)
		(layer "F.Cu")
		(net "P3E_CPU0_PE1_PCH_CON_TXN<10>")
	)
	(segment
		(start 68.345812 -4.90347)
		(end 68.345304 -4.902962)
		(width 0.127)
		(layer "F.Cu")
		(net "P3E_CPU0_PE1_PCH_CON_TXN<10>")
	)
	(segment
		(start 53.958236 7.999222)
		(end 53.739542 8.311388)
		(width 0.127)
		(layer "F.Cu")
		(net "P3E_CPU0_PE1_PCH_CON_TXN<10>")
	)
	(segment
		(start 70.079362 -7.250176)
		(end 69.747892 -7.939024)
		(width 0.127)
		(layer "F.Cu")
		(net "P3E_CPU0_PE1_PCH_CON_TXN<10>")
	)
	(segment
		(start 53.056028 10.765282)
		(end 53.093112 10.802366)
		(width 0.127)
		(layer "F.Cu")
		(net "P3E_CPU0_PE1_PCH_CON_TXN<10>")
	)
	(segment
		(start 53.101494 9.22274)
		(end 52.93233 10.182606)
		(width 0.127)
		(layer "F.Cu")
		(net "P3E_CPU0_PE1_PCH_CON_TXN<10>")
	)
	(segment
		(start 68.036694 -4.5974)
		(end 57.720738 2.625852)
		(width 0.127)
		(layer "F.Cu")
		(net "P3E_CPU0_PE1_PCH_CON_TXN<10>")
	)
	(segment
		(start 68.342256 -4.902962)
		(end 68.036694 -4.5974)
		(width 0.127)
		(layer "F.Cu")
		(net "P3E_CPU0_PE1_PCH_CON_TXN<10>")
	)
	(segment
		(start 69.225414 -6.945376)
		(end 69.040248 -5.89534)
		(width 0.127)
		(layer "F.Cu")
		(net "P3E_CPU0_PE1_PCH_CON_TXN<10>")
	)
	(segment
		(start 53.17998 11.011662)
		(end 53.17998 12.133072)
		(width 0.127)
		(layer "F.Cu")
		(net "P3E_CPU0_PE1_PCH_CON_TXN<10>")
	)
	(segment
		(start 68.345304 -4.902962)
		(end 68.342256 -4.902962)
		(width 0.127)
		(layer "F.Cu")
		(net "P3E_CPU0_PE1_PCH_CON_TXN<10>")
	)
	(segment
		(start 54.377844 7.400036)
		(end 54.42077 7.64413)
		(width 0.127)
		(layer "F.Cu")
		(net "P3E_CPU0_PE1_PCH_CON_TXN<10>")
	)
	(segment
		(start 69.040248 -5.89534)
		(end 68.345812 -4.90347)
		(width 0.127)
		(layer "F.Cu")
		(net "P3E_CPU0_PE1_PCH_CON_TXN<10>")
	)
	(segment
		(start 53.739542 8.311388)
		(end 53.782722 8.555482)
		(width 0.127)
		(layer "F.Cu")
		(net "P3E_CPU0_PE1_PCH_CON_TXN<10>")
	)
	(segment
		(start 57.720738 2.625852)
		(end 54.377844 7.400036)
		(width 0.127)
		(layer "F.Cu")
		(net "P3E_CPU0_PE1_PCH_CON_TXN<10>")
	)
	(segment
		(start 69.225414 -7.419594)
		(end 69.225414 -6.945376)
		(width 0.127)
		(layer "F.Cu")
		(net "P3E_CPU0_PE1_PCH_CON_TXN<10>")
	)
	(segment
		(start 54.20233 7.956296)
		(end 53.958236 7.999222)
		(width 0.127)
		(layer "F.Cu")
		(net "P3E_CPU0_PE1_PCH_CON_TXN<10>")
	)
	(segment
		(start 52.93233 10.182606)
		(end 52.93233 10.466324)
		(width 0.127)
		(layer "F.Cu")
		(net "P3E_CPU0_PE1_PCH_CON_TXN<10>")
	)
	(arc
		(start 53.093112 10.802366)
		(mid 53.157382 10.898363)
		(end 53.17998 11.011662)
		(width 0.127)
		(layer "F.Cu")
		(net "P3E_CPU0_PE1_PCH_CON_TXN<10>")
	)
	(arc
		(start 69.390006 -7.949946)
		(mid 69.26754 -7.69724)
		(end 69.225414 -7.419594)
		(width 0.127)
		(layer "F.Cu")
		(net "P3E_CPU0_PE1_PCH_CON_TXN<10>")
	)
	(arc
		(start 69.70776 -7.979156)
		(mid 69.541998 -8.039101)
		(end 69.390006 -7.949946)
		(width 0.127)
		(layer "F.Cu")
		(net "P3E_CPU0_PE1_PCH_CON_TXN<10>")
	)
	(arc
		(start 52.93233 10.466324)
		(mid 52.964473 10.628096)
		(end 53.056028 10.765282)
		(width 0.127)
		(layer "F.Cu")
		(net "P3E_CPU0_PE1_PCH_CON_TXN<10>")
	)
	(segment
		(start 74.95413 -6.791198)
		(end 74.95413 -7.453122)
		(width 0.127)
		(layer "B.Cu")
		(net "P3E_CPU0_PE1_PCH_CON_RXP<9>")
	)
	(segment
		(start 55.827676 10.418064)
		(end 55.827676 9.191752)
		(width 0.127)
		(layer "B.Cu")
		(net "P3E_CPU0_PE1_PCH_CON_RXP<9>")
	)
	(segment
		(start 56.172862 8.09625)
		(end 56.391302 7.784338)
		(width 0.127)
		(layer "B.Cu")
		(net "P3E_CPU0_PE1_PCH_CON_RXP<9>")
	)
	(segment
		(start 75.32243 -8.343646)
		(end 75.756008 -8.777224)
		(width 0.127)
		(layer "B.Cu")
		(net "P3E_CPU0_PE1_PCH_CON_RXP<9>")
	)
	(segment
		(start 57.02935 6.872986)
		(end 57.273444 6.829806)
		(width 0.127)
		(layer "B.Cu")
		(net "P3E_CPU0_PE1_PCH_CON_RXP<9>")
	)
	(segment
		(start 56.81091 7.184898)
		(end 57.02935 6.872986)
		(width 0.127)
		(layer "B.Cu")
		(net "P3E_CPU0_PE1_PCH_CON_RXP<9>")
	)
	(segment
		(start 74.056494 -6.2738)
		(end 74.273156 -6.2738)
		(width 0.127)
		(layer "B.Cu")
		(net "P3E_CPU0_PE1_PCH_CON_RXP<9>")
	)
	(segment
		(start 75.137772 -11.89228)
		(end 75.079352 -11.749786)
		(width 0.127)
		(layer "B.Cu")
		(net "P3E_CPU0_PE1_PCH_CON_RXP<9>")
	)
	(segment
		(start 74.701908 -6.4516)
		(end 74.892154 -6.641846)
		(width 0.127)
		(layer "B.Cu")
		(net "P3E_CPU0_PE1_PCH_CON_RXP<9>")
	)
	(segment
		(start 56.215788 8.340344)
		(end 56.172862 8.09625)
		(width 0.127)
		(layer "B.Cu")
		(net "P3E_CPU0_PE1_PCH_CON_RXP<9>")
	)
	(segment
		(start 55.580026 12.514072)
		(end 55.580026 11.01598)
		(width 0.127)
		(layer "B.Cu")
		(net "P3E_CPU0_PE1_PCH_CON_RXP<9>")
	)
	(segment
		(start 56.85409 7.428992)
		(end 56.81091 7.184898)
		(width 0.127)
		(layer "B.Cu")
		(net "P3E_CPU0_PE1_PCH_CON_RXP<9>")
	)
	(segment
		(start 75.452478 -12.524486)
		(end 75.137772 -11.89228)
		(width 0.127)
		(layer "B.Cu")
		(net "P3E_CPU0_PE1_PCH_CON_RXP<9>")
	)
	(segment
		(start 57.273444 6.829806)
		(end 59.16803 4.124198)
		(width 0.127)
		(layer "B.Cu")
		(net "P3E_CPU0_PE1_PCH_CON_RXP<9>")
	)
	(segment
		(start 55.997348 8.65251)
		(end 56.215788 8.340344)
		(width 0.127)
		(layer "B.Cu")
		(net "P3E_CPU0_PE1_PCH_CON_RXP<9>")
	)
	(segment
		(start 75.736958 -12.52474)
		(end 75.623166 -12.581382)
		(width 0.127)
		(layer "B.Cu")
		(net "P3E_CPU0_PE1_PCH_CON_RXP<9>")
	)
	(segment
		(start 56.635396 7.741158)
		(end 56.85409 7.428992)
		(width 0.127)
		(layer "B.Cu")
		(net "P3E_CPU0_PE1_PCH_CON_RXP<9>")
	)
	(segment
		(start 56.391302 7.784338)
		(end 56.635396 7.741158)
		(width 0.127)
		(layer "B.Cu")
		(net "P3E_CPU0_PE1_PCH_CON_RXP<9>")
	)
	(segment
		(start 59.398916 3.893312)
		(end 73.80859 -6.196076)
		(width 0.127)
		(layer "B.Cu")
		(net "P3E_CPU0_PE1_PCH_CON_RXP<9>")
	)
	(segment
		(start 75.623166 -12.581382)
		(end 75.622912 -12.581382)
		(width 0.127)
		(layer "B.Cu")
		(net "P3E_CPU0_PE1_PCH_CON_RXP<9>")
	)
	(arc
		(start 55.580026 11.01598)
		(mid 55.612179 10.854334)
		(end 55.703724 10.717276)
		(width 0.127)
		(layer "B.Cu")
		(net "P3E_CPU0_PE1_PCH_CON_RXP<9>")
	)
	(arc
		(start 75.981306 -11.10234)
		(mid 75.97653 -11.550474)
		(end 76.015596 -11.996928)
		(width 0.127)
		(layer "B.Cu")
		(net "P3E_CPU0_PE1_PCH_CON_RXP<9>")
	)
	(arc
		(start 75.756008 -8.777224)
		(mid 75.850694 -8.918932)
		(end 75.884024 -9.086088)
		(width 0.127)
		(layer "B.Cu")
		(net "P3E_CPU0_PE1_PCH_CON_RXP<9>")
	)
	(arc
		(start 74.95413 -7.453122)
		(mid 75.049688 -7.935028)
		(end 75.32243 -8.343646)
		(width 0.127)
		(layer "B.Cu")
		(net "P3E_CPU0_PE1_PCH_CON_RXP<9>")
	)
	(arc
		(start 73.80859 -6.196076)
		(mid 73.926558 -6.254023)
		(end 74.056494 -6.2738)
		(width 0.127)
		(layer "B.Cu")
		(net "P3E_CPU0_PE1_PCH_CON_RXP<9>")
	)
	(arc
		(start 76.015596 -11.996928)
		(mid 75.960925 -12.305511)
		(end 75.736958 -12.52474)
		(width 0.127)
		(layer "B.Cu")
		(net "P3E_CPU0_PE1_PCH_CON_RXP<9>")
	)
	(arc
		(start 55.703724 10.717276)
		(mid 55.795451 10.579996)
		(end 55.827676 10.418064)
		(width 0.127)
		(layer "B.Cu")
		(net "P3E_CPU0_PE1_PCH_CON_RXP<9>")
	)
	(arc
		(start 75.884024 -9.086088)
		(mid 75.883894 -9.096505)
		(end 75.883516 -9.106916)
		(width 0.127)
		(layer "B.Cu")
		(net "P3E_CPU0_PE1_PCH_CON_RXP<9>")
	)
	(arc
		(start 74.892154 -6.641846)
		(mid 74.937994 -6.710355)
		(end 74.95413 -6.791198)
		(width 0.127)
		(layer "B.Cu")
		(net "P3E_CPU0_PE1_PCH_CON_RXP<9>")
	)
	(arc
		(start 59.16803 4.124198)
		(mid 59.273373 3.998655)
		(end 59.398916 3.893312)
		(width 0.127)
		(layer "B.Cu")
		(net "P3E_CPU0_PE1_PCH_CON_RXP<9>")
	)
	(arc
		(start 75.883516 -9.106916)
		(mid 75.986353 -10.101984)
		(end 75.981306 -11.10234)
		(width 0.127)
		(layer "B.Cu")
		(net "P3E_CPU0_PE1_PCH_CON_RXP<9>")
	)
	(arc
		(start 55.827676 9.191752)
		(mid 55.871023 8.909077)
		(end 55.997348 8.65251)
		(width 0.127)
		(layer "B.Cu")
		(net "P3E_CPU0_PE1_PCH_CON_RXP<9>")
	)
	(arc
		(start 74.273156 -6.2738)
		(mid 74.505205 -6.320069)
		(end 74.701908 -6.4516)
		(width 0.127)
		(layer "B.Cu")
		(net "P3E_CPU0_PE1_PCH_CON_RXP<9>")
	)
	(arc
		(start 75.622912 -12.581382)
		(mid 75.525856 -12.588323)
		(end 75.452478 -12.524486)
		(width 0.127)
		(layer "B.Cu")
		(net "P3E_CPU0_PE1_PCH_CON_RXP<9>")
	)
	(segment
		(start 66.617088 0.32385)
		(end 69.820028 -1.879346)
		(width 0.127)
		(layer "B.Cu")
		(net "P3E_CPU0_PE1_PCH_CON_RXP<8>")
	)
	(segment
		(start 59.251342 7.215886)
		(end 59.495182 7.17169)
		(width 0.127)
		(layer "B.Cu")
		(net "P3E_CPU0_PE1_PCH_CON_RXP<8>")
	)
	(segment
		(start 59.495182 7.17169)
		(end 60.231782 6.109208)
		(width 0.127)
		(layer "B.Cu")
		(net "P3E_CPU0_PE1_PCH_CON_RXP<8>")
	)
	(segment
		(start 78.95463 -7.1374)
		(end 78.95463 -7.453122)
		(width 0.127)
		(layer "B.Cu")
		(net "P3E_CPU0_PE1_PCH_CON_RXP<8>")
	)
	(segment
		(start 58.103516 10.75563)
		(end 58.1406 10.718546)
		(width 0.127)
		(layer "B.Cu")
		(net "P3E_CPU0_PE1_PCH_CON_RXP<8>")
	)
	(segment
		(start 58.617358 8.130032)
		(end 58.861452 8.085836)
		(width 0.127)
		(layer "B.Cu")
		(net "P3E_CPU0_PE1_PCH_CON_RXP<8>")
	)
	(segment
		(start 58.444638 8.687054)
		(end 58.400442 8.443214)
		(width 0.127)
		(layer "B.Cu")
		(net "P3E_CPU0_PE1_PCH_CON_RXP<8>")
	)
	(segment
		(start 58.400442 8.443214)
		(end 58.617358 8.130032)
		(width 0.127)
		(layer "B.Cu")
		(net "P3E_CPU0_PE1_PCH_CON_RXP<8>")
	)
	(segment
		(start 77.714856 -5.62737)
		(end 78.244446 -5.911342)
		(width 0.127)
		(layer "B.Cu")
		(net "P3E_CPU0_PE1_PCH_CON_RXP<8>")
	)
	(segment
		(start 62.063884 3.492246)
		(end 63.614046 2.406904)
		(width 0.127)
		(layer "B.Cu")
		(net "P3E_CPU0_PE1_PCH_CON_RXP<8>")
	)
	(segment
		(start 58.227468 9.000236)
		(end 58.444638 8.687054)
		(width 0.127)
		(layer "B.Cu")
		(net "P3E_CPU0_PE1_PCH_CON_RXP<8>")
	)
	(segment
		(start 58.861452 8.085836)
		(end 59.078368 7.772908)
		(width 0.127)
		(layer "B.Cu")
		(net "P3E_CPU0_PE1_PCH_CON_RXP<8>")
	)
	(segment
		(start 79.623666 -12.581382)
		(end 79.623412 -12.581382)
		(width 0.127)
		(layer "B.Cu")
		(net "P3E_CPU0_PE1_PCH_CON_RXP<8>")
	)
	(segment
		(start 60.231782 6.109208)
		(end 62.063884 3.492246)
		(width 0.127)
		(layer "B.Cu")
		(net "P3E_CPU0_PE1_PCH_CON_RXP<8>")
	)
	(segment
		(start 59.078368 7.772908)
		(end 59.034172 7.529068)
		(width 0.127)
		(layer "B.Cu")
		(net "P3E_CPU0_PE1_PCH_CON_RXP<8>")
	)
	(segment
		(start 79.32293 -8.343646)
		(end 79.756508 -8.777224)
		(width 0.127)
		(layer "B.Cu")
		(net "P3E_CPU0_PE1_PCH_CON_RXP<8>")
	)
	(segment
		(start 59.034172 7.529068)
		(end 59.251342 7.215886)
		(width 0.127)
		(layer "B.Cu")
		(net "P3E_CPU0_PE1_PCH_CON_RXP<8>")
	)
	(segment
		(start 74.402696 -5.043678)
		(end 77.714856 -5.62737)
		(width 0.127)
		(layer "B.Cu")
		(net "P3E_CPU0_PE1_PCH_CON_RXP<8>")
	)
	(segment
		(start 79.737458 -12.52474)
		(end 79.623666 -12.581382)
		(width 0.127)
		(layer "B.Cu")
		(net "P3E_CPU0_PE1_PCH_CON_RXP<8>")
	)
	(segment
		(start 79.452978 -12.524486)
		(end 79.138272 -11.89228)
		(width 0.127)
		(layer "B.Cu")
		(net "P3E_CPU0_PE1_PCH_CON_RXP<8>")
	)
	(segment
		(start 69.820028 -1.879346)
		(end 74.402696 -5.043678)
		(width 0.127)
		(layer "B.Cu")
		(net "P3E_CPU0_PE1_PCH_CON_RXP<8>")
	)
	(segment
		(start 58.227468 10.50925)
		(end 58.227468 9.000236)
		(width 0.127)
		(layer "B.Cu")
		(net "P3E_CPU0_PE1_PCH_CON_RXP<8>")
	)
	(segment
		(start 79.138272 -11.89228)
		(end 79.079852 -11.749786)
		(width 0.127)
		(layer "B.Cu")
		(net "P3E_CPU0_PE1_PCH_CON_RXP<8>")
	)
	(segment
		(start 63.614046 2.406904)
		(end 66.617088 0.32385)
		(width 0.127)
		(layer "B.Cu")
		(net "P3E_CPU0_PE1_PCH_CON_RXP<8>")
	)
	(segment
		(start 57.979818 12.514072)
		(end 57.979818 11.054588)
		(width 0.127)
		(layer "B.Cu")
		(net "P3E_CPU0_PE1_PCH_CON_RXP<8>")
	)
	(arc
		(start 79.884016 -9.106916)
		(mid 79.986853 -10.101984)
		(end 79.981806 -11.10234)
		(width 0.127)
		(layer "B.Cu")
		(net "P3E_CPU0_PE1_PCH_CON_RXP<8>")
	)
	(arc
		(start 78.244446 -5.911342)
		(mid 78.764233 -6.428966)
		(end 78.95463 -7.1374)
		(width 0.127)
		(layer "B.Cu")
		(net "P3E_CPU0_PE1_PCH_CON_RXP<8>")
	)
	(arc
		(start 57.979818 11.054588)
		(mid 58.011961 10.892816)
		(end 58.103516 10.75563)
		(width 0.127)
		(layer "B.Cu")
		(net "P3E_CPU0_PE1_PCH_CON_RXP<8>")
	)
	(arc
		(start 79.756508 -8.777224)
		(mid 79.851194 -8.918932)
		(end 79.884524 -9.086088)
		(width 0.127)
		(layer "B.Cu")
		(net "P3E_CPU0_PE1_PCH_CON_RXP<8>")
	)
	(arc
		(start 79.981806 -11.10234)
		(mid 79.97703 -11.550474)
		(end 80.016096 -11.996928)
		(width 0.127)
		(layer "B.Cu")
		(net "P3E_CPU0_PE1_PCH_CON_RXP<8>")
	)
	(arc
		(start 58.1406 10.718546)
		(mid 58.20487 10.622549)
		(end 58.227468 10.50925)
		(width 0.127)
		(layer "B.Cu")
		(net "P3E_CPU0_PE1_PCH_CON_RXP<8>")
	)
	(arc
		(start 79.884524 -9.086088)
		(mid 79.884394 -9.096505)
		(end 79.884016 -9.106916)
		(width 0.127)
		(layer "B.Cu")
		(net "P3E_CPU0_PE1_PCH_CON_RXP<8>")
	)
	(arc
		(start 79.623412 -12.581382)
		(mid 79.526356 -12.588323)
		(end 79.452978 -12.524486)
		(width 0.127)
		(layer "B.Cu")
		(net "P3E_CPU0_PE1_PCH_CON_RXP<8>")
	)
	(arc
		(start 78.95463 -7.453122)
		(mid 79.050188 -7.935028)
		(end 79.32293 -8.343646)
		(width 0.127)
		(layer "B.Cu")
		(net "P3E_CPU0_PE1_PCH_CON_RXP<8>")
	)
	(arc
		(start 80.016096 -11.996928)
		(mid 79.961425 -12.305511)
		(end 79.737458 -12.52474)
		(width 0.127)
		(layer "B.Cu")
		(net "P3E_CPU0_PE1_PCH_CON_RXP<8>")
	)
	(segment
		(start 39.561008 6.765798)
		(end 41.618154 5.625846)
		(width 0.127)
		(layer "B.Cu")
		(net "P3E_CPU0_PE1_PCH_CON_RXP<15>")
	)
	(segment
		(start 36.379912 12.514072)
		(end 36.379912 11.013694)
		(width 0.127)
		(layer "B.Cu")
		(net "P3E_CPU0_PE1_PCH_CON_RXP<15>")
	)
	(segment
		(start 36.771326 9.06145)
		(end 37.11575 8.560308)
		(width 0.127)
		(layer "B.Cu")
		(net "P3E_CPU0_PE1_PCH_CON_RXP<15>")
	)
	(segment
		(start 37.11575 8.560308)
		(end 39.561008 6.765798)
		(width 0.127)
		(layer "B.Cu")
		(net "P3E_CPU0_PE1_PCH_CON_RXP<15>")
	)
	(segment
		(start 48.455072 -13.024866)
		(end 48.209454 -13.516356)
		(width 0.127)
		(layer "B.Cu")
		(net "P3E_CPU0_PE1_PCH_CON_RXP<15>")
	)
	(segment
		(start 49.616868 -2.745486)
		(end 48.945546 -7.277862)
		(width 0.127)
		(layer "B.Cu")
		(net "P3E_CPU0_PE1_PCH_CON_RXP<15>")
	)
	(segment
		(start 48.945546 -7.277862)
		(end 48.9458 -7.300722)
		(width 0.127)
		(layer "B.Cu")
		(net "P3E_CPU0_PE1_PCH_CON_RXP<15>")
	)
	(segment
		(start 44.031154 5.232146)
		(end 44.0309 5.232146)
		(width 0.127)
		(layer "B.Cu")
		(net "P3E_CPU0_PE1_PCH_CON_RXP<15>")
	)
	(segment
		(start 48.209454 -13.516356)
		(end 48.080422 -13.750036)
		(width 0.127)
		(layer "B.Cu")
		(net "P3E_CPU0_PE1_PCH_CON_RXP<15>")
	)
	(segment
		(start 36.627562 9.800336)
		(end 36.771326 9.06145)
		(width 0.127)
		(layer "B.Cu")
		(net "P3E_CPU0_PE1_PCH_CON_RXP<15>")
	)
	(segment
		(start 41.618154 5.625846)
		(end 44.031154 5.232146)
		(width 0.127)
		(layer "B.Cu")
		(net "P3E_CPU0_PE1_PCH_CON_RXP<15>")
	)
	(segment
		(start 49.125378 -0.40513)
		(end 49.546002 -1.858518)
		(width 0.127)
		(layer "B.Cu")
		(net "P3E_CPU0_PE1_PCH_CON_RXP<15>")
	)
	(segment
		(start 44.0309 5.232146)
		(end 45.017436 4.684522)
		(width 0.127)
		(layer "B.Cu")
		(net "P3E_CPU0_PE1_PCH_CON_RXP<15>")
	)
	(segment
		(start 36.627562 10.416032)
		(end 36.627562 9.800336)
		(width 0.127)
		(layer "B.Cu")
		(net "P3E_CPU0_PE1_PCH_CON_RXP<15>")
	)
	(segment
		(start 46.00448 4.136898)
		(end 49.125378 -0.40513)
		(width 0.127)
		(layer "B.Cu")
		(net "P3E_CPU0_PE1_PCH_CON_RXP<15>")
	)
	(segment
		(start 49.581308 -2.301748)
		(end 49.616868 -2.745486)
		(width 0.127)
		(layer "B.Cu")
		(net "P3E_CPU0_PE1_PCH_CON_RXP<15>")
	)
	(segment
		(start 48.397922 -12.854432)
		(end 48.398176 -12.854432)
		(width 0.127)
		(layer "B.Cu")
		(net "P3E_CPU0_PE1_PCH_CON_RXP<15>")
	)
	(segment
		(start 48.284384 -12.79779)
		(end 48.397922 -12.854432)
		(width 0.127)
		(layer "B.Cu")
		(net "P3E_CPU0_PE1_PCH_CON_RXP<15>")
	)
	(segment
		(start 49.546002 -1.858518)
		(end 49.581308 -2.301748)
		(width 0.127)
		(layer "B.Cu")
		(net "P3E_CPU0_PE1_PCH_CON_RXP<15>")
	)
	(segment
		(start 45.017436 4.684522)
		(end 46.00448 4.136898)
		(width 0.127)
		(layer "B.Cu")
		(net "P3E_CPU0_PE1_PCH_CON_RXP<15>")
	)
	(arc
		(start 47.999904 -10.474706)
		(mid 48.029977 -10.949114)
		(end 47.938182 -11.415522)
		(width 0.127)
		(layer "B.Cu")
		(net "P3E_CPU0_PE1_PCH_CON_RXP<15>")
	)
	(arc
		(start 47.920148 -12.36218)
		(mid 48.056904 -12.617912)
		(end 48.284384 -12.79779)
		(width 0.127)
		(layer "B.Cu")
		(net "P3E_CPU0_PE1_PCH_CON_RXP<15>")
	)
	(arc
		(start 48.9458 -7.300722)
		(mid 48.895724 -7.553234)
		(end 48.75276 -7.76732)
		(width 0.127)
		(layer "B.Cu")
		(net "P3E_CPU0_PE1_PCH_CON_RXP<15>")
	)
	(arc
		(start 48.277018 -8.280146)
		(mid 48.045258 -8.835857)
		(end 47.93742 -9.428226)
		(width 0.127)
		(layer "B.Cu")
		(net "P3E_CPU0_PE1_PCH_CON_RXP<15>")
	)
	(arc
		(start 47.938182 -11.415522)
		(mid 47.856549 -11.887473)
		(end 47.920148 -12.36218)
		(width 0.127)
		(layer "B.Cu")
		(net "P3E_CPU0_PE1_PCH_CON_RXP<15>")
	)
	(arc
		(start 48.398176 -12.854432)
		(mid 48.461939 -12.927885)
		(end 48.455072 -13.024866)
		(width 0.127)
		(layer "B.Cu")
		(net "P3E_CPU0_PE1_PCH_CON_RXP<15>")
	)
	(arc
		(start 36.503864 10.714736)
		(mid 36.595436 10.577689)
		(end 36.627562 10.416032)
		(width 0.127)
		(layer "B.Cu")
		(net "P3E_CPU0_PE1_PCH_CON_RXP<15>")
	)
	(arc
		(start 48.75276 -7.76732)
		(mid 48.483241 -7.994376)
		(end 48.277018 -8.280146)
		(width 0.127)
		(layer "B.Cu")
		(net "P3E_CPU0_PE1_PCH_CON_RXP<15>")
	)
	(arc
		(start 47.93742 -9.428226)
		(mid 47.933987 -9.953536)
		(end 47.999904 -10.474706)
		(width 0.127)
		(layer "B.Cu")
		(net "P3E_CPU0_PE1_PCH_CON_RXP<15>")
	)
	(arc
		(start 36.379912 11.013694)
		(mid 36.412134 10.851882)
		(end 36.503864 10.714736)
		(width 0.127)
		(layer "B.Cu")
		(net "P3E_CPU0_PE1_PCH_CON_RXP<15>")
	)
	(segment
		(start 52.9717 -6.706616)
		(end 52.9717 -7.40918)
		(width 0.127)
		(layer "B.Cu")
		(net "P3E_CPU0_PE1_PCH_CON_RXP<14>")
	)
	(segment
		(start 38.779958 12.514072)
		(end 38.779958 10.874248)
		(width 0.127)
		(layer "B.Cu")
		(net "P3E_CPU0_PE1_PCH_CON_RXP<14>")
	)
	(segment
		(start 39.630604 8.236458)
		(end 39.63416 8.236458)
		(width 0.127)
		(layer "B.Cu")
		(net "P3E_CPU0_PE1_PCH_CON_RXP<14>")
	)
	(segment
		(start 52.860448 -6.293358)
		(end 52.969668 -6.698996)
		(width 0.127)
		(layer "B.Cu")
		(net "P3E_CPU0_PE1_PCH_CON_RXP<14>")
	)
	(segment
		(start 52.969668 -6.698996)
		(end 52.9717 -6.706616)
		(width 0.127)
		(layer "B.Cu")
		(net "P3E_CPU0_PE1_PCH_CON_RXP<14>")
	)
	(segment
		(start 52.571142 -5.219192)
		(end 52.670202 -5.586984)
		(width 0.127)
		(layer "B.Cu")
		(net "P3E_CPU0_PE1_PCH_CON_RXP<14>")
	)
	(segment
		(start 53.738018 -12.52474)
		(end 53.624226 -12.581382)
		(width 0.127)
		(layer "B.Cu")
		(net "P3E_CPU0_PE1_PCH_CON_RXP<14>")
	)
	(segment
		(start 46.98746 5.036566)
		(end 51.652932 -1.810004)
		(width 0.127)
		(layer "B.Cu")
		(net "P3E_CPU0_PE1_PCH_CON_RXP<14>")
	)
	(segment
		(start 52.546504 -5.801868)
		(end 52.645564 -6.16966)
		(width 0.127)
		(layer "B.Cu")
		(net "P3E_CPU0_PE1_PCH_CON_RXP<14>")
	)
	(segment
		(start 39.63416 8.236458)
		(end 39.752524 8.11784)
		(width 0.127)
		(layer "B.Cu")
		(net "P3E_CPU0_PE1_PCH_CON_RXP<14>")
	)
	(segment
		(start 52.380896 -4.512818)
		(end 52.257198 -4.727702)
		(width 0.127)
		(layer "B.Cu")
		(net "P3E_CPU0_PE1_PCH_CON_RXP<14>")
	)
	(segment
		(start 52.645564 -6.16966)
		(end 52.860448 -6.293358)
		(width 0.127)
		(layer "B.Cu")
		(net "P3E_CPU0_PE1_PCH_CON_RXP<14>")
	)
	(segment
		(start 38.984174 9.658858)
		(end 39.101776 8.9916)
		(width 0.127)
		(layer "B.Cu")
		(net "P3E_CPU0_PE1_PCH_CON_RXP<14>")
	)
	(segment
		(start 52.356258 -5.095494)
		(end 52.571142 -5.219192)
		(width 0.127)
		(layer "B.Cu")
		(net "P3E_CPU0_PE1_PCH_CON_RXP<14>")
	)
	(segment
		(start 38.903656 10.57529)
		(end 38.94074 10.538206)
		(width 0.127)
		(layer "B.Cu")
		(net "P3E_CPU0_PE1_PCH_CON_RXP<14>")
	)
	(segment
		(start 39.752524 8.11784)
		(end 41.835324 6.880352)
		(width 0.127)
		(layer "B.Cu")
		(net "P3E_CPU0_PE1_PCH_CON_RXP<14>")
	)
	(segment
		(start 39.101776 8.9916)
		(end 39.63035 8.236712)
		(width 0.127)
		(layer "B.Cu")
		(net "P3E_CPU0_PE1_PCH_CON_RXP<14>")
	)
	(segment
		(start 53.453538 -12.524486)
		(end 53.239162 -12.093702)
		(width 0.127)
		(layer "B.Cu")
		(net "P3E_CPU0_PE1_PCH_CON_RXP<14>")
	)
	(segment
		(start 52.670202 -5.586984)
		(end 52.546504 -5.801868)
		(width 0.127)
		(layer "B.Cu")
		(net "P3E_CPU0_PE1_PCH_CON_RXP<14>")
	)
	(segment
		(start 51.652932 -1.810004)
		(end 52.380896 -4.512818)
		(width 0.127)
		(layer "B.Cu")
		(net "P3E_CPU0_PE1_PCH_CON_RXP<14>")
	)
	(segment
		(start 39.63035 8.236712)
		(end 39.630604 8.236458)
		(width 0.127)
		(layer "B.Cu")
		(net "P3E_CPU0_PE1_PCH_CON_RXP<14>")
	)
	(segment
		(start 52.257198 -4.727702)
		(end 52.356258 -5.095494)
		(width 0.127)
		(layer "B.Cu")
		(net "P3E_CPU0_PE1_PCH_CON_RXP<14>")
	)
	(segment
		(start 39.027608 10.32891)
		(end 39.027608 9.930892)
		(width 0.127)
		(layer "B.Cu")
		(net "P3E_CPU0_PE1_PCH_CON_RXP<14>")
	)
	(segment
		(start 53.624226 -12.581382)
		(end 53.623972 -12.581382)
		(width 0.127)
		(layer "B.Cu")
		(net "P3E_CPU0_PE1_PCH_CON_RXP<14>")
	)
	(segment
		(start 39.023036 9.878568)
		(end 38.984174 9.658858)
		(width 0.127)
		(layer "B.Cu")
		(net "P3E_CPU0_PE1_PCH_CON_RXP<14>")
	)
	(segment
		(start 41.835324 6.880352)
		(end 44.72305 6.538214)
		(width 0.127)
		(layer "B.Cu")
		(net "P3E_CPU0_PE1_PCH_CON_RXP<14>")
	)
	(segment
		(start 44.72305 6.538214)
		(end 46.98746 5.036566)
		(width 0.127)
		(layer "B.Cu")
		(net "P3E_CPU0_PE1_PCH_CON_RXP<14>")
	)
	(segment
		(start 53.239162 -12.093702)
		(end 53.080412 -11.749786)
		(width 0.127)
		(layer "B.Cu")
		(net "P3E_CPU0_PE1_PCH_CON_RXP<14>")
	)
	(arc
		(start 38.779958 10.874248)
		(mid 38.812101 10.712476)
		(end 38.903656 10.57529)
		(width 0.127)
		(layer "B.Cu")
		(net "P3E_CPU0_PE1_PCH_CON_RXP<14>")
	)
	(arc
		(start 39.027608 9.930892)
		(mid 39.02646 9.904631)
		(end 39.023036 9.878568)
		(width 0.127)
		(layer "B.Cu")
		(net "P3E_CPU0_PE1_PCH_CON_RXP<14>")
	)
	(arc
		(start 38.94074 10.538206)
		(mid 39.00501 10.442209)
		(end 39.027608 10.32891)
		(width 0.127)
		(layer "B.Cu")
		(net "P3E_CPU0_PE1_PCH_CON_RXP<14>")
	)
	(arc
		(start 54.016656 -11.996928)
		(mid 53.961985 -12.305511)
		(end 53.738018 -12.52474)
		(width 0.127)
		(layer "B.Cu")
		(net "P3E_CPU0_PE1_PCH_CON_RXP<14>")
	)
	(arc
		(start 53.888894 -9.132824)
		(mid 53.98816 -10.115088)
		(end 53.982366 -11.10234)
		(width 0.127)
		(layer "B.Cu")
		(net "P3E_CPU0_PE1_PCH_CON_RXP<14>")
	)
	(arc
		(start 53.623972 -12.581382)
		(mid 53.526916 -12.588323)
		(end 53.453538 -12.524486)
		(width 0.127)
		(layer "B.Cu")
		(net "P3E_CPU0_PE1_PCH_CON_RXP<14>")
	)
	(arc
		(start 53.982366 -11.10234)
		(mid 53.97759 -11.550474)
		(end 54.016656 -11.996928)
		(width 0.127)
		(layer "B.Cu")
		(net "P3E_CPU0_PE1_PCH_CON_RXP<14>")
	)
	(arc
		(start 52.9717 -7.40918)
		(mid 53.090121 -7.982927)
		(end 53.425852 -8.463026)
		(width 0.127)
		(layer "B.Cu")
		(net "P3E_CPU0_PE1_PCH_CON_RXP<14>")
	)
	(arc
		(start 53.425852 -8.463026)
		(mid 53.73423 -8.744803)
		(end 53.888894 -9.132824)
		(width 0.127)
		(layer "B.Cu")
		(net "P3E_CPU0_PE1_PCH_CON_RXP<14>")
	)
	(segment
		(start 47.282608 6.905752)
		(end 47.320708 7.150608)
		(width 0.127)
		(layer "B.Cu")
		(net "P3E_CPU0_PE1_PCH_CON_RXP<13>")
	)
	(segment
		(start 55.163974 -3.570732)
		(end 47.752508 6.560312)
		(width 0.127)
		(layer "B.Cu")
		(net "P3E_CPU0_PE1_PCH_CON_RXP<13>")
	)
	(segment
		(start 47.320708 7.150608)
		(end 47.095664 7.458202)
		(width 0.127)
		(layer "B.Cu")
		(net "P3E_CPU0_PE1_PCH_CON_RXP<13>")
	)
	(segment
		(start 56.900318 -7.306056)
		(end 56.90997 -7.179056)
		(width 0.127)
		(layer "B.Cu")
		(net "P3E_CPU0_PE1_PCH_CON_RXP<13>")
	)
	(segment
		(start 56.899556 -7.306564)
		(end 56.89981 -7.30631)
		(width 0.127)
		(layer "B.Cu")
		(net "P3E_CPU0_PE1_PCH_CON_RXP<13>")
	)
	(segment
		(start 56.89981 -7.30631)
		(end 56.900064 -7.30631)
		(width 0.127)
		(layer "B.Cu")
		(net "P3E_CPU0_PE1_PCH_CON_RXP<13>")
	)
	(segment
		(start 57.623202 -12.581382)
		(end 57.623456 -12.581382)
		(width 0.127)
		(layer "B.Cu")
		(net "P3E_CPU0_PE1_PCH_CON_RXP<13>")
	)
	(segment
		(start 46.850808 7.496048)
		(end 46.625764 7.803642)
		(width 0.127)
		(layer "B.Cu")
		(net "P3E_CPU0_PE1_PCH_CON_RXP<13>")
	)
	(segment
		(start 46.43882 8.356092)
		(end 46.227492 9.342882)
		(width 0.127)
		(layer "B.Cu")
		(net "P3E_CPU0_PE1_PCH_CON_RXP<13>")
	)
	(segment
		(start 46.625764 7.803642)
		(end 46.663864 8.048498)
		(width 0.127)
		(layer "B.Cu")
		(net "P3E_CPU0_PE1_PCH_CON_RXP<13>")
	)
	(segment
		(start 47.095664 7.458202)
		(end 46.850808 7.496048)
		(width 0.127)
		(layer "B.Cu")
		(net "P3E_CPU0_PE1_PCH_CON_RXP<13>")
	)
	(segment
		(start 46.227492 9.342882)
		(end 46.227492 10.366756)
		(width 0.127)
		(layer "B.Cu")
		(net "P3E_CPU0_PE1_PCH_CON_RXP<13>")
	)
	(segment
		(start 45.979842 10.964164)
		(end 45.979842 12.514072)
		(width 0.127)
		(layer "B.Cu")
		(net "P3E_CPU0_PE1_PCH_CON_RXP<13>")
	)
	(segment
		(start 47.752508 6.560312)
		(end 47.507652 6.598158)
		(width 0.127)
		(layer "B.Cu")
		(net "P3E_CPU0_PE1_PCH_CON_RXP<13>")
	)
	(segment
		(start 47.507652 6.598158)
		(end 47.282608 6.905752)
		(width 0.127)
		(layer "B.Cu")
		(net "P3E_CPU0_PE1_PCH_CON_RXP<13>")
	)
	(segment
		(start 57.623456 -12.581382)
		(end 57.737248 -12.52474)
		(width 0.127)
		(layer "B.Cu")
		(net "P3E_CPU0_PE1_PCH_CON_RXP<13>")
	)
	(segment
		(start 56.820562 -6.672834)
		(end 55.163974 -3.570732)
		(width 0.127)
		(layer "B.Cu")
		(net "P3E_CPU0_PE1_PCH_CON_RXP<13>")
	)
	(segment
		(start 46.104048 10.665206)
		(end 46.103794 10.66546)
		(width 0.127)
		(layer "B.Cu")
		(net "P3E_CPU0_PE1_PCH_CON_RXP<13>")
	)
	(segment
		(start 46.663864 8.048498)
		(end 46.43882 8.356092)
		(width 0.127)
		(layer "B.Cu")
		(net "P3E_CPU0_PE1_PCH_CON_RXP<13>")
	)
	(segment
		(start 57.079642 -11.749786)
		(end 57.242964 -12.102846)
		(width 0.127)
		(layer "B.Cu")
		(net "P3E_CPU0_PE1_PCH_CON_RXP<13>")
	)
	(segment
		(start 57.242964 -12.102846)
		(end 57.452768 -12.524486)
		(width 0.127)
		(layer "B.Cu")
		(net "P3E_CPU0_PE1_PCH_CON_RXP<13>")
	)
	(segment
		(start 56.90997 -7.179056)
		(end 56.820562 -6.672834)
		(width 0.127)
		(layer "B.Cu")
		(net "P3E_CPU0_PE1_PCH_CON_RXP<13>")
	)
	(segment
		(start 56.900064 -7.30631)
		(end 56.900318 -7.306056)
		(width 0.127)
		(layer "B.Cu")
		(net "P3E_CPU0_PE1_PCH_CON_RXP<13>")
	)
	(arc
		(start 57.737248 -12.52474)
		(mid 57.961263 -12.305536)
		(end 58.015886 -11.996928)
		(width 0.127)
		(layer "B.Cu")
		(net "P3E_CPU0_PE1_PCH_CON_RXP<13>")
	)
	(arc
		(start 57.45226 -8.479028)
		(mid 57.000395 -7.975518)
		(end 56.899556 -7.306564)
		(width 0.127)
		(layer "B.Cu")
		(net "P3E_CPU0_PE1_PCH_CON_RXP<13>")
	)
	(arc
		(start 46.227492 10.366756)
		(mid 46.195407 10.528236)
		(end 46.104048 10.665206)
		(width 0.127)
		(layer "B.Cu")
		(net "P3E_CPU0_PE1_PCH_CON_RXP<13>")
	)
	(arc
		(start 57.452768 -12.524486)
		(mid 57.526182 -12.588215)
		(end 57.623202 -12.581382)
		(width 0.127)
		(layer "B.Cu")
		(net "P3E_CPU0_PE1_PCH_CON_RXP<13>")
	)
	(arc
		(start 58.015886 -11.996928)
		(mid 57.976825 -11.550474)
		(end 57.981596 -11.10234)
		(width 0.127)
		(layer "B.Cu")
		(net "P3E_CPU0_PE1_PCH_CON_RXP<13>")
	)
	(arc
		(start 57.888124 -9.132824)
		(mid 57.74226 -8.757889)
		(end 57.45226 -8.479028)
		(width 0.127)
		(layer "B.Cu")
		(net "P3E_CPU0_PE1_PCH_CON_RXP<13>")
	)
	(arc
		(start 46.103794 10.66546)
		(mid 46.012139 10.802492)
		(end 45.979842 10.964164)
		(width 0.127)
		(layer "B.Cu")
		(net "P3E_CPU0_PE1_PCH_CON_RXP<13>")
	)
	(arc
		(start 57.981596 -11.10234)
		(mid 57.987412 -10.115087)
		(end 57.888124 -9.132824)
		(width 0.127)
		(layer "B.Cu")
		(net "P3E_CPU0_PE1_PCH_CON_RXP<13>")
	)
	(segment
		(start 49.074832 7.523226)
		(end 49.031906 7.279132)
		(width 0.127)
		(layer "B.Cu")
		(net "P3E_CPU0_PE1_PCH_CON_RXP<12>")
	)
	(segment
		(start 61.452506 -8.478774)
		(end 61.45276 -8.479028)
		(width 0.127)
		(layer "B.Cu")
		(net "P3E_CPU0_PE1_PCH_CON_RXP<12>")
	)
	(segment
		(start 48.628046 10.430002)
		(end 48.657764 10.03808)
		(width 0.127)
		(layer "B.Cu")
		(net "P3E_CPU0_PE1_PCH_CON_RXP<12>")
	)
	(segment
		(start 59.993784 -5.167376)
		(end 60.849256 -6.388862)
		(width 0.127)
		(layer "B.Cu")
		(net "P3E_CPU0_PE1_PCH_CON_RXP<12>")
	)
	(segment
		(start 48.379888 12.514072)
		(end 48.379888 11.027918)
		(width 0.127)
		(layer "B.Cu")
		(net "P3E_CPU0_PE1_PCH_CON_RXP<12>")
	)
	(segment
		(start 61.453268 -12.524486)
		(end 61.080142 -11.749786)
		(width 0.127)
		(layer "B.Cu")
		(net "P3E_CPU0_PE1_PCH_CON_RXP<12>")
	)
	(segment
		(start 53.465984 1.25222)
		(end 56.005984 -2.375408)
		(width 0.127)
		(layer "B.Cu")
		(net "P3E_CPU0_PE1_PCH_CON_RXP<12>")
	)
	(segment
		(start 48.657764 10.03808)
		(end 48.575722 9.573006)
		(width 0.127)
		(layer "B.Cu")
		(net "P3E_CPU0_PE1_PCH_CON_RXP<12>")
	)
	(segment
		(start 61.737748 -12.52474)
		(end 61.623956 -12.581382)
		(width 0.127)
		(layer "B.Cu")
		(net "P3E_CPU0_PE1_PCH_CON_RXP<12>")
	)
	(segment
		(start 49.031906 7.279132)
		(end 49.250346 6.96722)
		(width 0.127)
		(layer "B.Cu")
		(net "P3E_CPU0_PE1_PCH_CON_RXP<12>")
	)
	(segment
		(start 48.578262 9.570466)
		(end 48.578262 9.414256)
		(width 0.127)
		(layer "B.Cu")
		(net "P3E_CPU0_PE1_PCH_CON_RXP<12>")
	)
	(segment
		(start 49.669954 6.36778)
		(end 49.888648 6.055868)
		(width 0.127)
		(layer "B.Cu")
		(net "P3E_CPU0_PE1_PCH_CON_RXP<12>")
	)
	(segment
		(start 49.713134 6.611874)
		(end 49.669954 6.36778)
		(width 0.127)
		(layer "B.Cu")
		(net "P3E_CPU0_PE1_PCH_CON_RXP<12>")
	)
	(segment
		(start 48.575722 9.573006)
		(end 48.578262 9.570466)
		(width 0.127)
		(layer "B.Cu")
		(net "P3E_CPU0_PE1_PCH_CON_RXP<12>")
	)
	(segment
		(start 50.132742 6.012688)
		(end 53.046376 1.851406)
		(width 0.127)
		(layer "B.Cu")
		(net "P3E_CPU0_PE1_PCH_CON_RXP<12>")
	)
	(segment
		(start 48.578262 9.414256)
		(end 48.856392 7.835392)
		(width 0.127)
		(layer "B.Cu")
		(net "P3E_CPU0_PE1_PCH_CON_RXP<12>")
	)
	(segment
		(start 60.953396 -6.979666)
		(end 60.903866 -7.280656)
		(width 0.127)
		(layer "B.Cu")
		(net "P3E_CPU0_PE1_PCH_CON_RXP<12>")
	)
	(segment
		(start 61.623956 -12.581382)
		(end 61.623702 -12.581382)
		(width 0.127)
		(layer "B.Cu")
		(net "P3E_CPU0_PE1_PCH_CON_RXP<12>")
	)
	(segment
		(start 49.49444 6.92404)
		(end 49.713134 6.611874)
		(width 0.127)
		(layer "B.Cu")
		(net "P3E_CPU0_PE1_PCH_CON_RXP<12>")
	)
	(segment
		(start 48.627538 10.43051)
		(end 48.628046 10.430002)
		(width 0.127)
		(layer "B.Cu")
		(net "P3E_CPU0_PE1_PCH_CON_RXP<12>")
	)
	(segment
		(start 53.046376 1.851406)
		(end 53.465984 1.25222)
		(width 0.127)
		(layer "B.Cu")
		(net "P3E_CPU0_PE1_PCH_CON_RXP<12>")
	)
	(segment
		(start 60.849256 -6.388862)
		(end 60.953396 -6.979666)
		(width 0.127)
		(layer "B.Cu")
		(net "P3E_CPU0_PE1_PCH_CON_RXP<12>")
	)
	(segment
		(start 48.856392 7.835392)
		(end 49.074832 7.523226)
		(width 0.127)
		(layer "B.Cu")
		(net "P3E_CPU0_PE1_PCH_CON_RXP<12>")
	)
	(segment
		(start 56.005984 -2.375408)
		(end 59.993784 -5.167376)
		(width 0.127)
		(layer "B.Cu")
		(net "P3E_CPU0_PE1_PCH_CON_RXP<12>")
	)
	(segment
		(start 49.888648 6.055868)
		(end 50.132742 6.012688)
		(width 0.127)
		(layer "B.Cu")
		(net "P3E_CPU0_PE1_PCH_CON_RXP<12>")
	)
	(segment
		(start 49.250346 6.96722)
		(end 49.49444 6.92404)
		(width 0.127)
		(layer "B.Cu")
		(net "P3E_CPU0_PE1_PCH_CON_RXP<12>")
	)
	(segment
		(start 48.50384 10.729214)
		(end 48.504094 10.72896)
		(width 0.127)
		(layer "B.Cu")
		(net "P3E_CPU0_PE1_PCH_CON_RXP<12>")
	)
	(arc
		(start 48.379888 11.027918)
		(mid 48.412144 10.866228)
		(end 48.50384 10.729214)
		(width 0.127)
		(layer "B.Cu")
		(net "P3E_CPU0_PE1_PCH_CON_RXP<12>")
	)
	(arc
		(start 61.888624 -9.132824)
		(mid 61.98789 -10.115088)
		(end 61.982096 -11.10234)
		(width 0.127)
		(layer "B.Cu")
		(net "P3E_CPU0_PE1_PCH_CON_RXP<12>")
	)
	(arc
		(start 61.45276 -8.479028)
		(mid 61.742809 -8.757856)
		(end 61.888624 -9.132824)
		(width 0.127)
		(layer "B.Cu")
		(net "P3E_CPU0_PE1_PCH_CON_RXP<12>")
	)
	(arc
		(start 60.903866 -7.280656)
		(mid 60.99536 -7.963416)
		(end 61.452506 -8.478774)
		(width 0.127)
		(layer "B.Cu")
		(net "P3E_CPU0_PE1_PCH_CON_RXP<12>")
	)
	(arc
		(start 61.982096 -11.10234)
		(mid 61.97732 -11.550474)
		(end 62.016386 -11.996928)
		(width 0.127)
		(layer "B.Cu")
		(net "P3E_CPU0_PE1_PCH_CON_RXP<12>")
	)
	(arc
		(start 62.016386 -11.996928)
		(mid 61.961715 -12.305511)
		(end 61.737748 -12.52474)
		(width 0.127)
		(layer "B.Cu")
		(net "P3E_CPU0_PE1_PCH_CON_RXP<12>")
	)
	(arc
		(start 48.504094 10.72896)
		(mid 48.59548 10.592002)
		(end 48.627538 10.43051)
		(width 0.127)
		(layer "B.Cu")
		(net "P3E_CPU0_PE1_PCH_CON_RXP<12>")
	)
	(arc
		(start 61.623702 -12.581382)
		(mid 61.526646 -12.588323)
		(end 61.453268 -12.524486)
		(width 0.127)
		(layer "B.Cu")
		(net "P3E_CPU0_PE1_PCH_CON_RXP<12>")
	)
	(segment
		(start 51.027584 10.41781)
		(end 51.028092 10.417302)
		(width 0.127)
		(layer "B.Cu")
		(net "P3E_CPU0_PE1_PCH_CON_RXP<11>")
	)
	(segment
		(start 53.23205 4.991862)
		(end 53.406294 4.742942)
		(width 0.127)
		(layer "B.Cu")
		(net "P3E_CPU0_PE1_PCH_CON_RXP<11>")
	)
	(segment
		(start 52.038758 6.698742)
		(end 51.995832 6.454648)
		(width 0.127)
		(layer "B.Cu")
		(net "P3E_CPU0_PE1_PCH_CON_RXP<11>")
	)
	(segment
		(start 51.357784 7.366)
		(end 51.576224 7.054088)
		(width 0.127)
		(layer "B.Cu")
		(net "P3E_CPU0_PE1_PCH_CON_RXP<11>")
	)
	(segment
		(start 51.18227 7.92226)
		(end 51.40071 7.610094)
		(width 0.127)
		(layer "B.Cu")
		(net "P3E_CPU0_PE1_PCH_CON_RXP<11>")
	)
	(segment
		(start 50.779934 12.514072)
		(end 50.779934 11.015472)
		(width 0.127)
		(layer "B.Cu")
		(net "P3E_CPU0_PE1_PCH_CON_RXP<11>")
	)
	(segment
		(start 51.05781 10.025126)
		(end 50.93462 9.327134)
		(width 0.127)
		(layer "B.Cu")
		(net "P3E_CPU0_PE1_PCH_CON_RXP<11>")
	)
	(segment
		(start 53.406294 4.742942)
		(end 53.408326 4.740148)
		(width 0.127)
		(layer "B.Cu")
		(net "P3E_CPU0_PE1_PCH_CON_RXP<11>")
	)
	(segment
		(start 66.814954 -6.689598)
		(end 66.954654 -7.481824)
		(width 0.127)
		(layer "B.Cu")
		(net "P3E_CPU0_PE1_PCH_CON_RXP<11>")
	)
	(segment
		(start 51.576224 7.054088)
		(end 51.820318 7.010908)
		(width 0.127)
		(layer "B.Cu")
		(net "P3E_CPU0_PE1_PCH_CON_RXP<11>")
	)
	(segment
		(start 52.214272 6.142736)
		(end 52.458366 6.099556)
		(width 0.127)
		(layer "B.Cu")
		(net "P3E_CPU0_PE1_PCH_CON_RXP<11>")
	)
	(segment
		(start 51.995832 6.454648)
		(end 52.214272 6.142736)
		(width 0.127)
		(layer "B.Cu")
		(net "P3E_CPU0_PE1_PCH_CON_RXP<11>")
	)
	(segment
		(start 50.93462 9.327134)
		(end 51.18227 7.92226)
		(width 0.127)
		(layer "B.Cu")
		(net "P3E_CPU0_PE1_PCH_CON_RXP<11>")
	)
	(segment
		(start 67.737228 -12.52474)
		(end 67.623436 -12.581382)
		(width 0.127)
		(layer "B.Cu")
		(net "P3E_CPU0_PE1_PCH_CON_RXP<11>")
	)
	(segment
		(start 51.028092 10.417302)
		(end 51.05781 10.025126)
		(width 0.127)
		(layer "B.Cu")
		(net "P3E_CPU0_PE1_PCH_CON_RXP<11>")
	)
	(segment
		(start 67.138042 -11.89228)
		(end 67.079622 -11.749786)
		(width 0.127)
		(layer "B.Cu")
		(net "P3E_CPU0_PE1_PCH_CON_RXP<11>")
	)
	(segment
		(start 67.623436 -12.581382)
		(end 67.623182 -12.581382)
		(width 0.127)
		(layer "B.Cu")
		(net "P3E_CPU0_PE1_PCH_CON_RXP<11>")
	)
	(segment
		(start 51.820318 7.010908)
		(end 52.038758 6.698742)
		(width 0.127)
		(layer "B.Cu")
		(net "P3E_CPU0_PE1_PCH_CON_RXP<11>")
	)
	(segment
		(start 55.808626 1.31191)
		(end 66.409824 -6.11124)
		(width 0.127)
		(layer "B.Cu")
		(net "P3E_CPU0_PE1_PCH_CON_RXP<11>")
	)
	(segment
		(start 53.231542 4.995164)
		(end 53.23205 4.991862)
		(width 0.127)
		(layer "B.Cu")
		(net "P3E_CPU0_PE1_PCH_CON_RXP<11>")
	)
	(segment
		(start 53.408326 4.740148)
		(end 55.808626 1.31191)
		(width 0.127)
		(layer "B.Cu")
		(net "P3E_CPU0_PE1_PCH_CON_RXP<11>")
	)
	(segment
		(start 52.458366 6.099556)
		(end 53.231542 4.995164)
		(width 0.127)
		(layer "B.Cu")
		(net "P3E_CPU0_PE1_PCH_CON_RXP<11>")
	)
	(segment
		(start 67.452748 -12.524486)
		(end 67.138042 -11.89228)
		(width 0.127)
		(layer "B.Cu")
		(net "P3E_CPU0_PE1_PCH_CON_RXP<11>")
	)
	(segment
		(start 66.409824 -6.11124)
		(end 66.814954 -6.689598)
		(width 0.127)
		(layer "B.Cu")
		(net "P3E_CPU0_PE1_PCH_CON_RXP<11>")
	)
	(segment
		(start 67.3227 -8.343646)
		(end 67.756278 -8.777224)
		(width 0.127)
		(layer "B.Cu")
		(net "P3E_CPU0_PE1_PCH_CON_RXP<11>")
	)
	(segment
		(start 51.40071 7.610094)
		(end 51.357784 7.366)
		(width 0.127)
		(layer "B.Cu")
		(net "P3E_CPU0_PE1_PCH_CON_RXP<11>")
	)
	(arc
		(start 68.015866 -11.996928)
		(mid 67.961195 -12.305511)
		(end 67.737228 -12.52474)
		(width 0.127)
		(layer "B.Cu")
		(net "P3E_CPU0_PE1_PCH_CON_RXP<11>")
	)
	(arc
		(start 66.954654 -7.481824)
		(mid 67.055467 -7.948281)
		(end 67.3227 -8.343646)
		(width 0.127)
		(layer "B.Cu")
		(net "P3E_CPU0_PE1_PCH_CON_RXP<11>")
	)
	(arc
		(start 67.623182 -12.581382)
		(mid 67.526126 -12.588323)
		(end 67.452748 -12.524486)
		(width 0.127)
		(layer "B.Cu")
		(net "P3E_CPU0_PE1_PCH_CON_RXP<11>")
	)
	(arc
		(start 50.779934 11.015472)
		(mid 50.812156 10.85366)
		(end 50.903886 10.716514)
		(width 0.127)
		(layer "B.Cu")
		(net "P3E_CPU0_PE1_PCH_CON_RXP<11>")
	)
	(arc
		(start 50.903886 10.716514)
		(mid 50.995458 10.579467)
		(end 51.027584 10.41781)
		(width 0.127)
		(layer "B.Cu")
		(net "P3E_CPU0_PE1_PCH_CON_RXP<11>")
	)
	(arc
		(start 67.981576 -11.10234)
		(mid 67.9768 -11.550474)
		(end 68.015866 -11.996928)
		(width 0.127)
		(layer "B.Cu")
		(net "P3E_CPU0_PE1_PCH_CON_RXP<11>")
	)
	(arc
		(start 67.884294 -9.086088)
		(mid 67.884164 -9.096505)
		(end 67.883786 -9.106916)
		(width 0.127)
		(layer "B.Cu")
		(net "P3E_CPU0_PE1_PCH_CON_RXP<11>")
	)
	(arc
		(start 67.756278 -8.777224)
		(mid 67.850964 -8.918932)
		(end 67.884294 -9.086088)
		(width 0.127)
		(layer "B.Cu")
		(net "P3E_CPU0_PE1_PCH_CON_RXP<11>")
	)
	(arc
		(start 67.883786 -9.106916)
		(mid 67.986623 -10.101984)
		(end 67.981576 -11.10234)
		(width 0.127)
		(layer "B.Cu")
		(net "P3E_CPU0_PE1_PCH_CON_RXP<11>")
	)
	(segment
		(start 70.844664 -6.030976)
		(end 70.870572 -6.150864)
		(width 0.127)
		(layer "B.Cu")
		(net "P3E_CPU0_PE1_PCH_CON_RXP<10>")
	)
	(segment
		(start 71.737728 -12.52474)
		(end 71.623936 -12.581382)
		(width 0.127)
		(layer "B.Cu")
		(net "P3E_CPU0_PE1_PCH_CON_RXP<10>")
	)
	(segment
		(start 54.489858 7.092696)
		(end 54.733952 7.049516)
		(width 0.127)
		(layer "B.Cu")
		(net "P3E_CPU0_PE1_PCH_CON_RXP<10>")
	)
	(segment
		(start 53.676296 8.560054)
		(end 53.63337 8.31596)
		(width 0.127)
		(layer "B.Cu")
		(net "P3E_CPU0_PE1_PCH_CON_RXP<10>")
	)
	(segment
		(start 71.3232 -8.343646)
		(end 71.756778 -8.777224)
		(width 0.127)
		(layer "B.Cu")
		(net "P3E_CPU0_PE1_PCH_CON_RXP<10>")
	)
	(segment
		(start 53.42763 10.481818)
		(end 53.429408 10.479024)
		(width 0.127)
		(layer "B.Cu")
		(net "P3E_CPU0_PE1_PCH_CON_RXP<10>")
	)
	(segment
		(start 53.302408 9.753092)
		(end 53.457856 8.87222)
		(width 0.127)
		(layer "B.Cu")
		(net "P3E_CPU0_PE1_PCH_CON_RXP<10>")
	)
	(segment
		(start 70.9549 -6.6294)
		(end 70.9549 -7.453122)
		(width 0.127)
		(layer "B.Cu")
		(net "P3E_CPU0_PE1_PCH_CON_RXP<10>")
	)
	(segment
		(start 54.271418 7.404608)
		(end 54.489858 7.092696)
		(width 0.127)
		(layer "B.Cu")
		(net "P3E_CPU0_PE1_PCH_CON_RXP<10>")
	)
	(segment
		(start 53.4289 10.476738)
		(end 53.302408 9.753092)
		(width 0.127)
		(layer "B.Cu")
		(net "P3E_CPU0_PE1_PCH_CON_RXP<10>")
	)
	(segment
		(start 53.429408 10.479024)
		(end 53.4289 10.476738)
		(width 0.127)
		(layer "B.Cu")
		(net "P3E_CPU0_PE1_PCH_CON_RXP<10>")
	)
	(segment
		(start 54.733952 7.049516)
		(end 56.822848 4.066286)
		(width 0.127)
		(layer "B.Cu")
		(net "P3E_CPU0_PE1_PCH_CON_RXP<10>")
	)
	(segment
		(start 53.303932 10.780522)
		(end 53.304186 10.780268)
		(width 0.127)
		(layer "B.Cu")
		(net "P3E_CPU0_PE1_PCH_CON_RXP<10>")
	)
	(segment
		(start 70.461378 -5.48386)
		(end 70.844664 -6.030976)
		(width 0.127)
		(layer "B.Cu")
		(net "P3E_CPU0_PE1_PCH_CON_RXP<10>")
	)
	(segment
		(start 53.63337 8.31596)
		(end 53.85181 8.004048)
		(width 0.127)
		(layer "B.Cu")
		(net "P3E_CPU0_PE1_PCH_CON_RXP<10>")
	)
	(segment
		(start 53.17998 12.514072)
		(end 53.17998 11.079226)
		(width 0.127)
		(layer "B.Cu")
		(net "P3E_CPU0_PE1_PCH_CON_RXP<10>")
	)
	(segment
		(start 70.870572 -6.150864)
		(end 70.9549 -6.6294)
		(width 0.127)
		(layer "B.Cu")
		(net "P3E_CPU0_PE1_PCH_CON_RXP<10>")
	)
	(segment
		(start 53.85181 8.004048)
		(end 54.095904 7.960868)
		(width 0.127)
		(layer "B.Cu")
		(net "P3E_CPU0_PE1_PCH_CON_RXP<10>")
	)
	(segment
		(start 71.453248 -12.524486)
		(end 71.138542 -11.89228)
		(width 0.127)
		(layer "B.Cu")
		(net "P3E_CPU0_PE1_PCH_CON_RXP<10>")
	)
	(segment
		(start 54.314598 7.648702)
		(end 54.271418 7.404608)
		(width 0.127)
		(layer "B.Cu")
		(net "P3E_CPU0_PE1_PCH_CON_RXP<10>")
	)
	(segment
		(start 71.138542 -11.89228)
		(end 71.080122 -11.749786)
		(width 0.127)
		(layer "B.Cu")
		(net "P3E_CPU0_PE1_PCH_CON_RXP<10>")
	)
	(segment
		(start 54.095904 7.960868)
		(end 54.314598 7.648702)
		(width 0.127)
		(layer "B.Cu")
		(net "P3E_CPU0_PE1_PCH_CON_RXP<10>")
	)
	(segment
		(start 56.822848 4.066286)
		(end 70.461378 -5.48386)
		(width 0.127)
		(layer "B.Cu")
		(net "P3E_CPU0_PE1_PCH_CON_RXP<10>")
	)
	(segment
		(start 71.623936 -12.581382)
		(end 71.623682 -12.581382)
		(width 0.127)
		(layer "B.Cu")
		(net "P3E_CPU0_PE1_PCH_CON_RXP<10>")
	)
	(segment
		(start 53.457856 8.87222)
		(end 53.676296 8.560054)
		(width 0.127)
		(layer "B.Cu")
		(net "P3E_CPU0_PE1_PCH_CON_RXP<10>")
	)
	(arc
		(start 71.982076 -11.10234)
		(mid 71.9773 -11.550474)
		(end 72.016366 -11.996928)
		(width 0.127)
		(layer "B.Cu")
		(net "P3E_CPU0_PE1_PCH_CON_RXP<10>")
	)
	(arc
		(start 71.884794 -9.086088)
		(mid 71.884664 -9.096505)
		(end 71.884286 -9.106916)
		(width 0.127)
		(layer "B.Cu")
		(net "P3E_CPU0_PE1_PCH_CON_RXP<10>")
	)
	(arc
		(start 53.17998 11.079226)
		(mid 53.212236 10.917536)
		(end 53.303932 10.780522)
		(width 0.127)
		(layer "B.Cu")
		(net "P3E_CPU0_PE1_PCH_CON_RXP<10>")
	)
	(arc
		(start 70.9549 -7.453122)
		(mid 71.050458 -7.935028)
		(end 71.3232 -8.343646)
		(width 0.127)
		(layer "B.Cu")
		(net "P3E_CPU0_PE1_PCH_CON_RXP<10>")
	)
	(arc
		(start 71.884286 -9.106916)
		(mid 71.987123 -10.101984)
		(end 71.982076 -11.10234)
		(width 0.127)
		(layer "B.Cu")
		(net "P3E_CPU0_PE1_PCH_CON_RXP<10>")
	)
	(arc
		(start 72.016366 -11.996928)
		(mid 71.961695 -12.305511)
		(end 71.737728 -12.52474)
		(width 0.127)
		(layer "B.Cu")
		(net "P3E_CPU0_PE1_PCH_CON_RXP<10>")
	)
	(arc
		(start 71.756778 -8.777224)
		(mid 71.851464 -8.918932)
		(end 71.884794 -9.086088)
		(width 0.127)
		(layer "B.Cu")
		(net "P3E_CPU0_PE1_PCH_CON_RXP<10>")
	)
	(arc
		(start 53.304186 10.780268)
		(mid 53.395572 10.64331)
		(end 53.42763 10.481818)
		(width 0.127)
		(layer "B.Cu")
		(net "P3E_CPU0_PE1_PCH_CON_RXP<10>")
	)
	(arc
		(start 71.623682 -12.581382)
		(mid 71.526626 -12.588323)
		(end 71.453248 -12.524486)
		(width 0.127)
		(layer "B.Cu")
		(net "P3E_CPU0_PE1_PCH_CON_RXP<10>")
	)
	(segment
		(start 56.132476 10.44067)
		(end 56.132476 9.191752)
		(width 0.127)
		(layer "B.Cu")
		(net "P3E_CPU0_PE1_PCH_CON_RXN<9>")
	)
	(segment
		(start 74.917554 -6.235954)
		(end 75.1078 -6.4262)
		(width 0.127)
		(layer "B.Cu")
		(net "P3E_CPU0_PE1_PCH_CON_RXN<9>")
	)
	(segment
		(start 75.53833 -8.128)
		(end 75.971654 -8.561578)
		(width 0.127)
		(layer "B.Cu")
		(net "P3E_CPU0_PE1_PCH_CON_RXN<9>")
	)
	(segment
		(start 75.759818 -12.853924)
		(end 75.759564 -12.853924)
		(width 0.127)
		(layer "B.Cu")
		(net "P3E_CPU0_PE1_PCH_CON_RXN<9>")
	)
	(segment
		(start 59.573922 4.143248)
		(end 73.983342 -5.94614)
		(width 0.127)
		(layer "B.Cu")
		(net "P3E_CPU0_PE1_PCH_CON_RXN<9>")
	)
	(segment
		(start 75.761088 -12.853416)
		(end 75.759818 -12.853924)
		(width 0.127)
		(layer "B.Cu")
		(net "P3E_CPU0_PE1_PCH_CON_RXN<9>")
	)
	(segment
		(start 75.873102 -12.797536)
		(end 75.761088 -12.853416)
		(width 0.127)
		(layer "B.Cu")
		(net "P3E_CPU0_PE1_PCH_CON_RXN<9>")
	)
	(segment
		(start 56.247284 8.827516)
		(end 59.417966 4.299204)
		(width 0.127)
		(layer "B.Cu")
		(net "P3E_CPU0_PE1_PCH_CON_RXN<9>")
	)
	(segment
		(start 75.972162 -13.560044)
		(end 76.080112 -13.750036)
		(width 0.127)
		(layer "B.Cu")
		(net "P3E_CPU0_PE1_PCH_CON_RXN<9>")
	)
	(segment
		(start 75.702668 -13.024358)
		(end 75.972162 -13.560044)
		(width 0.127)
		(layer "B.Cu")
		(net "P3E_CPU0_PE1_PCH_CON_RXN<9>")
	)
	(segment
		(start 74.05624 -5.969)
		(end 74.273156 -5.969)
		(width 0.127)
		(layer "B.Cu")
		(net "P3E_CPU0_PE1_PCH_CON_RXN<9>")
	)
	(segment
		(start 56.379872 12.514072)
		(end 56.379872 11.038078)
		(width 0.127)
		(layer "B.Cu")
		(net "P3E_CPU0_PE1_PCH_CON_RXN<9>")
	)
	(segment
		(start 75.25893 -6.790944)
		(end 75.25893 -7.453376)
		(width 0.127)
		(layer "B.Cu")
		(net "P3E_CPU0_PE1_PCH_CON_RXN<9>")
	)
	(arc
		(start 56.256174 10.739374)
		(mid 56.164602 10.602327)
		(end 56.132476 10.44067)
		(width 0.127)
		(layer "B.Cu")
		(net "P3E_CPU0_PE1_PCH_CON_RXN<9>")
	)
	(arc
		(start 76.317602 -11.955526)
		(mid 76.230599 -12.447957)
		(end 75.873102 -12.797536)
		(width 0.127)
		(layer "B.Cu")
		(net "P3E_CPU0_PE1_PCH_CON_RXN<9>")
	)
	(arc
		(start 59.417966 4.299204)
		(mid 59.489121 4.214403)
		(end 59.573922 4.143248)
		(width 0.127)
		(layer "B.Cu")
		(net "P3E_CPU0_PE1_PCH_CON_RXN<9>")
	)
	(arc
		(start 74.273156 -5.969)
		(mid 74.621915 -6.038373)
		(end 74.917554 -6.235954)
		(width 0.127)
		(layer "B.Cu")
		(net "P3E_CPU0_PE1_PCH_CON_RXN<9>")
	)
	(arc
		(start 56.132476 9.191752)
		(mid 56.161855 9.000799)
		(end 56.247284 8.827516)
		(width 0.127)
		(layer "B.Cu")
		(net "P3E_CPU0_PE1_PCH_CON_RXN<9>")
	)
	(arc
		(start 56.379872 11.038078)
		(mid 56.347719 10.876432)
		(end 56.256174 10.739374)
		(width 0.127)
		(layer "B.Cu")
		(net "P3E_CPU0_PE1_PCH_CON_RXN<9>")
	)
	(arc
		(start 75.759564 -12.853924)
		(mid 75.695801 -12.927377)
		(end 75.702668 -13.024358)
		(width 0.127)
		(layer "B.Cu")
		(net "P3E_CPU0_PE1_PCH_CON_RXN<9>")
	)
	(arc
		(start 75.971654 -8.561578)
		(mid 76.132532 -8.80221)
		(end 76.189078 -9.086088)
		(width 0.127)
		(layer "B.Cu")
		(net "P3E_CPU0_PE1_PCH_CON_RXN<9>")
	)
	(arc
		(start 75.25893 -7.453376)
		(mid 75.331551 -7.818465)
		(end 75.53833 -8.128)
		(width 0.127)
		(layer "B.Cu")
		(net "P3E_CPU0_PE1_PCH_CON_RXN<9>")
	)
	(arc
		(start 73.983342 -5.94614)
		(mid 74.018033 -5.963169)
		(end 74.05624 -5.969)
		(width 0.127)
		(layer "B.Cu")
		(net "P3E_CPU0_PE1_PCH_CON_RXN<9>")
	)
	(arc
		(start 76.189078 -9.086088)
		(mid 76.291606 -10.100656)
		(end 76.285598 -11.120374)
		(width 0.127)
		(layer "B.Cu")
		(net "P3E_CPU0_PE1_PCH_CON_RXN<9>")
	)
	(arc
		(start 75.1078 -6.4262)
		(mid 75.219617 -6.593546)
		(end 75.25893 -6.790944)
		(width 0.127)
		(layer "B.Cu")
		(net "P3E_CPU0_PE1_PCH_CON_RXN<9>")
	)
	(arc
		(start 76.285598 -11.120374)
		(mid 76.28113 -11.538735)
		(end 76.317602 -11.955526)
		(width 0.127)
		(layer "B.Cu")
		(net "P3E_CPU0_PE1_PCH_CON_RXN<9>")
	)
	(segment
		(start 58.532268 9.09574)
		(end 60.481972 6.283452)
		(width 0.127)
		(layer "B.Cu")
		(net "P3E_CPU0_PE1_PCH_CON_RXN<8>")
	)
	(segment
		(start 79.53883 -8.128)
		(end 79.972154 -8.561578)
		(width 0.127)
		(layer "B.Cu")
		(net "P3E_CPU0_PE1_PCH_CON_RXN<8>")
	)
	(segment
		(start 62.282832 3.711194)
		(end 63.78829 2.657094)
		(width 0.127)
		(layer "B.Cu")
		(net "P3E_CPU0_PE1_PCH_CON_RXN<8>")
	)
	(segment
		(start 63.78829 2.657094)
		(end 66.79057 0.574802)
		(width 0.127)
		(layer "B.Cu")
		(net "P3E_CPU0_PE1_PCH_CON_RXN<8>")
	)
	(segment
		(start 79.703168 -13.024358)
		(end 80.079342 -13.750036)
		(width 0.127)
		(layer "B.Cu")
		(net "P3E_CPU0_PE1_PCH_CON_RXN<8>")
	)
	(segment
		(start 60.481972 6.283452)
		(end 62.282832 3.711194)
		(width 0.127)
		(layer "B.Cu")
		(net "P3E_CPU0_PE1_PCH_CON_RXN<8>")
	)
	(segment
		(start 79.760318 -12.853924)
		(end 79.760064 -12.853924)
		(width 0.127)
		(layer "B.Cu")
		(net "P3E_CPU0_PE1_PCH_CON_RXN<8>")
	)
	(segment
		(start 79.873602 -12.797536)
		(end 79.761588 -12.853416)
		(width 0.127)
		(layer "B.Cu")
		(net "P3E_CPU0_PE1_PCH_CON_RXN<8>")
	)
	(segment
		(start 79.761588 -12.853416)
		(end 79.760318 -12.853924)
		(width 0.127)
		(layer "B.Cu")
		(net "P3E_CPU0_PE1_PCH_CON_RXN<8>")
	)
	(segment
		(start 58.532268 10.427462)
		(end 58.532268 9.09574)
		(width 0.127)
		(layer "B.Cu")
		(net "P3E_CPU0_PE1_PCH_CON_RXN<8>")
	)
	(segment
		(start 79.25943 -7.1374)
		(end 79.25943 -7.453376)
		(width 0.127)
		(layer "B.Cu")
		(net "P3E_CPU0_PE1_PCH_CON_RXN<8>")
	)
	(segment
		(start 66.79057 0.574802)
		(end 69.993256 -1.62814)
		(width 0.127)
		(layer "B.Cu")
		(net "P3E_CPU0_PE1_PCH_CON_RXN<8>")
	)
	(segment
		(start 58.779918 12.514072)
		(end 58.779918 11.025124)
		(width 0.127)
		(layer "B.Cu")
		(net "P3E_CPU0_PE1_PCH_CON_RXN<8>")
	)
	(segment
		(start 69.993256 -1.62814)
		(end 74.521314 -4.75488)
		(width 0.127)
		(layer "B.Cu")
		(net "P3E_CPU0_PE1_PCH_CON_RXN<8>")
	)
	(segment
		(start 77.815948 -5.335524)
		(end 78.305152 -5.597906)
		(width 0.127)
		(layer "B.Cu")
		(net "P3E_CPU0_PE1_PCH_CON_RXN<8>")
	)
	(segment
		(start 74.521314 -4.75488)
		(end 77.815948 -5.335524)
		(width 0.127)
		(layer "B.Cu")
		(net "P3E_CPU0_PE1_PCH_CON_RXN<8>")
	)
	(arc
		(start 78.305152 -5.597906)
		(mid 78.35094 -5.621819)
		(end 78.396084 -5.646928)
		(width 0.127)
		(layer "B.Cu")
		(net "P3E_CPU0_PE1_PCH_CON_RXN<8>")
	)
	(arc
		(start 78.396084 -5.646928)
		(mid 79.027985 -6.276178)
		(end 79.25943 -7.1374)
		(width 0.127)
		(layer "B.Cu")
		(net "P3E_CPU0_PE1_PCH_CON_RXN<8>")
	)
	(arc
		(start 80.318102 -11.955526)
		(mid 80.231099 -12.447957)
		(end 79.873602 -12.797536)
		(width 0.127)
		(layer "B.Cu")
		(net "P3E_CPU0_PE1_PCH_CON_RXN<8>")
	)
	(arc
		(start 58.779918 11.025124)
		(mid 58.747765 10.863478)
		(end 58.65622 10.72642)
		(width 0.127)
		(layer "B.Cu")
		(net "P3E_CPU0_PE1_PCH_CON_RXN<8>")
	)
	(arc
		(start 79.760064 -12.853924)
		(mid 79.696301 -12.927377)
		(end 79.703168 -13.024358)
		(width 0.127)
		(layer "B.Cu")
		(net "P3E_CPU0_PE1_PCH_CON_RXN<8>")
	)
	(arc
		(start 80.286098 -11.120374)
		(mid 80.28163 -11.538735)
		(end 80.318102 -11.955526)
		(width 0.127)
		(layer "B.Cu")
		(net "P3E_CPU0_PE1_PCH_CON_RXN<8>")
	)
	(arc
		(start 79.25943 -7.453376)
		(mid 79.332051 -7.818465)
		(end 79.53883 -8.128)
		(width 0.127)
		(layer "B.Cu")
		(net "P3E_CPU0_PE1_PCH_CON_RXN<8>")
	)
	(arc
		(start 58.65622 10.72642)
		(mid 58.564463 10.589285)
		(end 58.532268 10.427462)
		(width 0.127)
		(layer "B.Cu")
		(net "P3E_CPU0_PE1_PCH_CON_RXN<8>")
	)
	(arc
		(start 80.189578 -9.086088)
		(mid 80.292106 -10.100656)
		(end 80.286098 -11.120374)
		(width 0.127)
		(layer "B.Cu")
		(net "P3E_CPU0_PE1_PCH_CON_RXN<8>")
	)
	(arc
		(start 79.972154 -8.561578)
		(mid 80.133032 -8.80221)
		(end 80.189578 -9.086088)
		(width 0.127)
		(layer "B.Cu")
		(net "P3E_CPU0_PE1_PCH_CON_RXN<8>")
	)
	(segment
		(start 36.932362 10.417556)
		(end 36.932362 9.8298)
		(width 0.127)
		(layer "B.Cu")
		(net "P3E_CPU0_PE1_PCH_CON_RXN<15>")
	)
	(segment
		(start 49.655984 -4.562856)
		(end 49.803812 -4.761992)
		(width 0.127)
		(layer "B.Cu")
		(net "P3E_CPU0_PE1_PCH_CON_RXN<15>")
	)
	(segment
		(start 37.338 8.7757)
		(end 39.7256 7.0231)
		(width 0.127)
		(layer "B.Cu")
		(net "P3E_CPU0_PE1_PCH_CON_RXN<15>")
	)
	(segment
		(start 48.534574 -12.58189)
		(end 48.534828 -12.58189)
		(width 0.127)
		(layer "B.Cu")
		(net "P3E_CPU0_PE1_PCH_CON_RXN<15>")
	)
	(segment
		(start 41.7195 5.9182)
		(end 44.1325 5.5245)
		(width 0.127)
		(layer "B.Cu")
		(net "P3E_CPU0_PE1_PCH_CON_RXN<15>")
	)
	(segment
		(start 49.548796 -5.286502)
		(end 49.492916 -5.663438)
		(width 0.127)
		(layer "B.Cu")
		(net "P3E_CPU0_PE1_PCH_CON_RXN<15>")
	)
	(segment
		(start 49.640744 -5.862574)
		(end 49.584864 -6.23951)
		(width 0.127)
		(layer "B.Cu")
		(net "P3E_CPU0_PE1_PCH_CON_RXN<15>")
	)
	(segment
		(start 49.803812 -4.761992)
		(end 49.747932 -5.138928)
		(width 0.127)
		(layer "B.Cu")
		(net "P3E_CPU0_PE1_PCH_CON_RXN<15>")
	)
	(segment
		(start 49.9237 -2.7559)
		(end 49.655984 -4.562856)
		(width 0.127)
		(layer "B.Cu")
		(net "P3E_CPU0_PE1_PCH_CON_RXN<15>")
	)
	(segment
		(start 37.180012 12.514072)
		(end 37.180012 10.962894)
		(width 0.127)
		(layer "B.Cu")
		(net "P3E_CPU0_PE1_PCH_CON_RXN<15>")
	)
	(segment
		(start 37.093144 10.753598)
		(end 37.05606 10.716514)
		(width 0.127)
		(layer "B.Cu")
		(net "P3E_CPU0_PE1_PCH_CON_RXN<15>")
	)
	(segment
		(start 49.404524 -0.27305)
		(end 49.8475 -1.8034)
		(width 0.127)
		(layer "B.Cu")
		(net "P3E_CPU0_PE1_PCH_CON_RXN<15>")
	)
	(segment
		(start 46.2153 4.3688)
		(end 49.404524 -0.27305)
		(width 0.127)
		(layer "B.Cu")
		(net "P3E_CPU0_PE1_PCH_CON_RXN<15>")
	)
	(segment
		(start 49.385728 -6.387084)
		(end 49.2506 -7.300214)
		(width 0.127)
		(layer "B.Cu")
		(net "P3E_CPU0_PE1_PCH_CON_RXN<15>")
	)
	(segment
		(start 48.420782 -12.524994)
		(end 48.534574 -12.58189)
		(width 0.127)
		(layer "B.Cu")
		(net "P3E_CPU0_PE1_PCH_CON_RXN<15>")
	)
	(segment
		(start 39.7256 7.0231)
		(end 41.7195 5.9182)
		(width 0.127)
		(layer "B.Cu")
		(net "P3E_CPU0_PE1_PCH_CON_RXN<15>")
	)
	(segment
		(start 49.8475 -1.8034)
		(end 49.9237 -2.7559)
		(width 0.127)
		(layer "B.Cu")
		(net "P3E_CPU0_PE1_PCH_CON_RXN<15>")
	)
	(segment
		(start 48.872902 -12.189206)
		(end 49.079912 -11.749786)
		(width 0.127)
		(layer "B.Cu")
		(net "P3E_CPU0_PE1_PCH_CON_RXN<15>")
	)
	(segment
		(start 49.492916 -5.663438)
		(end 49.640744 -5.862574)
		(width 0.127)
		(layer "B.Cu")
		(net "P3E_CPU0_PE1_PCH_CON_RXN<15>")
	)
	(segment
		(start 49.584864 -6.23951)
		(end 49.385728 -6.387084)
		(width 0.127)
		(layer "B.Cu")
		(net "P3E_CPU0_PE1_PCH_CON_RXN<15>")
	)
	(segment
		(start 37.0586 9.1821)
		(end 37.338 8.7757)
		(width 0.127)
		(layer "B.Cu")
		(net "P3E_CPU0_PE1_PCH_CON_RXN<15>")
	)
	(segment
		(start 48.705262 -12.524994)
		(end 48.872902 -12.189206)
		(width 0.127)
		(layer "B.Cu")
		(net "P3E_CPU0_PE1_PCH_CON_RXN<15>")
	)
	(segment
		(start 44.1325 5.5245)
		(end 46.2153 4.3688)
		(width 0.127)
		(layer "B.Cu")
		(net "P3E_CPU0_PE1_PCH_CON_RXN<15>")
	)
	(segment
		(start 36.932362 9.8298)
		(end 37.0586 9.1821)
		(width 0.127)
		(layer "B.Cu")
		(net "P3E_CPU0_PE1_PCH_CON_RXN<15>")
	)
	(segment
		(start 49.747932 -5.138928)
		(end 49.548796 -5.286502)
		(width 0.127)
		(layer "B.Cu")
		(net "P3E_CPU0_PE1_PCH_CON_RXN<15>")
	)
	(arc
		(start 37.05606 10.716514)
		(mid 36.964518 10.579322)
		(end 36.932362 10.417556)
		(width 0.127)
		(layer "B.Cu")
		(net "P3E_CPU0_PE1_PCH_CON_RXN<15>")
	)
	(arc
		(start 48.227234 -11.512296)
		(mid 48.161393 -11.893205)
		(end 48.212756 -12.276328)
		(width 0.127)
		(layer "B.Cu")
		(net "P3E_CPU0_PE1_PCH_CON_RXN<15>")
	)
	(arc
		(start 48.241458 -9.450324)
		(mid 48.238251 -9.935344)
		(end 48.299116 -10.41654)
		(width 0.127)
		(layer "B.Cu")
		(net "P3E_CPU0_PE1_PCH_CON_RXN<15>")
	)
	(arc
		(start 48.212756 -12.276328)
		(mid 48.290868 -12.422334)
		(end 48.420782 -12.524994)
		(width 0.127)
		(layer "B.Cu")
		(net "P3E_CPU0_PE1_PCH_CON_RXN<15>")
	)
	(arc
		(start 49.2506 -7.300214)
		(mid 49.170343 -7.686562)
		(end 48.94199 -8.008366)
		(width 0.127)
		(layer "B.Cu")
		(net "P3E_CPU0_PE1_PCH_CON_RXN<15>")
	)
	(arc
		(start 48.299116 -10.41654)
		(mid 48.334136 -10.969074)
		(end 48.227234 -11.512296)
		(width 0.127)
		(layer "B.Cu")
		(net "P3E_CPU0_PE1_PCH_CON_RXN<15>")
	)
	(arc
		(start 48.94199 -8.008366)
		(mid 48.716029 -8.191928)
		(end 48.544226 -8.426958)
		(width 0.127)
		(layer "B.Cu")
		(net "P3E_CPU0_PE1_PCH_CON_RXN<15>")
	)
	(arc
		(start 37.180012 10.962894)
		(mid 37.157438 10.849585)
		(end 37.093144 10.753598)
		(width 0.127)
		(layer "B.Cu")
		(net "P3E_CPU0_PE1_PCH_CON_RXN<15>")
	)
	(arc
		(start 48.544226 -8.426958)
		(mid 48.337629 -8.922303)
		(end 48.241458 -9.450324)
		(width 0.127)
		(layer "B.Cu")
		(net "P3E_CPU0_PE1_PCH_CON_RXN<15>")
	)
	(arc
		(start 48.534828 -12.58189)
		(mid 48.631884 -12.588831)
		(end 48.705262 -12.524994)
		(width 0.127)
		(layer "B.Cu")
		(net "P3E_CPU0_PE1_PCH_CON_RXN<15>")
	)
	(segment
		(start 53.964078 -13.543788)
		(end 54.079902 -13.750036)
		(width 0.127)
		(layer "B.Cu")
		(net "P3E_CPU0_PE1_PCH_CON_RXN<14>")
	)
	(segment
		(start 39.39032 9.11098)
		(end 39.849298 8.45566)
		(width 0.127)
		(layer "B.Cu")
		(net "P3E_CPU0_PE1_PCH_CON_RXN<14>")
	)
	(segment
		(start 53.2765 -6.666484)
		(end 53.2765 -7.408926)
		(width 0.127)
		(layer "B.Cu")
		(net "P3E_CPU0_PE1_PCH_CON_RXN<14>")
	)
	(segment
		(start 47.2059 5.2578)
		(end 51.9049 -1.6383)
		(width 0.127)
		(layer "B.Cu")
		(net "P3E_CPU0_PE1_PCH_CON_RXN<14>")
	)
	(segment
		(start 53.760878 -12.853924)
		(end 53.760624 -12.853924)
		(width 0.127)
		(layer "B.Cu")
		(net "P3E_CPU0_PE1_PCH_CON_RXN<14>")
	)
	(segment
		(start 44.831 6.8326)
		(end 47.2059 5.2578)
		(width 0.127)
		(layer "B.Cu")
		(net "P3E_CPU0_PE1_PCH_CON_RXN<14>")
	)
	(segment
		(start 39.332408 10.328402)
		(end 39.332408 9.924796)
		(width 0.127)
		(layer "B.Cu")
		(net "P3E_CPU0_PE1_PCH_CON_RXN<14>")
	)
	(segment
		(start 39.849298 8.45566)
		(end 39.849806 8.455152)
		(width 0.127)
		(layer "B.Cu")
		(net "P3E_CPU0_PE1_PCH_CON_RXN<14>")
	)
	(segment
		(start 39.49319 10.66419)
		(end 39.456106 10.627106)
		(width 0.127)
		(layer "B.Cu")
		(net "P3E_CPU0_PE1_PCH_CON_RXN<14>")
	)
	(segment
		(start 39.579804 12.514072)
		(end 39.579804 10.873232)
		(width 0.127)
		(layer "B.Cu")
		(net "P3E_CPU0_PE1_PCH_CON_RXN<14>")
	)
	(segment
		(start 51.933856 -1.680972)
		(end 53.264308 -6.620002)
		(width 0.127)
		(layer "B.Cu")
		(net "P3E_CPU0_PE1_PCH_CON_RXN<14>")
	)
	(segment
		(start 39.941246 8.360664)
		(end 41.9354 7.1755)
		(width 0.127)
		(layer "B.Cu")
		(net "P3E_CPU0_PE1_PCH_CON_RXN<14>")
	)
	(segment
		(start 39.2938 9.658858)
		(end 39.39032 9.11098)
		(width 0.127)
		(layer "B.Cu")
		(net "P3E_CPU0_PE1_PCH_CON_RXN<14>")
	)
	(segment
		(start 39.849806 8.455152)
		(end 39.849806 8.452104)
		(width 0.127)
		(layer "B.Cu")
		(net "P3E_CPU0_PE1_PCH_CON_RXN<14>")
	)
	(segment
		(start 53.703728 -13.024358)
		(end 53.964078 -13.543788)
		(width 0.127)
		(layer "B.Cu")
		(net "P3E_CPU0_PE1_PCH_CON_RXN<14>")
	)
	(segment
		(start 39.849806 8.452104)
		(end 39.941246 8.360664)
		(width 0.127)
		(layer "B.Cu")
		(net "P3E_CPU0_PE1_PCH_CON_RXN<14>")
	)
	(segment
		(start 53.264308 -6.620002)
		(end 53.2765 -6.666484)
		(width 0.127)
		(layer "B.Cu")
		(net "P3E_CPU0_PE1_PCH_CON_RXN<14>")
	)
	(segment
		(start 41.9354 7.1755)
		(end 44.831 6.8326)
		(width 0.127)
		(layer "B.Cu")
		(net "P3E_CPU0_PE1_PCH_CON_RXN<14>")
	)
	(segment
		(start 53.874162 -12.797536)
		(end 53.762148 -12.853416)
		(width 0.127)
		(layer "B.Cu")
		(net "P3E_CPU0_PE1_PCH_CON_RXN<14>")
	)
	(segment
		(start 39.32428 9.831578)
		(end 39.2938 9.658858)
		(width 0.127)
		(layer "B.Cu")
		(net "P3E_CPU0_PE1_PCH_CON_RXN<14>")
	)
	(segment
		(start 51.9049 -1.6383)
		(end 51.933856 -1.680972)
		(width 0.127)
		(layer "B.Cu")
		(net "P3E_CPU0_PE1_PCH_CON_RXN<14>")
	)
	(segment
		(start 53.762148 -12.853416)
		(end 53.760878 -12.853924)
		(width 0.127)
		(layer "B.Cu")
		(net "P3E_CPU0_PE1_PCH_CON_RXN<14>")
	)
	(arc
		(start 39.332408 9.924796)
		(mid 39.330387 9.878009)
		(end 39.32428 9.831578)
		(width 0.127)
		(layer "B.Cu")
		(net "P3E_CPU0_PE1_PCH_CON_RXN<14>")
	)
	(arc
		(start 39.456106 10.627106)
		(mid 39.364534 10.490059)
		(end 39.332408 10.328402)
		(width 0.127)
		(layer "B.Cu")
		(net "P3E_CPU0_PE1_PCH_CON_RXN<14>")
	)
	(arc
		(start 53.612034 -8.218932)
		(mid 53.996728 -8.588757)
		(end 54.190138 -9.086088)
		(width 0.127)
		(layer "B.Cu")
		(net "P3E_CPU0_PE1_PCH_CON_RXN<14>")
	)
	(arc
		(start 54.318662 -11.955526)
		(mid 54.231659 -12.447957)
		(end 53.874162 -12.797536)
		(width 0.127)
		(layer "B.Cu")
		(net "P3E_CPU0_PE1_PCH_CON_RXN<14>")
	)
	(arc
		(start 54.190138 -9.086088)
		(mid 54.292666 -10.100656)
		(end 54.286658 -11.120374)
		(width 0.127)
		(layer "B.Cu")
		(net "P3E_CPU0_PE1_PCH_CON_RXN<14>")
	)
	(arc
		(start 53.760624 -12.853924)
		(mid 53.696861 -12.927377)
		(end 53.703728 -13.024358)
		(width 0.127)
		(layer "B.Cu")
		(net "P3E_CPU0_PE1_PCH_CON_RXN<14>")
	)
	(arc
		(start 53.2765 -7.408926)
		(mid 53.363699 -7.847305)
		(end 53.612034 -8.218932)
		(width 0.127)
		(layer "B.Cu")
		(net "P3E_CPU0_PE1_PCH_CON_RXN<14>")
	)
	(arc
		(start 54.286658 -11.120374)
		(mid 54.28219 -11.538735)
		(end 54.318662 -11.955526)
		(width 0.127)
		(layer "B.Cu")
		(net "P3E_CPU0_PE1_PCH_CON_RXN<14>")
	)
	(arc
		(start 39.579804 10.873232)
		(mid 39.557299 10.760089)
		(end 39.49319 10.66419)
		(width 0.127)
		(layer "B.Cu")
		(net "P3E_CPU0_PE1_PCH_CON_RXN<14>")
	)
	(segment
		(start 46.532292 10.365486)
		(end 46.532292 9.375394)
		(width 0.127)
		(layer "B.Cu")
		(net "P3E_CPU0_PE1_PCH_CON_RXN<13>")
	)
	(segment
		(start 57.873392 -12.797536)
		(end 57.761378 -12.853416)
		(width 0.127)
		(layer "B.Cu")
		(net "P3E_CPU0_PE1_PCH_CON_RXN<13>")
	)
	(segment
		(start 57.204356 -7.329424)
		(end 57.204102 -7.329678)
		(width 0.127)
		(layer "B.Cu")
		(net "P3E_CPU0_PE1_PCH_CON_RXN<13>")
	)
	(segment
		(start 57.20461 -7.329678)
		(end 57.204356 -7.329932)
		(width 0.127)
		(layer "B.Cu")
		(net "P3E_CPU0_PE1_PCH_CON_RXN<13>")
	)
	(segment
		(start 57.214262 -7.202424)
		(end 57.214008 -7.202424)
		(width 0.127)
		(layer "B.Cu")
		(net "P3E_CPU0_PE1_PCH_CON_RXN<13>")
	)
	(segment
		(start 57.907936 -13.432028)
		(end 58.080402 -13.750036)
		(width 0.127)
		(layer "B.Cu")
		(net "P3E_CPU0_PE1_PCH_CON_RXN<13>")
	)
	(segment
		(start 57.761378 -12.853416)
		(end 57.760108 -12.853924)
		(width 0.127)
		(layer "B.Cu")
		(net "P3E_CPU0_PE1_PCH_CON_RXN<13>")
	)
	(segment
		(start 46.779942 12.514072)
		(end 46.779942 10.963148)
		(width 0.127)
		(layer "B.Cu")
		(net "P3E_CPU0_PE1_PCH_CON_RXN<13>")
	)
	(segment
		(start 57.204102 -7.329678)
		(end 57.20461 -7.329678)
		(width 0.127)
		(layer "B.Cu")
		(net "P3E_CPU0_PE1_PCH_CON_RXN<13>")
	)
	(segment
		(start 57.214008 -7.202424)
		(end 57.204356 -7.329424)
		(width 0.127)
		(layer "B.Cu")
		(net "P3E_CPU0_PE1_PCH_CON_RXN<13>")
	)
	(segment
		(start 57.217056 -7.163816)
		(end 57.214262 -7.202424)
		(width 0.127)
		(layer "B.Cu")
		(net "P3E_CPU0_PE1_PCH_CON_RXN<13>")
	)
	(segment
		(start 57.112408 -6.571996)
		(end 57.217056 -7.163816)
		(width 0.127)
		(layer "B.Cu")
		(net "P3E_CPU0_PE1_PCH_CON_RXN<13>")
	)
	(segment
		(start 55.4101 -3.3909)
		(end 55.4228 -3.408172)
		(width 0.127)
		(layer "B.Cu")
		(net "P3E_CPU0_PE1_PCH_CON_RXN<13>")
	)
	(segment
		(start 55.4228 -3.408172)
		(end 57.112408 -6.571996)
		(width 0.127)
		(layer "B.Cu")
		(net "P3E_CPU0_PE1_PCH_CON_RXN<13>")
	)
	(segment
		(start 46.532292 9.375394)
		(end 46.7233 8.4836)
		(width 0.127)
		(layer "B.Cu")
		(net "P3E_CPU0_PE1_PCH_CON_RXN<13>")
	)
	(segment
		(start 46.7233 8.4836)
		(end 55.4101 -3.3909)
		(width 0.127)
		(layer "B.Cu")
		(net "P3E_CPU0_PE1_PCH_CON_RXN<13>")
	)
	(segment
		(start 57.760108 -12.853924)
		(end 57.759854 -12.853924)
		(width 0.127)
		(layer "B.Cu")
		(net "P3E_CPU0_PE1_PCH_CON_RXN<13>")
	)
	(segment
		(start 57.702958 -13.024358)
		(end 57.907936 -13.432028)
		(width 0.127)
		(layer "B.Cu")
		(net "P3E_CPU0_PE1_PCH_CON_RXN<13>")
	)
	(arc
		(start 57.611264 -8.218932)
		(mid 57.995958 -8.588757)
		(end 58.189368 -9.086088)
		(width 0.127)
		(layer "B.Cu")
		(net "P3E_CPU0_PE1_PCH_CON_RXN<13>")
	)
	(arc
		(start 57.204356 -7.329932)
		(mid 57.202776 -7.339702)
		(end 57.201308 -7.34949)
		(width 0.127)
		(layer "B.Cu")
		(net "P3E_CPU0_PE1_PCH_CON_RXN<13>")
	)
	(arc
		(start 57.759854 -12.853924)
		(mid 57.696091 -12.927377)
		(end 57.702958 -13.024358)
		(width 0.127)
		(layer "B.Cu")
		(net "P3E_CPU0_PE1_PCH_CON_RXN<13>")
	)
	(arc
		(start 58.189368 -9.086088)
		(mid 58.291896 -10.100656)
		(end 58.285888 -11.120374)
		(width 0.127)
		(layer "B.Cu")
		(net "P3E_CPU0_PE1_PCH_CON_RXN<13>")
	)
	(arc
		(start 46.779942 10.963148)
		(mid 46.747789 10.801502)
		(end 46.656244 10.664444)
		(width 0.127)
		(layer "B.Cu")
		(net "P3E_CPU0_PE1_PCH_CON_RXN<13>")
	)
	(arc
		(start 57.201308 -7.34949)
		(mid 57.276188 -7.845548)
		(end 57.611264 -8.218932)
		(width 0.127)
		(layer "B.Cu")
		(net "P3E_CPU0_PE1_PCH_CON_RXN<13>")
	)
	(arc
		(start 46.656244 10.664444)
		(mid 46.564487 10.527309)
		(end 46.532292 10.365486)
		(width 0.127)
		(layer "B.Cu")
		(net "P3E_CPU0_PE1_PCH_CON_RXN<13>")
	)
	(arc
		(start 58.285888 -11.120374)
		(mid 58.28142 -11.538735)
		(end 58.317892 -11.955526)
		(width 0.127)
		(layer "B.Cu")
		(net "P3E_CPU0_PE1_PCH_CON_RXN<13>")
	)
	(arc
		(start 58.317892 -11.955526)
		(mid 58.230889 -12.447957)
		(end 57.873392 -12.797536)
		(width 0.127)
		(layer "B.Cu")
		(net "P3E_CPU0_PE1_PCH_CON_RXN<13>")
	)
	(segment
		(start 61.703458 -13.024358)
		(end 62.079632 -13.750036)
		(width 0.127)
		(layer "B.Cu")
		(net "P3E_CPU0_PE1_PCH_CON_RXN<12>")
	)
	(segment
		(start 61.761878 -12.853416)
		(end 61.760608 -12.853924)
		(width 0.127)
		(layer "B.Cu")
		(net "P3E_CPU0_PE1_PCH_CON_RXN<12>")
	)
	(segment
		(start 49.179988 12.514072)
		(end 49.179988 11.052048)
		(width 0.127)
		(layer "B.Cu")
		(net "P3E_CPU0_PE1_PCH_CON_RXN<12>")
	)
	(segment
		(start 48.885348 9.572752)
		(end 48.883062 9.570466)
		(width 0.127)
		(layer "B.Cu")
		(net "P3E_CPU0_PE1_PCH_CON_RXN<12>")
	)
	(segment
		(start 61.873892 -12.797536)
		(end 61.761878 -12.853416)
		(width 0.127)
		(layer "B.Cu")
		(net "P3E_CPU0_PE1_PCH_CON_RXN<12>")
	)
	(segment
		(start 48.883062 9.570466)
		(end 48.883062 9.440926)
		(width 0.127)
		(layer "B.Cu")
		(net "P3E_CPU0_PE1_PCH_CON_RXN<12>")
	)
	(segment
		(start 48.883062 9.440926)
		(end 49.144936 7.954772)
		(width 0.127)
		(layer "B.Cu")
		(net "P3E_CPU0_PE1_PCH_CON_RXN<12>")
	)
	(segment
		(start 61.1378 -6.269482)
		(end 61.262768 -6.977888)
		(width 0.127)
		(layer "B.Cu")
		(net "P3E_CPU0_PE1_PCH_CON_RXN<12>")
	)
	(segment
		(start 48.932338 10.454132)
		(end 48.932592 10.453878)
		(width 0.127)
		(layer "B.Cu")
		(net "P3E_CPU0_PE1_PCH_CON_RXN<12>")
	)
	(segment
		(start 48.932084 10.453624)
		(end 48.964596 10.02284)
		(width 0.127)
		(layer "B.Cu")
		(net "P3E_CPU0_PE1_PCH_CON_RXN<12>")
	)
	(segment
		(start 61.760608 -12.853924)
		(end 61.760354 -12.853924)
		(width 0.127)
		(layer "B.Cu")
		(net "P3E_CPU0_PE1_PCH_CON_RXN<12>")
	)
	(segment
		(start 48.964596 10.02284)
		(end 48.885348 9.573006)
		(width 0.127)
		(layer "B.Cu")
		(net "P3E_CPU0_PE1_PCH_CON_RXN<12>")
	)
	(segment
		(start 48.932592 10.453878)
		(end 48.93183 10.453878)
		(width 0.127)
		(layer "B.Cu")
		(net "P3E_CPU0_PE1_PCH_CON_RXN<12>")
	)
	(segment
		(start 48.93183 10.453878)
		(end 48.932084 10.453624)
		(width 0.127)
		(layer "B.Cu")
		(net "P3E_CPU0_PE1_PCH_CON_RXN<12>")
	)
	(segment
		(start 56.224932 -2.15646)
		(end 60.212732 -4.948428)
		(width 0.127)
		(layer "B.Cu")
		(net "P3E_CPU0_PE1_PCH_CON_RXN<12>")
	)
	(segment
		(start 60.212732 -4.948428)
		(end 61.1378 -6.269482)
		(width 0.127)
		(layer "B.Cu")
		(net "P3E_CPU0_PE1_PCH_CON_RXN<12>")
	)
	(segment
		(start 48.885348 9.573006)
		(end 48.885348 9.572752)
		(width 0.127)
		(layer "B.Cu")
		(net "P3E_CPU0_PE1_PCH_CON_RXN<12>")
	)
	(segment
		(start 49.144936 7.954772)
		(end 56.224932 -2.15646)
		(width 0.127)
		(layer "B.Cu")
		(net "P3E_CPU0_PE1_PCH_CON_RXN<12>")
	)
	(segment
		(start 61.262768 -6.977888)
		(end 61.204856 -7.330186)
		(width 0.127)
		(layer "B.Cu")
		(net "P3E_CPU0_PE1_PCH_CON_RXN<12>")
	)
	(arc
		(start 49.179988 11.052048)
		(mid 49.147777 10.89011)
		(end 49.056036 10.752836)
		(width 0.127)
		(layer "B.Cu")
		(net "P3E_CPU0_PE1_PCH_CON_RXN<12>")
	)
	(arc
		(start 62.286388 -11.120374)
		(mid 62.28192 -11.538735)
		(end 62.318392 -11.955526)
		(width 0.127)
		(layer "B.Cu")
		(net "P3E_CPU0_PE1_PCH_CON_RXN<12>")
	)
	(arc
		(start 62.189868 -9.086088)
		(mid 62.292396 -10.100656)
		(end 62.286388 -11.120374)
		(width 0.127)
		(layer "B.Cu")
		(net "P3E_CPU0_PE1_PCH_CON_RXN<12>")
	)
	(arc
		(start 61.204856 -7.330186)
		(mid 61.272638 -7.836675)
		(end 61.611764 -8.218932)
		(width 0.127)
		(layer "B.Cu")
		(net "P3E_CPU0_PE1_PCH_CON_RXN<12>")
	)
	(arc
		(start 61.760354 -12.853924)
		(mid 61.696591 -12.927377)
		(end 61.703458 -13.024358)
		(width 0.127)
		(layer "B.Cu")
		(net "P3E_CPU0_PE1_PCH_CON_RXN<12>")
	)
	(arc
		(start 62.318392 -11.955526)
		(mid 62.231389 -12.447957)
		(end 61.873892 -12.797536)
		(width 0.127)
		(layer "B.Cu")
		(net "P3E_CPU0_PE1_PCH_CON_RXN<12>")
	)
	(arc
		(start 49.056036 10.752836)
		(mid 48.964464 10.615789)
		(end 48.932338 10.454132)
		(width 0.127)
		(layer "B.Cu")
		(net "P3E_CPU0_PE1_PCH_CON_RXN<12>")
	)
	(arc
		(start 61.611764 -8.218932)
		(mid 61.996458 -8.588757)
		(end 62.189868 -9.086088)
		(width 0.127)
		(layer "B.Cu")
		(net "P3E_CPU0_PE1_PCH_CON_RXN<12>")
	)
	(segment
		(start 53.658008 4.915154)
		(end 56.027574 1.530858)
		(width 0.127)
		(layer "B.Cu")
		(net "P3E_CPU0_PE1_PCH_CON_RXN<11>")
	)
	(segment
		(start 51.470814 8.04164)
		(end 53.6575 4.91871)
		(width 0.127)
		(layer "B.Cu")
		(net "P3E_CPU0_PE1_PCH_CON_RXN<11>")
	)
	(segment
		(start 67.103498 -6.570218)
		(end 67.2592 -7.453376)
		(width 0.127)
		(layer "B.Cu")
		(net "P3E_CPU0_PE1_PCH_CON_RXN<11>")
	)
	(segment
		(start 56.027574 1.530858)
		(end 66.628772 -5.892292)
		(width 0.127)
		(layer "B.Cu")
		(net "P3E_CPU0_PE1_PCH_CON_RXN<11>")
	)
	(segment
		(start 51.331876 10.440924)
		(end 51.33213 10.44067)
		(width 0.127)
		(layer "B.Cu")
		(net "P3E_CPU0_PE1_PCH_CON_RXN<11>")
	)
	(segment
		(start 67.873372 -12.797536)
		(end 67.761358 -12.853416)
		(width 0.127)
		(layer "B.Cu")
		(net "P3E_CPU0_PE1_PCH_CON_RXN<11>")
	)
	(segment
		(start 51.244246 9.327134)
		(end 51.470814 8.04164)
		(width 0.127)
		(layer "B.Cu")
		(net "P3E_CPU0_PE1_PCH_CON_RXN<11>")
	)
	(segment
		(start 67.5386 -8.128)
		(end 67.971924 -8.561578)
		(width 0.127)
		(layer "B.Cu")
		(net "P3E_CPU0_PE1_PCH_CON_RXN<11>")
	)
	(segment
		(start 53.6575 4.91871)
		(end 53.658008 4.918202)
		(width 0.127)
		(layer "B.Cu")
		(net "P3E_CPU0_PE1_PCH_CON_RXN<11>")
	)
	(segment
		(start 67.702938 -13.024358)
		(end 67.972432 -13.560044)
		(width 0.127)
		(layer "B.Cu")
		(net "P3E_CPU0_PE1_PCH_CON_RXN<11>")
	)
	(segment
		(start 51.57978 12.514072)
		(end 51.57978 11.038586)
		(width 0.127)
		(layer "B.Cu")
		(net "P3E_CPU0_PE1_PCH_CON_RXN<11>")
	)
	(segment
		(start 53.658008 4.918202)
		(end 53.658008 4.915154)
		(width 0.127)
		(layer "B.Cu")
		(net "P3E_CPU0_PE1_PCH_CON_RXN<11>")
	)
	(segment
		(start 67.972432 -13.560044)
		(end 68.080382 -13.750036)
		(width 0.127)
		(layer "B.Cu")
		(net "P3E_CPU0_PE1_PCH_CON_RXN<11>")
	)
	(segment
		(start 51.33213 10.44067)
		(end 51.364642 10.009886)
		(width 0.127)
		(layer "B.Cu")
		(net "P3E_CPU0_PE1_PCH_CON_RXN<11>")
	)
	(segment
		(start 67.761358 -12.853416)
		(end 67.760088 -12.853924)
		(width 0.127)
		(layer "B.Cu")
		(net "P3E_CPU0_PE1_PCH_CON_RXN<11>")
	)
	(segment
		(start 66.628772 -5.892292)
		(end 67.103498 -6.570218)
		(width 0.127)
		(layer "B.Cu")
		(net "P3E_CPU0_PE1_PCH_CON_RXN<11>")
	)
	(segment
		(start 67.760088 -12.853924)
		(end 67.759834 -12.853924)
		(width 0.127)
		(layer "B.Cu")
		(net "P3E_CPU0_PE1_PCH_CON_RXN<11>")
	)
	(segment
		(start 51.364642 10.009886)
		(end 51.244246 9.327134)
		(width 0.127)
		(layer "B.Cu")
		(net "P3E_CPU0_PE1_PCH_CON_RXN<11>")
	)
	(segment
		(start 51.332638 10.440924)
		(end 51.331876 10.440924)
		(width 0.127)
		(layer "B.Cu")
		(net "P3E_CPU0_PE1_PCH_CON_RXN<11>")
	)
	(segment
		(start 51.332384 10.441178)
		(end 51.332638 10.440924)
		(width 0.127)
		(layer "B.Cu")
		(net "P3E_CPU0_PE1_PCH_CON_RXN<11>")
	)
	(arc
		(start 67.759834 -12.853924)
		(mid 67.696071 -12.927377)
		(end 67.702938 -13.024358)
		(width 0.127)
		(layer "B.Cu")
		(net "P3E_CPU0_PE1_PCH_CON_RXN<11>")
	)
	(arc
		(start 68.285868 -11.120374)
		(mid 68.2814 -11.538735)
		(end 68.317872 -11.955526)
		(width 0.127)
		(layer "B.Cu")
		(net "P3E_CPU0_PE1_PCH_CON_RXN<11>")
	)
	(arc
		(start 51.456082 10.739882)
		(mid 51.36451 10.602835)
		(end 51.332384 10.441178)
		(width 0.127)
		(layer "B.Cu")
		(net "P3E_CPU0_PE1_PCH_CON_RXN<11>")
	)
	(arc
		(start 67.2592 -7.453376)
		(mid 67.331821 -7.818465)
		(end 67.5386 -8.128)
		(width 0.127)
		(layer "B.Cu")
		(net "P3E_CPU0_PE1_PCH_CON_RXN<11>")
	)
	(arc
		(start 68.189348 -9.086088)
		(mid 68.291876 -10.100656)
		(end 68.285868 -11.120374)
		(width 0.127)
		(layer "B.Cu")
		(net "P3E_CPU0_PE1_PCH_CON_RXN<11>")
	)
	(arc
		(start 51.57978 11.038586)
		(mid 51.547627 10.87694)
		(end 51.456082 10.739882)
		(width 0.127)
		(layer "B.Cu")
		(net "P3E_CPU0_PE1_PCH_CON_RXN<11>")
	)
	(arc
		(start 68.317872 -11.955526)
		(mid 68.230869 -12.447957)
		(end 67.873372 -12.797536)
		(width 0.127)
		(layer "B.Cu")
		(net "P3E_CPU0_PE1_PCH_CON_RXN<11>")
	)
	(arc
		(start 67.971924 -8.561578)
		(mid 68.132802 -8.80221)
		(end 68.189348 -9.086088)
		(width 0.127)
		(layer "B.Cu")
		(net "P3E_CPU0_PE1_PCH_CON_RXN<11>")
	)
	(segment
		(start 71.761858 -12.853416)
		(end 71.760588 -12.853924)
		(width 0.127)
		(layer "B.Cu")
		(net "P3E_CPU0_PE1_PCH_CON_RXN<10>")
	)
	(segment
		(start 53.612034 9.753346)
		(end 53.7464 8.9916)
		(width 0.127)
		(layer "B.Cu")
		(net "P3E_CPU0_PE1_PCH_CON_RXN<10>")
	)
	(segment
		(start 53.979826 12.514072)
		(end 53.979826 11.025632)
		(width 0.127)
		(layer "B.Cu")
		(net "P3E_CPU0_PE1_PCH_CON_RXN<10>")
	)
	(segment
		(start 71.873872 -12.797536)
		(end 71.761858 -12.853416)
		(width 0.127)
		(layer "B.Cu")
		(net "P3E_CPU0_PE1_PCH_CON_RXN<10>")
	)
	(segment
		(start 53.729636 10.426446)
		(end 53.729128 10.42416)
		(width 0.127)
		(layer "B.Cu")
		(net "P3E_CPU0_PE1_PCH_CON_RXN<10>")
	)
	(segment
		(start 71.2597 -6.60273)
		(end 71.2597 -7.453376)
		(width 0.127)
		(layer "B.Cu")
		(net "P3E_CPU0_PE1_PCH_CON_RXN<10>")
	)
	(segment
		(start 71.5391 -8.128)
		(end 71.972424 -8.561578)
		(width 0.127)
		(layer "B.Cu")
		(net "P3E_CPU0_PE1_PCH_CON_RXN<10>")
	)
	(segment
		(start 53.7464 8.9916)
		(end 57.041796 4.285234)
		(width 0.127)
		(layer "B.Cu")
		(net "P3E_CPU0_PE1_PCH_CON_RXN<10>")
	)
	(segment
		(start 71.129652 -5.906516)
		(end 71.169784 -6.09219)
		(width 0.127)
		(layer "B.Cu")
		(net "P3E_CPU0_PE1_PCH_CON_RXN<10>")
	)
	(segment
		(start 57.041796 4.285234)
		(end 70.680326 -5.264912)
		(width 0.127)
		(layer "B.Cu")
		(net "P3E_CPU0_PE1_PCH_CON_RXN<10>")
	)
	(segment
		(start 71.703438 -13.024358)
		(end 72.079612 -13.750036)
		(width 0.127)
		(layer "B.Cu")
		(net "P3E_CPU0_PE1_PCH_CON_RXN<10>")
	)
	(segment
		(start 53.73243 10.428224)
		(end 53.729636 10.426446)
		(width 0.127)
		(layer "B.Cu")
		(net "P3E_CPU0_PE1_PCH_CON_RXN<10>")
	)
	(segment
		(start 71.760588 -12.853924)
		(end 71.760334 -12.853924)
		(width 0.127)
		(layer "B.Cu")
		(net "P3E_CPU0_PE1_PCH_CON_RXN<10>")
	)
	(segment
		(start 70.680326 -5.264912)
		(end 71.129652 -5.906516)
		(width 0.127)
		(layer "B.Cu")
		(net "P3E_CPU0_PE1_PCH_CON_RXN<10>")
	)
	(segment
		(start 53.729128 10.42416)
		(end 53.612034 9.753346)
		(width 0.127)
		(layer "B.Cu")
		(net "P3E_CPU0_PE1_PCH_CON_RXN<10>")
	)
	(segment
		(start 71.169784 -6.09219)
		(end 71.2597 -6.60273)
		(width 0.127)
		(layer "B.Cu")
		(net "P3E_CPU0_PE1_PCH_CON_RXN<10>")
	)
	(arc
		(start 71.760334 -12.853924)
		(mid 71.696571 -12.927377)
		(end 71.703438 -13.024358)
		(width 0.127)
		(layer "B.Cu")
		(net "P3E_CPU0_PE1_PCH_CON_RXN<10>")
	)
	(arc
		(start 71.2597 -7.453376)
		(mid 71.332321 -7.818465)
		(end 71.5391 -8.128)
		(width 0.127)
		(layer "B.Cu")
		(net "P3E_CPU0_PE1_PCH_CON_RXN<10>")
	)
	(arc
		(start 72.286368 -11.120374)
		(mid 72.2819 -11.538735)
		(end 72.318372 -11.955526)
		(width 0.127)
		(layer "B.Cu")
		(net "P3E_CPU0_PE1_PCH_CON_RXN<10>")
	)
	(arc
		(start 71.972424 -8.561578)
		(mid 72.133302 -8.80221)
		(end 72.189848 -9.086088)
		(width 0.127)
		(layer "B.Cu")
		(net "P3E_CPU0_PE1_PCH_CON_RXN<10>")
	)
	(arc
		(start 53.979826 11.025632)
		(mid 53.947673 10.863986)
		(end 53.856128 10.726928)
		(width 0.127)
		(layer "B.Cu")
		(net "P3E_CPU0_PE1_PCH_CON_RXN<10>")
	)
	(arc
		(start 72.318372 -11.955526)
		(mid 72.231369 -12.447957)
		(end 71.873872 -12.797536)
		(width 0.127)
		(layer "B.Cu")
		(net "P3E_CPU0_PE1_PCH_CON_RXN<10>")
	)
	(arc
		(start 53.856128 10.726928)
		(mid 53.764556 10.589881)
		(end 53.73243 10.428224)
		(width 0.127)
		(layer "B.Cu")
		(net "P3E_CPU0_PE1_PCH_CON_RXN<10>")
	)
	(arc
		(start 72.189848 -9.086088)
		(mid 72.292376 -10.100656)
		(end 72.286368 -11.120374)
		(width 0.127)
		(layer "B.Cu")
		(net "P3E_CPU0_PE1_PCH_CON_RXN<10>")
	)
	(via
		(at 14.8336 -6.6548)
		(size 0.7112)
		(drill 0.3556)
		(layers "F.Cu" "B.Cu")
		(net "AGND_P3V3")
	)
	(segment
		(start 15.8115 -7.4803)
		(end 15.8115 -8.4963)
		(width 0.254)
		(layer "B.Cu")
		(net "AGND_P3V3")
	)
	(segment
		(start 16.256 -6.5024)
		(end 14.986 -6.5024)
		(width 0.254)
		(layer "B.Cu")
		(net "AGND_P3V3")
	)
	(segment
		(start 14.8336 -6.8072)
		(end 15.5067 -7.4803)
		(width 0.254)
		(layer "B.Cu")
		(net "AGND_P3V3")
	)
	(segment
		(start 15.8115 -8.4963)
		(end 15.7861 -8.5217)
		(width 0.254)
		(layer "B.Cu")
		(net "AGND_P3V3")
	)
	(segment
		(start 18.942304 -8.579104)
		(end 19.945604 -8.579104)
		(width 0.254)
		(layer "B.Cu")
		(net "AGND_P3V3")
	)
	(segment
		(start 15.7861 -8.5217)
		(end 15.7861 -9.4742)
		(width 0.254)
		(layer "B.Cu")
		(net "AGND_P3V3")
	)
	(segment
		(start 19.945604 -8.579104)
		(end 20.971002 -8.579104)
		(width 0.2032)
		(layer "B.Cu")
		(net "AGND_P3V3")
	)
	(segment
		(start 15.7861 -9.4742)
		(end 15.6972 -9.5631)
		(width 0.254)
		(layer "B.Cu")
		(net "AGND_P3V3")
	)
	(segment
		(start 15.5067 -7.4803)
		(end 15.8115 -7.4803)
		(width 0.254)
		(layer "B.Cu")
		(net "AGND_P3V3")
	)
	(segment
		(start 16.256 -6.5024)
		(end 16.8656 -6.5024)
		(width 0.254)
		(layer "B.Cu")
		(net "AGND_P3V3")
	)
	(segment
		(start 14.8336 -6.6548)
		(end 14.8336 -6.8072)
		(width 0.254)
		(layer "B.Cu")
		(net "AGND_P3V3")
	)
	(segment
		(start 16.8656 -6.5024)
		(end 18.942304 -8.579104)
		(width 0.254)
		(layer "B.Cu")
		(net "AGND_P3V3")
	)
	(segment
		(start 14.986 -6.5024)
		(end 14.8336 -6.6548)
		(width 0.254)
		(layer "B.Cu")
		(net "AGND_P3V3")
	)
	(segment
		(start 134.613904 -20.326096)
		(end 133.26745 -21.67255)
		(width 0.1143)
		(layer "F.Cu")
		(net "USB2_P02_DP")
	)
	(segment
		(start 134.613904 -2.717546)
		(end 134.613904 -20.326096)
		(width 0.1143)
		(layer "F.Cu")
		(net "USB2_P02_DP")
	)
	(segment
		(start 127.94107 -27.616404)
		(end 127.11938 -27.616404)
		(width 0.1143)
		(layer "F.Cu")
		(net "USB2_P02_DP")
	)
	(segment
		(start 131.92125 10.534396)
		(end 131.92125 4.382008)
		(width 0.1143)
		(layer "F.Cu")
		(net "USB2_P02_DP")
	)
	(segment
		(start 132.174996 12.234672)
		(end 132.174996 10.788142)
		(width 0.1143)
		(layer "F.Cu")
		(net "USB2_P02_DP")
	)
	(segment
		(start 133.26745 -21.67255)
		(end 133.26745 -26.24455)
		(width 0.1143)
		(layer "F.Cu")
		(net "USB2_P02_DP")
	)
	(segment
		(start 128.044956 -27.512518)
		(end 127.94107 -27.616404)
		(width 0.1143)
		(layer "F.Cu")
		(net "USB2_P02_DP")
	)
	(segment
		(start 131.92125 4.382008)
		(end 132.25145 4.051808)
		(width 0.1143)
		(layer "F.Cu")
		(net "USB2_P02_DP")
	)
	(segment
		(start 133.26745 -26.24455)
		(end 131.999482 -27.512518)
		(width 0.1143)
		(layer "F.Cu")
		(net "USB2_P02_DP")
	)
	(segment
		(start 132.174996 10.788142)
		(end 131.92125 10.534396)
		(width 0.1143)
		(layer "F.Cu")
		(net "USB2_P02_DP")
	)
	(segment
		(start 131.999482 -27.512518)
		(end 128.044956 -27.512518)
		(width 0.1143)
		(layer "F.Cu")
		(net "USB2_P02_DP")
	)
	(segment
		(start 132.25145 -0.355092)
		(end 134.613904 -2.717546)
		(width 0.1143)
		(layer "F.Cu")
		(net "USB2_P02_DP")
	)
	(segment
		(start 132.25145 4.051808)
		(end 132.25145 -0.355092)
		(width 0.1143)
		(layer "F.Cu")
		(net "USB2_P02_DP")
	)
	(segment
		(start 131.45389 10.016236)
		(end 131.45389 9.673336)
		(width 0.1143)
		(layer "F.Cu")
		(net "USB2_P02_DN")
	)
	(segment
		(start 131.62915 10.534396)
		(end 131.62915 10.191496)
		(width 0.1143)
		(layer "F.Cu")
		(net "USB2_P02_DN")
	)
	(segment
		(start 131.62915 8.461756)
		(end 131.62915 8.118856)
		(width 0.1143)
		(layer "F.Cu")
		(net "USB2_P02_DN")
	)
	(segment
		(start 128.044956 -27.220418)
		(end 127.94107 -27.116532)
		(width 0.1143)
		(layer "F.Cu")
		(net "USB2_P02_DN")
	)
	(segment
		(start 131.62915 4.26085)
		(end 131.95935 3.93065)
		(width 0.1143)
		(layer "F.Cu")
		(net "USB2_P02_DN")
	)
	(segment
		(start 131.878324 -27.220418)
		(end 128.044956 -27.220418)
		(width 0.1143)
		(layer "F.Cu")
		(net "USB2_P02_DN")
	)
	(segment
		(start 131.45389 8.637016)
		(end 131.62915 8.461756)
		(width 0.1143)
		(layer "F.Cu")
		(net "USB2_P02_DN")
	)
	(segment
		(start 131.62915 8.118856)
		(end 131.45389 7.943596)
		(width 0.1143)
		(layer "F.Cu")
		(net "USB2_P02_DN")
	)
	(segment
		(start 132.97535 -26.123392)
		(end 131.878324 -27.220418)
		(width 0.1143)
		(layer "F.Cu")
		(net "USB2_P02_DN")
	)
	(segment
		(start 131.95935 3.93065)
		(end 131.95935 -0.47625)
		(width 0.1143)
		(layer "F.Cu")
		(net "USB2_P02_DN")
	)
	(segment
		(start 127.94107 -27.116532)
		(end 127.11938 -27.116532)
		(width 0.1143)
		(layer "F.Cu")
		(net "USB2_P02_DN")
	)
	(segment
		(start 131.45389 7.600696)
		(end 131.62915 7.425436)
		(width 0.1143)
		(layer "F.Cu")
		(net "USB2_P02_DN")
	)
	(segment
		(start 131.62915 7.425436)
		(end 131.62915 4.26085)
		(width 0.1143)
		(layer "F.Cu")
		(net "USB2_P02_DN")
	)
	(segment
		(start 131.45389 7.943596)
		(end 131.45389 7.600696)
		(width 0.1143)
		(layer "F.Cu")
		(net "USB2_P02_DN")
	)
	(segment
		(start 134.321804 -2.838704)
		(end 134.321804 -20.204938)
		(width 0.1143)
		(layer "F.Cu")
		(net "USB2_P02_DN")
	)
	(segment
		(start 131.45389 8.979916)
		(end 131.45389 8.637016)
		(width 0.1143)
		(layer "F.Cu")
		(net "USB2_P02_DN")
	)
	(segment
		(start 131.62915 10.191496)
		(end 131.45389 10.016236)
		(width 0.1143)
		(layer "F.Cu")
		(net "USB2_P02_DN")
	)
	(segment
		(start 131.95935 -0.47625)
		(end 134.321804 -2.838704)
		(width 0.1143)
		(layer "F.Cu")
		(net "USB2_P02_DN")
	)
	(segment
		(start 134.321804 -20.204938)
		(end 132.97535 -21.551392)
		(width 0.1143)
		(layer "F.Cu")
		(net "USB2_P02_DN")
	)
	(segment
		(start 131.62915 9.498076)
		(end 131.62915 9.155176)
		(width 0.1143)
		(layer "F.Cu")
		(net "USB2_P02_DN")
	)
	(segment
		(start 131.62915 9.155176)
		(end 131.45389 8.979916)
		(width 0.1143)
		(layer "F.Cu")
		(net "USB2_P02_DN")
	)
	(segment
		(start 131.37515 10.788396)
		(end 131.62915 10.534396)
		(width 0.1143)
		(layer "F.Cu")
		(net "USB2_P02_DN")
	)
	(segment
		(start 131.45389 9.673336)
		(end 131.62915 9.498076)
		(width 0.1143)
		(layer "F.Cu")
		(net "USB2_P02_DN")
	)
	(segment
		(start 131.37515 12.234672)
		(end 131.37515 10.788396)
		(width 0.1143)
		(layer "F.Cu")
		(net "USB2_P02_DN")
	)
	(segment
		(start 132.97535 -21.551392)
		(end 132.97535 -26.123392)
		(width 0.1143)
		(layer "F.Cu")
		(net "USB2_P02_DN")
	)
	(segment
		(start 20.7772 8.3693)
		(end 21.17979 8.77189)
		(width 0.1016)
		(layer "F.Cu")
		(net "SMB_SLOTX24_STBY_LVC3_SDA_R2")
	)
	(segment
		(start 105.7783 4.3434)
		(end 105.7783 5.1943)
		(width 0.1016)
		(layer "F.Cu")
		(net "SMB_SLOTX24_STBY_LVC3_SDA_R2")
	)
	(segment
		(start 105.7783 5.1943)
		(end 105.664 5.3086)
		(width 0.1016)
		(layer "F.Cu")
		(net "SMB_SLOTX24_STBY_LVC3_SDA_R2")
	)
	(segment
		(start 20.6121 8.3693)
		(end 20.7772 8.3693)
		(width 0.1016)
		(layer "F.Cu")
		(net "SMB_SLOTX24_STBY_LVC3_SDA_R2")
	)
	(segment
		(start 21.17979 8.77189)
		(end 21.17979 12.133072)
		(width 0.1016)
		(layer "F.Cu")
		(net "SMB_SLOTX24_STBY_LVC3_SDA_R2")
	)
	(via
		(at 20.6121 8.3693)
		(size 0.508)
		(drill 0.254)
		(layers "F.Cu" "B.Cu")
		(net "SMB_SLOTX24_STBY_LVC3_SDA_R2")
	)
	(via
		(at 105.664 5.3086)
		(size 0.508)
		(drill 0.254)
		(layers "F.Cu" "B.Cu")
		(net "SMB_SLOTX24_STBY_LVC3_SDA_R2")
	)
	(via
		(at 105.7783 4.3434)
		(size 0.7112)
		(drill 0.3556)
		(layers "F.Cu" "B.Cu")
		(net "SMB_SLOTX24_STBY_LVC3_SDA_R2")
	)
	(segment
		(start 106.4133 4.9022)
		(end 106.7181 5.207)
		(width 0.1016)
		(layer "B.Cu")
		(net "SMB_SLOTX24_STBY_LVC3_SDA_R2")
	)
	(segment
		(start 105.664 5.3086)
		(end 106.0704 4.9022)
		(width 0.1016)
		(layer "B.Cu")
		(net "SMB_SLOTX24_STBY_LVC3_SDA_R2")
	)
	(segment
		(start 106.0704 4.9022)
		(end 106.4133 4.9022)
		(width 0.1016)
		(layer "B.Cu")
		(net "SMB_SLOTX24_STBY_LVC3_SDA_R2")
	)
	(segment
		(start 36.043616 5.7023)
		(end 34.393124 4.051808)
		(width 0.127)
		(layer "In3.Cu")
		(net "SMB_SLOTX24_STBY_LVC3_SDA_R2")
	)
	(segment
		(start 20.6375 8.3439)
		(end 20.6121 8.3693)
		(width 0.127)
		(layer "In3.Cu")
		(net "SMB_SLOTX24_STBY_LVC3_SDA_R2")
	)
	(segment
		(start 99.9363 5.6261)
		(end 98.261932 3.951732)
		(width 0.127)
		(layer "In3.Cu")
		(net "SMB_SLOTX24_STBY_LVC3_SDA_R2")
	)
	(segment
		(start 27.05989 6.096254)
		(end 27.059636 6.096)
		(width 0.127)
		(layer "In3.Cu")
		(net "SMB_SLOTX24_STBY_LVC3_SDA_R2")
	)
	(segment
		(start 27.9019 6.096)
		(end 27.901646 6.096254)
		(width 0.127)
		(layer "In3.Cu")
		(net "SMB_SLOTX24_STBY_LVC3_SDA_R2")
	)
	(segment
		(start 22.944582 8.3439)
		(end 20.6375 8.3439)
		(width 0.127)
		(layer "In3.Cu")
		(net "SMB_SLOTX24_STBY_LVC3_SDA_R2")
	)
	(segment
		(start 34.393124 4.051808)
		(end 30.552136 4.051808)
		(width 0.127)
		(layer "In3.Cu")
		(net "SMB_SLOTX24_STBY_LVC3_SDA_R2")
	)
	(segment
		(start 49.8983 3.951732)
		(end 48.147732 5.7023)
		(width 0.127)
		(layer "In3.Cu")
		(net "SMB_SLOTX24_STBY_LVC3_SDA_R2")
	)
	(segment
		(start 30.552136 4.051808)
		(end 28.507944 6.096)
		(width 0.127)
		(layer "In3.Cu")
		(net "SMB_SLOTX24_STBY_LVC3_SDA_R2")
	)
	(segment
		(start 27.901646 6.096254)
		(end 27.05989 6.096254)
		(width 0.127)
		(layer "In3.Cu")
		(net "SMB_SLOTX24_STBY_LVC3_SDA_R2")
	)
	(segment
		(start 98.261932 3.951732)
		(end 49.8983 3.951732)
		(width 0.127)
		(layer "In3.Cu")
		(net "SMB_SLOTX24_STBY_LVC3_SDA_R2")
	)
	(segment
		(start 105.664 5.3086)
		(end 105.3465 5.6261)
		(width 0.127)
		(layer "In3.Cu")
		(net "SMB_SLOTX24_STBY_LVC3_SDA_R2")
	)
	(segment
		(start 105.3465 5.6261)
		(end 99.9363 5.6261)
		(width 0.127)
		(layer "In3.Cu")
		(net "SMB_SLOTX24_STBY_LVC3_SDA_R2")
	)
	(segment
		(start 28.507944 6.096)
		(end 27.9019 6.096)
		(width 0.127)
		(layer "In3.Cu")
		(net "SMB_SLOTX24_STBY_LVC3_SDA_R2")
	)
	(segment
		(start 25.192482 6.096)
		(end 22.944582 8.3439)
		(width 0.127)
		(layer "In3.Cu")
		(net "SMB_SLOTX24_STBY_LVC3_SDA_R2")
	)
	(segment
		(start 27.059636 6.096)
		(end 25.192482 6.096)
		(width 0.127)
		(layer "In3.Cu")
		(net "SMB_SLOTX24_STBY_LVC3_SDA_R2")
	)
	(segment
		(start 48.147732 5.7023)
		(end 36.043616 5.7023)
		(width 0.127)
		(layer "In3.Cu")
		(net "SMB_SLOTX24_STBY_LVC3_SDA_R2")
	)
	(segment
		(start 21.5138 8.0772)
		(end 21.5138 9.8806)
		(width 0.1016)
		(layer "F.Cu")
		(net "SMB_SLOTX24_STBY_LVC3_SCL_R2")
	)
	(segment
		(start 21.97989 10.34669)
		(end 21.97989 12.133072)
		(width 0.1016)
		(layer "F.Cu")
		(net "SMB_SLOTX24_STBY_LVC3_SCL_R2")
	)
	(segment
		(start 20.9169 7.4803)
		(end 21.5138 8.0772)
		(width 0.1016)
		(layer "F.Cu")
		(net "SMB_SLOTX24_STBY_LVC3_SCL_R2")
	)
	(segment
		(start 20.710652 7.4803)
		(end 20.9169 7.4803)
		(width 0.1016)
		(layer "F.Cu")
		(net "SMB_SLOTX24_STBY_LVC3_SCL_R2")
	)
	(segment
		(start 21.5138 9.8806)
		(end 21.97989 10.34669)
		(width 0.1016)
		(layer "F.Cu")
		(net "SMB_SLOTX24_STBY_LVC3_SCL_R2")
	)
	(via
		(at 104.690926 5.08)
		(size 0.508)
		(drill 0.254)
		(layers "F.Cu" "B.Cu")
		(net "SMB_SLOTX24_STBY_LVC3_SCL_R2")
	)
	(via
		(at 21.458428 6.176772)
		(size 0.7112)
		(drill 0.3556)
		(layers "F.Cu" "B.Cu")
		(net "SMB_SLOTX24_STBY_LVC3_SCL_R2")
	)
	(via
		(at 20.710652 7.4803)
		(size 0.508)
		(drill 0.254)
		(layers "F.Cu" "B.Cu")
		(net "SMB_SLOTX24_STBY_LVC3_SCL_R2")
	)
	(segment
		(start 106.4641 4.4196)
		(end 106.7181 4.1656)
		(width 0.1016)
		(layer "B.Cu")
		(net "SMB_SLOTX24_STBY_LVC3_SCL_R2")
	)
	(segment
		(start 104.690926 5.08)
		(end 105.0036 5.08)
		(width 0.1016)
		(layer "B.Cu")
		(net "SMB_SLOTX24_STBY_LVC3_SCL_R2")
	)
	(segment
		(start 105.664 4.4196)
		(end 106.4641 4.4196)
		(width 0.1016)
		(layer "B.Cu")
		(net "SMB_SLOTX24_STBY_LVC3_SCL_R2")
	)
	(segment
		(start 21.3614 6.829552)
		(end 20.710652 7.4803)
		(width 0.1016)
		(layer "B.Cu")
		(net "SMB_SLOTX24_STBY_LVC3_SCL_R2")
	)
	(segment
		(start 21.458428 6.176772)
		(end 21.3614 6.2738)
		(width 0.1016)
		(layer "B.Cu")
		(net "SMB_SLOTX24_STBY_LVC3_SCL_R2")
	)
	(segment
		(start 105.0036 5.08)
		(end 105.664 4.4196)
		(width 0.1016)
		(layer "B.Cu")
		(net "SMB_SLOTX24_STBY_LVC3_SCL_R2")
	)
	(segment
		(start 21.3614 6.2738)
		(end 21.3614 6.829552)
		(width 0.1016)
		(layer "B.Cu")
		(net "SMB_SLOTX24_STBY_LVC3_SCL_R2")
	)
	(segment
		(start 27.691334 5.588)
		(end 28.297378 5.588)
		(width 0.127)
		(layer "In3.Cu")
		(net "SMB_SLOTX24_STBY_LVC3_SCL_R2")
	)
	(segment
		(start 50.108866 3.443732)
		(end 98.503232 3.443732)
		(width 0.127)
		(layer "In3.Cu")
		(net "SMB_SLOTX24_STBY_LVC3_SCL_R2")
	)
	(segment
		(start 104.652826 5.1181)
		(end 104.690926 5.08)
		(width 0.127)
		(layer "In3.Cu")
		(net "SMB_SLOTX24_STBY_LVC3_SCL_R2")
	)
	(segment
		(start 100.1776 5.1181)
		(end 104.652826 5.1181)
		(width 0.127)
		(layer "In3.Cu")
		(net "SMB_SLOTX24_STBY_LVC3_SCL_R2")
	)
	(segment
		(start 27.270202 5.588)
		(end 27.270456 5.588254)
		(width 0.127)
		(layer "In3.Cu")
		(net "SMB_SLOTX24_STBY_LVC3_SCL_R2")
	)
	(segment
		(start 21.015452 7.7851)
		(end 22.784816 7.7851)
		(width 0.127)
		(layer "In3.Cu")
		(net "SMB_SLOTX24_STBY_LVC3_SCL_R2")
	)
	(segment
		(start 36.254182 5.1943)
		(end 47.937166 5.1943)
		(width 0.127)
		(layer "In3.Cu")
		(net "SMB_SLOTX24_STBY_LVC3_SCL_R2")
	)
	(segment
		(start 27.270456 5.588254)
		(end 27.69108 5.588254)
		(width 0.127)
		(layer "In3.Cu")
		(net "SMB_SLOTX24_STBY_LVC3_SCL_R2")
	)
	(segment
		(start 28.297378 5.588)
		(end 30.34157 3.543808)
		(width 0.127)
		(layer "In3.Cu")
		(net "SMB_SLOTX24_STBY_LVC3_SCL_R2")
	)
	(segment
		(start 24.981916 5.588)
		(end 27.270202 5.588)
		(width 0.127)
		(layer "In3.Cu")
		(net "SMB_SLOTX24_STBY_LVC3_SCL_R2")
	)
	(segment
		(start 98.503232 3.443732)
		(end 100.1776 5.1181)
		(width 0.127)
		(layer "In3.Cu")
		(net "SMB_SLOTX24_STBY_LVC3_SCL_R2")
	)
	(segment
		(start 34.182812 3.543554)
		(end 34.603436 3.543554)
		(width 0.127)
		(layer "In3.Cu")
		(net "SMB_SLOTX24_STBY_LVC3_SCL_R2")
	)
	(segment
		(start 30.34157 3.543808)
		(end 34.182558 3.543808)
		(width 0.127)
		(layer "In3.Cu")
		(net "SMB_SLOTX24_STBY_LVC3_SCL_R2")
	)
	(segment
		(start 34.603436 3.543554)
		(end 36.254182 5.1943)
		(width 0.127)
		(layer "In3.Cu")
		(net "SMB_SLOTX24_STBY_LVC3_SCL_R2")
	)
	(segment
		(start 47.937166 5.1943)
		(end 49.687988 3.443478)
		(width 0.127)
		(layer "In3.Cu")
		(net "SMB_SLOTX24_STBY_LVC3_SCL_R2")
	)
	(segment
		(start 20.710652 7.4803)
		(end 21.015452 7.7851)
		(width 0.127)
		(layer "In3.Cu")
		(net "SMB_SLOTX24_STBY_LVC3_SCL_R2")
	)
	(segment
		(start 50.108612 3.443478)
		(end 50.108866 3.443732)
		(width 0.127)
		(layer "In3.Cu")
		(net "SMB_SLOTX24_STBY_LVC3_SCL_R2")
	)
	(segment
		(start 34.182558 3.543808)
		(end 34.182812 3.543554)
		(width 0.127)
		(layer "In3.Cu")
		(net "SMB_SLOTX24_STBY_LVC3_SCL_R2")
	)
	(segment
		(start 27.69108 5.588254)
		(end 27.691334 5.588)
		(width 0.127)
		(layer "In3.Cu")
		(net "SMB_SLOTX24_STBY_LVC3_SCL_R2")
	)
	(segment
		(start 22.784816 7.7851)
		(end 24.981916 5.588)
		(width 0.127)
		(layer "In3.Cu")
		(net "SMB_SLOTX24_STBY_LVC3_SCL_R2")
	)
	(segment
		(start 49.687988 3.443478)
		(end 50.108612 3.443478)
		(width 0.127)
		(layer "In3.Cu")
		(net "SMB_SLOTX24_STBY_LVC3_SCL_R2")
	)
	(segment
		(start 39.899336 2.864358)
		(end 39.934642 2.864358)
		(width 0.1016)
		(layer "F.Cu")
		(net "SMB_HOST_STBY_LVC3_SDA_R5")
	)
	(segment
		(start 36.888674 3.779774)
		(end 37.036248 3.6322)
		(width 0.1016)
		(layer "F.Cu")
		(net "SMB_HOST_STBY_LVC3_SDA_R5")
	)
	(segment
		(start 39.934642 2.864358)
		(end 40.1193 2.6797)
		(width 0.1016)
		(layer "F.Cu")
		(net "SMB_HOST_STBY_LVC3_SDA_R5")
	)
	(segment
		(start 39.131494 3.6322)
		(end 39.899336 2.864358)
		(width 0.1016)
		(layer "F.Cu")
		(net "SMB_HOST_STBY_LVC3_SDA_R5")
	)
	(segment
		(start 40.1193 2.6797)
		(end 40.50411 2.6797)
		(width 0.1016)
		(layer "F.Cu")
		(net "SMB_HOST_STBY_LVC3_SDA_R5")
	)
	(segment
		(start 37.036248 3.6322)
		(end 39.131494 3.6322)
		(width 0.1016)
		(layer "F.Cu")
		(net "SMB_HOST_STBY_LVC3_SDA_R5")
	)
	(via
		(at 28.4988 7.0485)
		(size 0.7112)
		(drill 0.3556)
		(layers "F.Cu" "B.Cu")
		(net "SMB_HOST_STBY_LVC3_SDA_R5")
	)
	(via
		(at 36.888674 3.779774)
		(size 0.508)
		(drill 0.254)
		(layers "F.Cu" "B.Cu")
		(net "SMB_HOST_STBY_LVC3_SDA_R5")
	)
	(via
		(at 40.50411 2.6797)
		(size 0.508)
		(drill 0.254)
		(layers "F.Cu" "B.Cu")
		(net "SMB_HOST_STBY_LVC3_SDA_R5")
	)
	(segment
		(start 36.8808 5.2832)
		(end 36.888674 5.275326)
		(width 0.1016)
		(layer "B.Cu")
		(net "SMB_HOST_STBY_LVC3_SDA_R5")
	)
	(segment
		(start 35.950652 6.4897)
		(end 36.8808 5.559552)
		(width 0.1016)
		(layer "B.Cu")
		(net "SMB_HOST_STBY_LVC3_SDA_R5")
	)
	(segment
		(start 40.894 2.6797)
		(end 41.2369 3.0226)
		(width 0.1016)
		(layer "B.Cu")
		(net "SMB_HOST_STBY_LVC3_SDA_R5")
	)
	(segment
		(start 27.3431 9.06653)
		(end 27.3431 9.8171)
		(width 0.1016)
		(layer "B.Cu")
		(net "SMB_HOST_STBY_LVC3_SDA_R5")
	)
	(segment
		(start 39.20236 3.22072)
		(end 41.07688 3.22072)
		(width 0.1016)
		(layer "B.Cu")
		(net "SMB_HOST_STBY_LVC3_SDA_R5")
	)
	(segment
		(start 27.799538 8.610092)
		(end 27.3431 9.06653)
		(width 0.1016)
		(layer "B.Cu")
		(net "SMB_HOST_STBY_LVC3_SDA_R5")
	)
	(segment
		(start 34.3027 6.9342)
		(end 35.950652 6.4897)
		(width 0.1016)
		(layer "B.Cu")
		(net "SMB_HOST_STBY_LVC3_SDA_R5")
	)
	(segment
		(start 41.07688 3.22072)
		(end 41.275 3.0226)
		(width 0.1016)
		(layer "B.Cu")
		(net "SMB_HOST_STBY_LVC3_SDA_R5")
	)
	(segment
		(start 41.2369 3.0226)
		(end 41.275 3.0226)
		(width 0.1016)
		(layer "B.Cu")
		(net "SMB_HOST_STBY_LVC3_SDA_R5")
	)
	(segment
		(start 28.4988 7.0485)
		(end 28.6131 6.9342)
		(width 0.1016)
		(layer "B.Cu")
		(net "SMB_HOST_STBY_LVC3_SDA_R5")
	)
	(segment
		(start 28.4988 7.0485)
		(end 27.799538 7.747762)
		(width 0.1016)
		(layer "B.Cu")
		(net "SMB_HOST_STBY_LVC3_SDA_R5")
	)
	(segment
		(start 28.6131 6.9342)
		(end 34.3027 6.9342)
		(width 0.1016)
		(layer "B.Cu")
		(net "SMB_HOST_STBY_LVC3_SDA_R5")
	)
	(segment
		(start 27.799538 7.747762)
		(end 27.799538 8.610092)
		(width 0.1016)
		(layer "B.Cu")
		(net "SMB_HOST_STBY_LVC3_SDA_R5")
	)
	(segment
		(start 36.888674 5.275326)
		(end 36.888674 3.779774)
		(width 0.1016)
		(layer "B.Cu")
		(net "SMB_HOST_STBY_LVC3_SDA_R5")
	)
	(segment
		(start 27.3431 9.8171)
		(end 26.779982 10.380218)
		(width 0.1016)
		(layer "B.Cu")
		(net "SMB_HOST_STBY_LVC3_SDA_R5")
	)
	(segment
		(start 26.779982 10.380218)
		(end 26.779982 12.514072)
		(width 0.1016)
		(layer "B.Cu")
		(net "SMB_HOST_STBY_LVC3_SDA_R5")
	)
	(segment
		(start 36.8808 5.559552)
		(end 36.8808 5.2832)
		(width 0.1016)
		(layer "B.Cu")
		(net "SMB_HOST_STBY_LVC3_SDA_R5")
	)
	(segment
		(start 40.50411 2.6797)
		(end 40.894 2.6797)
		(width 0.1016)
		(layer "B.Cu")
		(net "SMB_HOST_STBY_LVC3_SDA_R5")
	)
	(segment
		(start 38.982142 3.0988)
		(end 39.699184 2.381758)
		(width 0.1016)
		(layer "F.Cu")
		(net "SMB_HOST_STBY_LVC3_SCL_R5")
	)
	(segment
		(start 40.24503 1.865884)
		(end 40.24503 1.83007)
		(width 0.1016)
		(layer "F.Cu")
		(net "SMB_HOST_STBY_LVC3_SCL_R5")
	)
	(segment
		(start 37.7825 3.0988)
		(end 38.982142 3.0988)
		(width 0.1016)
		(layer "F.Cu")
		(net "SMB_HOST_STBY_LVC3_SCL_R5")
	)
	(segment
		(start 40.24503 1.83007)
		(end 40.513 1.5621)
		(width 0.1016)
		(layer "F.Cu")
		(net "SMB_HOST_STBY_LVC3_SCL_R5")
	)
	(segment
		(start 39.729156 2.381758)
		(end 40.24503 1.865884)
		(width 0.1016)
		(layer "F.Cu")
		(net "SMB_HOST_STBY_LVC3_SCL_R5")
	)
	(segment
		(start 39.699184 2.381758)
		(end 39.729156 2.381758)
		(width 0.1016)
		(layer "F.Cu")
		(net "SMB_HOST_STBY_LVC3_SCL_R5")
	)
	(via
		(at 37.7825 3.0988)
		(size 0.508)
		(drill 0.254)
		(layers "F.Cu" "B.Cu")
		(net "SMB_HOST_STBY_LVC3_SCL_R5")
	)
	(via
		(at 40.513 1.5621)
		(size 0.508)
		(drill 0.254)
		(layers "F.Cu" "B.Cu")
		(net "SMB_HOST_STBY_LVC3_SCL_R5")
	)
	(via
		(at 37.6428 5.5372)
		(size 0.7112)
		(drill 0.3556)
		(layers "F.Cu" "B.Cu")
		(net "SMB_HOST_STBY_LVC3_SCL_R5")
	)
	(segment
		(start 29.5021 8.9154)
		(end 27.873452 8.9154)
		(width 0.1016)
		(layer "B.Cu")
		(net "SMB_HOST_STBY_LVC3_SCL_R5")
	)
	(segment
		(start 37.421058 4.548378)
		(end 37.421058 4.006342)
		(width 0.1016)
		(layer "B.Cu")
		(net "SMB_HOST_STBY_LVC3_SCL_R5")
	)
	(segment
		(start 27.579828 9.209024)
		(end 27.579828 12.514072)
		(width 0.1016)
		(layer "B.Cu")
		(net "SMB_HOST_STBY_LVC3_SCL_R5")
	)
	(segment
		(start 39.952168 2.57048)
		(end 39.20236 2.57048)
		(width 0.1016)
		(layer "B.Cu")
		(net "SMB_HOST_STBY_LVC3_SCL_R5")
	)
	(segment
		(start 37.6428 5.5372)
		(end 37.6428 4.77012)
		(width 0.1016)
		(layer "B.Cu")
		(net "SMB_HOST_STBY_LVC3_SCL_R5")
	)
	(segment
		(start 40.5765 1.6256)
		(end 41.148 1.6256)
		(width 0.1016)
		(layer "B.Cu")
		(net "SMB_HOST_STBY_LVC3_SCL_R5")
	)
	(segment
		(start 40.513 1.5621)
		(end 40.5765 1.6256)
		(width 0.1016)
		(layer "B.Cu")
		(net "SMB_HOST_STBY_LVC3_SCL_R5")
	)
	(segment
		(start 41.148 1.6256)
		(end 41.275 1.7526)
		(width 0.1016)
		(layer "B.Cu")
		(net "SMB_HOST_STBY_LVC3_SCL_R5")
	)
	(segment
		(start 34.5948 7.4168)
		(end 31.0007 7.4168)
		(width 0.1016)
		(layer "B.Cu")
		(net "SMB_HOST_STBY_LVC3_SCL_R5")
	)
	(segment
		(start 41.275 1.7526)
		(end 41.275 1.9939)
		(width 0.1016)
		(layer "B.Cu")
		(net "SMB_HOST_STBY_LVC3_SCL_R5")
	)
	(segment
		(start 31.0007 7.4168)
		(end 29.5021 8.9154)
		(width 0.1016)
		(layer "B.Cu")
		(net "SMB_HOST_STBY_LVC3_SCL_R5")
	)
	(segment
		(start 36.233354 6.88975)
		(end 36.115752 6.9723)
		(width 0.1016)
		(layer "B.Cu")
		(net "SMB_HOST_STBY_LVC3_SCL_R5")
	)
	(segment
		(start 41.275 1.9939)
		(end 41.0718 2.1971)
		(width 0.1016)
		(layer "B.Cu")
		(net "SMB_HOST_STBY_LVC3_SCL_R5")
	)
	(segment
		(start 37.7825 3.6449)
		(end 37.7825 3.0988)
		(width 0.1016)
		(layer "B.Cu")
		(net "SMB_HOST_STBY_LVC3_SCL_R5")
	)
	(segment
		(start 37.585904 5.5372)
		(end 36.233354 6.88975)
		(width 0.1016)
		(layer "B.Cu")
		(net "SMB_HOST_STBY_LVC3_SCL_R5")
	)
	(segment
		(start 37.6428 5.5372)
		(end 37.585904 5.5372)
		(width 0.1016)
		(layer "B.Cu")
		(net "SMB_HOST_STBY_LVC3_SCL_R5")
	)
	(segment
		(start 27.873452 8.9154)
		(end 27.579828 9.209024)
		(width 0.1016)
		(layer "B.Cu")
		(net "SMB_HOST_STBY_LVC3_SCL_R5")
	)
	(segment
		(start 40.325548 2.1971)
		(end 39.952168 2.57048)
		(width 0.1016)
		(layer "B.Cu")
		(net "SMB_HOST_STBY_LVC3_SCL_R5")
	)
	(segment
		(start 37.6428 4.77012)
		(end 37.421058 4.548378)
		(width 0.1016)
		(layer "B.Cu")
		(net "SMB_HOST_STBY_LVC3_SCL_R5")
	)
	(segment
		(start 37.421058 4.006342)
		(end 37.7825 3.6449)
		(width 0.1016)
		(layer "B.Cu")
		(net "SMB_HOST_STBY_LVC3_SCL_R5")
	)
	(segment
		(start 41.0718 2.1971)
		(end 40.325548 2.1971)
		(width 0.1016)
		(layer "B.Cu")
		(net "SMB_HOST_STBY_LVC3_SCL_R5")
	)
	(segment
		(start 36.115752 6.9723)
		(end 34.5948 7.4168)
		(width 0.1016)
		(layer "B.Cu")
		(net "SMB_HOST_STBY_LVC3_SCL_R5")
	)
	(via
		(at 113.15954 5.206492)
		(size 0.508)
		(drill 0.254)
		(layers "F.Cu" "B.Cu")
		(net "P3E_CPU0_PE2_SS_RXP<9>")
	)
	(segment
		(start 113.42751 7.125462)
		(end 113.51514 6.62432)
		(width 0.127)
		(layer "B.Cu")
		(net "P3E_CPU0_PE2_SS_RXP<9>")
	)
	(segment
		(start 113.099088 10.954766)
		(end 113.099342 10.954512)
		(width 0.127)
		(layer "B.Cu")
		(net "P3E_CPU0_PE2_SS_RXP<9>")
	)
	(segment
		(start 113.544858 8.264906)
		(end 113.544858 8.264144)
		(width 0.127)
		(layer "B.Cu")
		(net "P3E_CPU0_PE2_SS_RXP<9>")
	)
	(segment
		(start 113.543842 8.263636)
		(end 113.48847 7.72795)
		(width 0.127)
		(layer "B.Cu")
		(net "P3E_CPU0_PE2_SS_RXP<9>")
	)
	(segment
		(start 113.51514 6.62432)
		(end 113.51514 5.816092)
		(width 0.127)
		(layer "B.Cu")
		(net "P3E_CPU0_PE2_SS_RXP<9>")
	)
	(segment
		(start 113.48847 7.72795)
		(end 113.42751 7.125462)
		(width 0.127)
		(layer "B.Cu")
		(net "P3E_CPU0_PE2_SS_RXP<9>")
	)
	(segment
		(start 113.543842 8.264398)
		(end 113.543842 8.263636)
		(width 0.127)
		(layer "B.Cu")
		(net "P3E_CPU0_PE2_SS_RXP<9>")
	)
	(segment
		(start 113.544858 8.264144)
		(end 113.543842 8.264398)
		(width 0.127)
		(layer "B.Cu")
		(net "P3E_CPU0_PE2_SS_RXP<9>")
	)
	(segment
		(start 112.975136 12.615672)
		(end 112.975136 11.25347)
		(width 0.127)
		(layer "B.Cu")
		(net "P3E_CPU0_PE2_SS_RXP<9>")
	)
	(segment
		(start 113.222786 10.656062)
		(end 113.222786 10.30859)
		(width 0.127)
		(layer "B.Cu")
		(net "P3E_CPU0_PE2_SS_RXP<9>")
	)
	(arc
		(start 112.975136 11.25347)
		(mid 113.007392 11.09178)
		(end 113.099088 10.954766)
		(width 0.127)
		(layer "B.Cu")
		(net "P3E_CPU0_PE2_SS_RXP<9>")
	)
	(arc
		(start 113.426494 9.047988)
		(mid 113.515103 8.660895)
		(end 113.544858 8.264906)
		(width 0.127)
		(layer "B.Cu")
		(net "P3E_CPU0_PE2_SS_RXP<9>")
	)
	(arc
		(start 113.099342 10.954512)
		(mid 113.190728 10.817554)
		(end 113.222786 10.656062)
		(width 0.127)
		(layer "B.Cu")
		(net "P3E_CPU0_PE2_SS_RXP<9>")
	)
	(arc
		(start 113.222786 10.30859)
		(mid 113.274045 9.670114)
		(end 113.426494 9.047988)
		(width 0.127)
		(layer "B.Cu")
		(net "P3E_CPU0_PE2_SS_RXP<9>")
	)
	(arc
		(start 113.51514 5.816092)
		(mid 113.419739 5.463229)
		(end 113.15954 5.206492)
		(width 0.127)
		(layer "B.Cu")
		(net "P3E_CPU0_PE2_SS_RXP<9>")
	)
	(segment
		(start 98.648012 -2.683002)
		(end 97.349818 -4.536948)
		(width 0.127)
		(layer "In2.Cu")
		(net "P3E_CPU0_PE2_SS_RXP<9>")
	)
	(segment
		(start 97.380044 -8.174736)
		(end 97.486978 -8.28294)
		(width 0.127)
		(layer "In2.Cu")
		(net "P3E_CPU0_PE2_SS_RXP<9>")
	)
	(segment
		(start 110.06582 1.399032)
		(end 102.552246 0.075184)
		(width 0.127)
		(layer "In2.Cu")
		(net "P3E_CPU0_PE2_SS_RXP<9>")
	)
	(segment
		(start 97.349818 -4.536948)
		(end 96.94164 -6.852666)
		(width 0.127)
		(layer "In2.Cu")
		(net "P3E_CPU0_PE2_SS_RXP<9>")
	)
	(segment
		(start 102.552246 0.075184)
		(end 101.346 -0.2032)
		(width 0.127)
		(layer "In2.Cu")
		(net "P3E_CPU0_PE2_SS_RXP<9>")
	)
	(segment
		(start 99.419156 -1.459738)
		(end 98.648012 -2.683002)
		(width 0.127)
		(layer "In2.Cu")
		(net "P3E_CPU0_PE2_SS_RXP<9>")
	)
	(segment
		(start 101.346 -0.2032)
		(end 101.327712 -0.207264)
		(width 0.127)
		(layer "In2.Cu")
		(net "P3E_CPU0_PE2_SS_RXP<9>")
	)
	(segment
		(start 112.468152 3.081528)
		(end 110.06582 1.399032)
		(width 0.127)
		(layer "In2.Cu")
		(net "P3E_CPU0_PE2_SS_RXP<9>")
	)
	(segment
		(start 96.92767 -13.932408)
		(end 96.92767 -14.19352)
		(width 0.127)
		(layer "In2.Cu")
		(net "P3E_CPU0_PE2_SS_RXP<9>")
	)
	(segment
		(start 113.503456 4.560062)
		(end 112.468152 3.081528)
		(width 0.127)
		(layer "In2.Cu")
		(net "P3E_CPU0_PE2_SS_RXP<9>")
	)
	(segment
		(start 95.984314 -16.029432)
		(end 89.18575 -25.73909)
		(width 0.127)
		(layer "In2.Cu")
		(net "P3E_CPU0_PE2_SS_RXP<9>")
	)
	(segment
		(start 97.90811 -9.298686)
		(end 97.90811 -11.87958)
		(width 0.127)
		(layer "In2.Cu")
		(net "P3E_CPU0_PE2_SS_RXP<9>")
	)
	(segment
		(start 100.482146 -0.519684)
		(end 99.419156 -1.459738)
		(width 0.127)
		(layer "In2.Cu")
		(net "P3E_CPU0_PE2_SS_RXP<9>")
	)
	(segment
		(start 88.287098 -33.087056)
		(end 88.400636 -33.143698)
		(width 0.127)
		(layer "In2.Cu")
		(net "P3E_CPU0_PE2_SS_RXP<9>")
	)
	(segment
		(start 96.797368 -14.666214)
		(end 95.984314 -16.029432)
		(width 0.127)
		(layer "In2.Cu")
		(net "P3E_CPU0_PE2_SS_RXP<9>")
	)
	(segment
		(start 113.538 4.755642)
		(end 113.503456 4.560062)
		(width 0.127)
		(layer "In2.Cu")
		(net "P3E_CPU0_PE2_SS_RXP<9>")
	)
	(segment
		(start 87.72779 -30.20822)
		(end 87.727536 -30.20822)
		(width 0.127)
		(layer "In2.Cu")
		(net "P3E_CPU0_PE2_SS_RXP<9>")
	)
	(segment
		(start 97.68459 -12.418568)
		(end 97.462594 -12.640564)
		(width 0.127)
		(layer "In2.Cu")
		(net "P3E_CPU0_PE2_SS_RXP<9>")
	)
	(segment
		(start 88.457786 -33.314132)
		(end 88.080342 -34.070036)
		(width 0.127)
		(layer "In2.Cu")
		(net "P3E_CPU0_PE2_SS_RXP<9>")
	)
	(segment
		(start 101.327712 -0.207264)
		(end 100.482146 -0.519684)
		(width 0.127)
		(layer "In2.Cu")
		(net "P3E_CPU0_PE2_SS_RXP<9>")
	)
	(segment
		(start 88.400636 -33.143698)
		(end 88.40089 -33.143952)
		(width 0.127)
		(layer "In2.Cu")
		(net "P3E_CPU0_PE2_SS_RXP<9>")
	)
	(segment
		(start 96.94164 -6.852666)
		(end 96.94164 -7.115302)
		(width 0.127)
		(layer "In2.Cu")
		(net "P3E_CPU0_PE2_SS_RXP<9>")
	)
	(arc
		(start 87.747602 -31.568898)
		(mid 87.864145 -31.912216)
		(end 87.866982 -32.274764)
		(width 0.127)
		(layer "In2.Cu")
		(net "P3E_CPU0_PE2_SS_RXP<9>")
	)
	(arc
		(start 87.989156 -29.421836)
		(mid 87.905372 -29.83062)
		(end 87.72779 -30.20822)
		(width 0.127)
		(layer "In2.Cu")
		(net "P3E_CPU0_PE2_SS_RXP<9>")
	)
	(arc
		(start 88.75776 -28.0416)
		(mid 88.515419 -28.498816)
		(end 88.20531 -28.913074)
		(width 0.127)
		(layer "In2.Cu")
		(net "P3E_CPU0_PE2_SS_RXP<9>")
	)
	(arc
		(start 87.718392 -30.222698)
		(mid 87.629331 -30.460102)
		(end 87.581486 -30.709108)
		(width 0.127)
		(layer "In2.Cu")
		(net "P3E_CPU0_PE2_SS_RXP<9>")
	)
	(arc
		(start 89.18575 -25.73909)
		(mid 88.862716 -26.474225)
		(end 88.84666 -27.27706)
		(width 0.127)
		(layer "In2.Cu")
		(net "P3E_CPU0_PE2_SS_RXP<9>")
	)
	(arc
		(start 97.90811 -11.87958)
		(mid 97.849985 -12.171325)
		(end 97.68459 -12.418568)
		(width 0.127)
		(layer "In2.Cu")
		(net "P3E_CPU0_PE2_SS_RXP<9>")
	)
	(arc
		(start 87.727536 -30.20822)
		(mid 87.722982 -30.21547)
		(end 87.718392 -30.222698)
		(width 0.127)
		(layer "In2.Cu")
		(net "P3E_CPU0_PE2_SS_RXP<9>")
	)
	(arc
		(start 97.462594 -12.640564)
		(mid 97.06667 -13.233296)
		(end 96.92767 -13.932408)
		(width 0.127)
		(layer "In2.Cu")
		(net "P3E_CPU0_PE2_SS_RXP<9>")
	)
	(arc
		(start 96.94164 -7.115302)
		(mid 97.055407 -7.688661)
		(end 97.380044 -8.174736)
		(width 0.127)
		(layer "In2.Cu")
		(net "P3E_CPU0_PE2_SS_RXP<9>")
	)
	(arc
		(start 87.602568 -31.16326)
		(mid 87.660497 -31.371295)
		(end 87.747602 -31.568898)
		(width 0.127)
		(layer "In2.Cu")
		(net "P3E_CPU0_PE2_SS_RXP<9>")
	)
	(arc
		(start 97.486978 -8.28294)
		(mid 97.798534 -8.748938)
		(end 97.90811 -9.298686)
		(width 0.127)
		(layer "In2.Cu")
		(net "P3E_CPU0_PE2_SS_RXP<9>")
	)
	(arc
		(start 88.84666 -27.27706)
		(mid 88.858631 -27.665887)
		(end 88.75776 -28.0416)
		(width 0.127)
		(layer "In2.Cu")
		(net "P3E_CPU0_PE2_SS_RXP<9>")
	)
	(arc
		(start 88.40089 -33.143952)
		(mid 88.464583 -33.217258)
		(end 88.457786 -33.314132)
		(width 0.127)
		(layer "In2.Cu")
		(net "P3E_CPU0_PE2_SS_RXP<9>")
	)
	(arc
		(start 88.20531 -28.913074)
		(mid 88.05638 -29.150098)
		(end 87.989156 -29.421836)
		(width 0.127)
		(layer "In2.Cu")
		(net "P3E_CPU0_PE2_SS_RXP<9>")
	)
	(arc
		(start 87.581486 -30.709108)
		(mid 87.574739 -30.936986)
		(end 87.602568 -31.16326)
		(width 0.127)
		(layer "In2.Cu")
		(net "P3E_CPU0_PE2_SS_RXP<9>")
	)
	(arc
		(start 96.92767 -14.19352)
		(mid 96.894514 -14.438692)
		(end 96.797368 -14.666214)
		(width 0.127)
		(layer "In2.Cu")
		(net "P3E_CPU0_PE2_SS_RXP<9>")
	)
	(arc
		(start 113.15954 5.206492)
		(mid 113.434624 5.053184)
		(end 113.538 4.755642)
		(width 0.127)
		(layer "In2.Cu")
		(net "P3E_CPU0_PE2_SS_RXP<9>")
	)
	(arc
		(start 87.866982 -32.274764)
		(mid 87.944868 -32.749258)
		(end 88.287098 -33.087056)
		(width 0.127)
		(layer "In2.Cu")
		(net "P3E_CPU0_PE2_SS_RXP<9>")
	)
	(via
		(at 110.56874 5.206492)
		(size 0.508)
		(drill 0.254)
		(layers "F.Cu" "B.Cu")
		(net "P3E_CPU0_PE2_SS_RXP<8>")
	)
	(segment
		(start 110.57509 12.615672)
		(end 110.57509 11.215116)
		(width 0.127)
		(layer "B.Cu")
		(net "P3E_CPU0_PE2_SS_RXP<8>")
	)
	(segment
		(start 110.82274 10.6172)
		(end 110.82274 10.30859)
		(width 0.127)
		(layer "B.Cu")
		(net "P3E_CPU0_PE2_SS_RXP<8>")
	)
	(segment
		(start 110.914434 7.451598)
		(end 110.92434 6.546342)
		(width 0.127)
		(layer "B.Cu")
		(net "P3E_CPU0_PE2_SS_RXP<8>")
	)
	(segment
		(start 110.891066 7.745476)
		(end 110.914434 7.451598)
		(width 0.127)
		(layer "B.Cu")
		(net "P3E_CPU0_PE2_SS_RXP<8>")
	)
	(segment
		(start 110.92434 6.546342)
		(end 110.92434 5.816092)
		(width 0.127)
		(layer "B.Cu")
		(net "P3E_CPU0_PE2_SS_RXP<8>")
	)
	(arc
		(start 110.698788 10.916412)
		(mid 110.790515 10.779132)
		(end 110.82274 10.6172)
		(width 0.127)
		(layer "B.Cu")
		(net "P3E_CPU0_PE2_SS_RXP<8>")
	)
	(arc
		(start 110.92434 5.816092)
		(mid 110.828939 5.463229)
		(end 110.56874 5.206492)
		(width 0.127)
		(layer "B.Cu")
		(net "P3E_CPU0_PE2_SS_RXP<8>")
	)
	(arc
		(start 110.57509 11.215116)
		(mid 110.607243 11.05347)
		(end 110.698788 10.916412)
		(width 0.127)
		(layer "B.Cu")
		(net "P3E_CPU0_PE2_SS_RXP<8>")
	)
	(arc
		(start 110.82274 10.30859)
		(mid 110.823822 9.026151)
		(end 110.891066 7.745476)
		(width 0.127)
		(layer "B.Cu")
		(net "P3E_CPU0_PE2_SS_RXP<8>")
	)
	(segment
		(start 84.400136 -33.143698)
		(end 84.40039 -33.143952)
		(width 0.127)
		(layer "In2.Cu")
		(net "P3E_CPU0_PE2_SS_RXP<8>")
	)
	(segment
		(start 93.222572 -5.48513)
		(end 92.93987 -7.088632)
		(width 0.127)
		(layer "In2.Cu")
		(net "P3E_CPU0_PE2_SS_RXP<8>")
	)
	(segment
		(start 93.68409 -12.418568)
		(end 93.462094 -12.640564)
		(width 0.127)
		(layer "In2.Cu")
		(net "P3E_CPU0_PE2_SS_RXP<8>")
	)
	(segment
		(start 83.72729 -30.20822)
		(end 83.727036 -30.20822)
		(width 0.127)
		(layer "In2.Cu")
		(net "P3E_CPU0_PE2_SS_RXP<8>")
	)
	(segment
		(start 93.90761 -9.298686)
		(end 93.90761 -11.87958)
		(width 0.127)
		(layer "In2.Cu")
		(net "P3E_CPU0_PE2_SS_RXP<8>")
	)
	(segment
		(start 101.095302 2.418334)
		(end 96.506538 -0.794766)
		(width 0.127)
		(layer "In2.Cu")
		(net "P3E_CPU0_PE2_SS_RXP<8>")
	)
	(segment
		(start 110.930436 4.675378)
		(end 110.90656 4.54025)
		(width 0.127)
		(layer "In2.Cu")
		(net "P3E_CPU0_PE2_SS_RXP<8>")
	)
	(segment
		(start 110.90656 4.54025)
		(end 110.908592 4.535424)
		(width 0.127)
		(layer "In2.Cu")
		(net "P3E_CPU0_PE2_SS_RXP<8>")
	)
	(segment
		(start 93.378274 -8.174736)
		(end 93.486478 -8.28294)
		(width 0.127)
		(layer "In2.Cu")
		(net "P3E_CPU0_PE2_SS_RXP<8>")
	)
	(segment
		(start 92.796868 -14.666214)
		(end 91.983814 -16.029432)
		(width 0.127)
		(layer "In2.Cu")
		(net "P3E_CPU0_PE2_SS_RXP<8>")
	)
	(segment
		(start 110.908592 4.535424)
		(end 110.907068 4.532122)
		(width 0.127)
		(layer "In2.Cu")
		(net "P3E_CPU0_PE2_SS_RXP<8>")
	)
	(segment
		(start 110.907068 4.532122)
		(end 110.8583 4.414774)
		(width 0.127)
		(layer "In2.Cu")
		(net "P3E_CPU0_PE2_SS_RXP<8>")
	)
	(segment
		(start 84.286598 -33.087056)
		(end 84.400136 -33.143698)
		(width 0.127)
		(layer "In2.Cu")
		(net "P3E_CPU0_PE2_SS_RXP<8>")
	)
	(segment
		(start 110.336076 4.04876)
		(end 101.095302 2.418334)
		(width 0.127)
		(layer "In2.Cu")
		(net "P3E_CPU0_PE2_SS_RXP<8>")
	)
	(segment
		(start 84.457286 -33.314132)
		(end 84.079842 -34.070036)
		(width 0.127)
		(layer "In2.Cu")
		(net "P3E_CPU0_PE2_SS_RXP<8>")
	)
	(segment
		(start 91.983814 -16.029432)
		(end 85.18525 -25.73909)
		(width 0.127)
		(layer "In2.Cu")
		(net "P3E_CPU0_PE2_SS_RXP<8>")
	)
	(segment
		(start 110.930436 4.93395)
		(end 110.930436 4.675378)
		(width 0.127)
		(layer "In2.Cu")
		(net "P3E_CPU0_PE2_SS_RXP<8>")
	)
	(segment
		(start 110.56874 5.206492)
		(end 110.656116 5.206492)
		(width 0.127)
		(layer "In2.Cu")
		(net "P3E_CPU0_PE2_SS_RXP<8>")
	)
	(segment
		(start 92.92717 -13.932408)
		(end 92.92717 -14.19352)
		(width 0.127)
		(layer "In2.Cu")
		(net "P3E_CPU0_PE2_SS_RXP<8>")
	)
	(segment
		(start 96.506538 -0.794766)
		(end 96.250506 -1.160526)
		(width 0.127)
		(layer "In2.Cu")
		(net "P3E_CPU0_PE2_SS_RXP<8>")
	)
	(segment
		(start 110.8583 4.414774)
		(end 110.336076 4.04876)
		(width 0.127)
		(layer "In2.Cu")
		(net "P3E_CPU0_PE2_SS_RXP<8>")
	)
	(segment
		(start 96.250506 -1.160526)
		(end 93.222572 -5.48513)
		(width 0.127)
		(layer "In2.Cu")
		(net "P3E_CPU0_PE2_SS_RXP<8>")
	)
	(arc
		(start 93.486478 -8.28294)
		(mid 93.798034 -8.748938)
		(end 93.90761 -9.298686)
		(width 0.127)
		(layer "In2.Cu")
		(net "P3E_CPU0_PE2_SS_RXP<8>")
	)
	(arc
		(start 83.988656 -29.421836)
		(mid 83.904872 -29.83062)
		(end 83.72729 -30.20822)
		(width 0.127)
		(layer "In2.Cu")
		(net "P3E_CPU0_PE2_SS_RXP<8>")
	)
	(arc
		(start 93.90761 -11.87958)
		(mid 93.849485 -12.171325)
		(end 93.68409 -12.418568)
		(width 0.127)
		(layer "In2.Cu")
		(net "P3E_CPU0_PE2_SS_RXP<8>")
	)
	(arc
		(start 83.580986 -30.709108)
		(mid 83.574239 -30.936986)
		(end 83.602068 -31.16326)
		(width 0.127)
		(layer "In2.Cu")
		(net "P3E_CPU0_PE2_SS_RXP<8>")
	)
	(arc
		(start 83.717892 -30.222698)
		(mid 83.628831 -30.460102)
		(end 83.580986 -30.709108)
		(width 0.127)
		(layer "In2.Cu")
		(net "P3E_CPU0_PE2_SS_RXP<8>")
	)
	(arc
		(start 84.20481 -28.913074)
		(mid 84.05588 -29.150098)
		(end 83.988656 -29.421836)
		(width 0.127)
		(layer "In2.Cu")
		(net "P3E_CPU0_PE2_SS_RXP<8>")
	)
	(arc
		(start 84.40039 -33.143952)
		(mid 84.464083 -33.217258)
		(end 84.457286 -33.314132)
		(width 0.127)
		(layer "In2.Cu")
		(net "P3E_CPU0_PE2_SS_RXP<8>")
	)
	(arc
		(start 84.84616 -27.27706)
		(mid 84.858131 -27.665887)
		(end 84.75726 -28.0416)
		(width 0.127)
		(layer "In2.Cu")
		(net "P3E_CPU0_PE2_SS_RXP<8>")
	)
	(arc
		(start 83.602068 -31.16326)
		(mid 83.659997 -31.371295)
		(end 83.747102 -31.568898)
		(width 0.127)
		(layer "In2.Cu")
		(net "P3E_CPU0_PE2_SS_RXP<8>")
	)
	(arc
		(start 84.75726 -28.0416)
		(mid 84.514919 -28.498816)
		(end 84.20481 -28.913074)
		(width 0.127)
		(layer "In2.Cu")
		(net "P3E_CPU0_PE2_SS_RXP<8>")
	)
	(arc
		(start 85.18525 -25.73909)
		(mid 84.862216 -26.474225)
		(end 84.84616 -27.27706)
		(width 0.127)
		(layer "In2.Cu")
		(net "P3E_CPU0_PE2_SS_RXP<8>")
	)
	(arc
		(start 92.92717 -14.19352)
		(mid 92.894014 -14.438692)
		(end 92.796868 -14.666214)
		(width 0.127)
		(layer "In2.Cu")
		(net "P3E_CPU0_PE2_SS_RXP<8>")
	)
	(arc
		(start 83.747102 -31.568898)
		(mid 83.863645 -31.912216)
		(end 83.866482 -32.274764)
		(width 0.127)
		(layer "In2.Cu")
		(net "P3E_CPU0_PE2_SS_RXP<8>")
	)
	(arc
		(start 92.93987 -7.088632)
		(mid 93.048462 -7.676343)
		(end 93.378274 -8.174736)
		(width 0.127)
		(layer "In2.Cu")
		(net "P3E_CPU0_PE2_SS_RXP<8>")
	)
	(arc
		(start 93.462094 -12.640564)
		(mid 93.06617 -13.233296)
		(end 92.92717 -13.932408)
		(width 0.127)
		(layer "In2.Cu")
		(net "P3E_CPU0_PE2_SS_RXP<8>")
	)
	(arc
		(start 110.850172 5.126228)
		(mid 110.909267 5.038001)
		(end 110.930436 4.93395)
		(width 0.127)
		(layer "In2.Cu")
		(net "P3E_CPU0_PE2_SS_RXP<8>")
	)
	(arc
		(start 110.656116 5.206492)
		(mid 110.761122 5.185641)
		(end 110.850172 5.126228)
		(width 0.127)
		(layer "In2.Cu")
		(net "P3E_CPU0_PE2_SS_RXP<8>")
	)
	(arc
		(start 83.727036 -30.20822)
		(mid 83.722482 -30.21547)
		(end 83.717892 -30.222698)
		(width 0.127)
		(layer "In2.Cu")
		(net "P3E_CPU0_PE2_SS_RXP<8>")
	)
	(arc
		(start 83.866482 -32.274764)
		(mid 83.944368 -32.749258)
		(end 84.286598 -33.087056)
		(width 0.127)
		(layer "In2.Cu")
		(net "P3E_CPU0_PE2_SS_RXP<8>")
	)
	(via
		(at 96.766888 5.165852)
		(size 0.508)
		(drill 0.254)
		(layers "F.Cu" "B.Cu")
		(net "P3E_CPU0_PE2_SS_RXP<7>")
	)
	(segment
		(start 97.081848 8.001762)
		(end 97.120456 7.87273)
		(width 0.127)
		(layer "B.Cu")
		(net "P3E_CPU0_PE2_SS_RXP<7>")
	)
	(segment
		(start 97.120456 7.87273)
		(end 97.115376 7.863078)
		(width 0.127)
		(layer "B.Cu")
		(net "P3E_CPU0_PE2_SS_RXP<7>")
	)
	(segment
		(start 97.118424 7.861554)
		(end 97.122488 7.416546)
		(width 0.127)
		(layer "B.Cu")
		(net "P3E_CPU0_PE2_SS_RXP<7>")
	)
	(segment
		(start 96.379792 12.514072)
		(end 96.379792 11.008614)
		(width 0.127)
		(layer "B.Cu")
		(net "P3E_CPU0_PE2_SS_RXP<7>")
	)
	(segment
		(start 97.122488 7.416546)
		(end 97.122488 5.775452)
		(width 0.127)
		(layer "B.Cu")
		(net "P3E_CPU0_PE2_SS_RXP<7>")
	)
	(segment
		(start 97.115376 7.863078)
		(end 97.118424 7.861554)
		(width 0.127)
		(layer "B.Cu")
		(net "P3E_CPU0_PE2_SS_RXP<7>")
	)
	(segment
		(start 96.627442 10.410698)
		(end 96.627442 10.09396)
		(width 0.127)
		(layer "B.Cu")
		(net "P3E_CPU0_PE2_SS_RXP<7>")
	)
	(segment
		(start 96.901508 8.603234)
		(end 97.081848 8.002016)
		(width 0.127)
		(layer "B.Cu")
		(net "P3E_CPU0_PE2_SS_RXP<7>")
	)
	(segment
		(start 97.081848 8.002016)
		(end 97.081848 8.001762)
		(width 0.127)
		(layer "B.Cu")
		(net "P3E_CPU0_PE2_SS_RXP<7>")
	)
	(arc
		(start 96.50349 10.70991)
		(mid 96.595217 10.57263)
		(end 96.627442 10.410698)
		(width 0.127)
		(layer "B.Cu")
		(net "P3E_CPU0_PE2_SS_RXP<7>")
	)
	(arc
		(start 96.627442 10.09396)
		(mid 96.723894 9.341137)
		(end 96.901508 8.603234)
		(width 0.127)
		(layer "B.Cu")
		(net "P3E_CPU0_PE2_SS_RXP<7>")
	)
	(arc
		(start 97.122488 5.775452)
		(mid 97.027087 5.422589)
		(end 96.766888 5.165852)
		(width 0.127)
		(layer "B.Cu")
		(net "P3E_CPU0_PE2_SS_RXP<7>")
	)
	(arc
		(start 96.379792 11.008614)
		(mid 96.411945 10.846968)
		(end 96.50349 10.70991)
		(width 0.127)
		(layer "B.Cu")
		(net "P3E_CPU0_PE2_SS_RXP<7>")
	)
	(segment
		(start 80.301592 -25.911302)
		(end 80.004412 -26.149554)
		(width 0.127)
		(layer "In2.Cu")
		(net "P3E_CPU0_PE2_SS_RXP<7>")
	)
	(segment
		(start 89.379044 -8.174736)
		(end 89.487248 -8.28294)
		(width 0.127)
		(layer "In2.Cu")
		(net "P3E_CPU0_PE2_SS_RXP<7>")
	)
	(segment
		(start 89.68486 -12.418568)
		(end 89.462864 -12.640564)
		(width 0.127)
		(layer "In2.Cu")
		(net "P3E_CPU0_PE2_SS_RXP<7>")
	)
	(segment
		(start 79.156052 -26.829258)
		(end 79.100172 -26.896314)
		(width 0.127)
		(layer "In2.Cu")
		(net "P3E_CPU0_PE2_SS_RXP<7>")
	)
	(segment
		(start 82.095594 -24.473662)
		(end 80.852772 -25.469596)
		(width 0.127)
		(layer "In2.Cu")
		(net "P3E_CPU0_PE2_SS_RXP<7>")
	)
	(segment
		(start 78.968854 -27.323542)
		(end 78.965552 -27.730704)
		(width 0.127)
		(layer "In2.Cu")
		(net "P3E_CPU0_PE2_SS_RXP<7>")
	)
	(segment
		(start 79.100172 -26.896314)
		(end 78.968854 -27.323542)
		(width 0.127)
		(layer "In2.Cu")
		(net "P3E_CPU0_PE2_SS_RXP<7>")
	)
	(segment
		(start 79.453486 -26.591006)
		(end 79.156052 -26.829258)
		(width 0.127)
		(layer "In2.Cu")
		(net "P3E_CPU0_PE2_SS_RXP<7>")
	)
	(segment
		(start 79.457296 -32.825436)
		(end 79.079852 -32.069786)
		(width 0.127)
		(layer "In2.Cu")
		(net "P3E_CPU0_PE2_SS_RXP<7>")
	)
	(segment
		(start 97.140522 4.46405)
		(end 96.968056 3.486404)
		(width 0.127)
		(layer "In2.Cu")
		(net "P3E_CPU0_PE2_SS_RXP<7>")
	)
	(segment
		(start 97.145348 4.714748)
		(end 97.140522 4.46405)
		(width 0.127)
		(layer "In2.Cu")
		(net "P3E_CPU0_PE2_SS_RXP<7>")
	)
	(segment
		(start 89.90838 -9.298686)
		(end 89.90838 -11.87958)
		(width 0.127)
		(layer "In2.Cu")
		(net "P3E_CPU0_PE2_SS_RXP<7>")
	)
	(segment
		(start 80.852772 -25.469596)
		(end 80.624172 -25.44445)
		(width 0.127)
		(layer "In2.Cu")
		(net "P3E_CPU0_PE2_SS_RXP<7>")
	)
	(segment
		(start 79.775812 -26.124154)
		(end 79.478632 -26.362406)
		(width 0.127)
		(layer "In2.Cu")
		(net "P3E_CPU0_PE2_SS_RXP<7>")
	)
	(segment
		(start 80.004412 -26.149554)
		(end 79.775812 -26.124154)
		(width 0.127)
		(layer "In2.Cu")
		(net "P3E_CPU0_PE2_SS_RXP<7>")
	)
	(segment
		(start 91.793568 -3.903472)
		(end 89.559638 -5.467604)
		(width 0.127)
		(layer "In2.Cu")
		(net "P3E_CPU0_PE2_SS_RXP<7>")
	)
	(segment
		(start 96.968056 3.486404)
		(end 91.793568 -3.903472)
		(width 0.127)
		(layer "In2.Cu")
		(net "P3E_CPU0_PE2_SS_RXP<7>")
	)
	(segment
		(start 88.834468 -14.856206)
		(end 82.095594 -24.473662)
		(width 0.127)
		(layer "In2.Cu")
		(net "P3E_CPU0_PE2_SS_RXP<7>")
	)
	(segment
		(start 79.478632 -26.362406)
		(end 79.453486 -26.591006)
		(width 0.127)
		(layer "In2.Cu")
		(net "P3E_CPU0_PE2_SS_RXP<7>")
	)
	(segment
		(start 79.62773 -32.882332)
		(end 79.627476 -32.882332)
		(width 0.127)
		(layer "In2.Cu")
		(net "P3E_CPU0_PE2_SS_RXP<7>")
	)
	(segment
		(start 88.92794 -13.932408)
		(end 88.92794 -14.325854)
		(width 0.127)
		(layer "In2.Cu")
		(net "P3E_CPU0_PE2_SS_RXP<7>")
	)
	(segment
		(start 80.326992 -25.682702)
		(end 80.301592 -25.911302)
		(width 0.127)
		(layer "In2.Cu")
		(net "P3E_CPU0_PE2_SS_RXP<7>")
	)
	(segment
		(start 80.624172 -25.44445)
		(end 80.326992 -25.682702)
		(width 0.127)
		(layer "In2.Cu")
		(net "P3E_CPU0_PE2_SS_RXP<7>")
	)
	(segment
		(start 89.559638 -5.467604)
		(end 89.032842 -6.220206)
		(width 0.127)
		(layer "In2.Cu")
		(net "P3E_CPU0_PE2_SS_RXP<7>")
	)
	(segment
		(start 88.92794 -14.325854)
		(end 88.834468 -14.856206)
		(width 0.127)
		(layer "In2.Cu")
		(net "P3E_CPU0_PE2_SS_RXP<7>")
	)
	(segment
		(start 89.032842 -6.220206)
		(end 88.94064 -6.743446)
		(width 0.127)
		(layer "In2.Cu")
		(net "P3E_CPU0_PE2_SS_RXP<7>")
	)
	(segment
		(start 79.741522 -32.82569)
		(end 79.62773 -32.882332)
		(width 0.127)
		(layer "In2.Cu")
		(net "P3E_CPU0_PE2_SS_RXP<7>")
	)
	(segment
		(start 88.94064 -6.743446)
		(end 88.94064 -7.115302)
		(width 0.127)
		(layer "In2.Cu")
		(net "P3E_CPU0_PE2_SS_RXP<7>")
	)
	(arc
		(start 79.648812 -28.854654)
		(mid 79.896067 -29.22647)
		(end 79.915766 -29.672534)
		(width 0.127)
		(layer "In2.Cu")
		(net "P3E_CPU0_PE2_SS_RXP<7>")
	)
	(arc
		(start 89.90838 -11.87958)
		(mid 89.850255 -12.171325)
		(end 89.68486 -12.418568)
		(width 0.127)
		(layer "In2.Cu")
		(net "P3E_CPU0_PE2_SS_RXP<7>")
	)
	(arc
		(start 79.915766 -29.672534)
		(mid 79.77817 -30.995924)
		(end 79.969614 -32.31261)
		(width 0.127)
		(layer "In2.Cu")
		(net "P3E_CPU0_PE2_SS_RXP<7>")
	)
	(arc
		(start 89.487248 -8.28294)
		(mid 89.798804 -8.748938)
		(end 89.90838 -9.298686)
		(width 0.127)
		(layer "In2.Cu")
		(net "P3E_CPU0_PE2_SS_RXP<7>")
	)
	(arc
		(start 88.94064 -7.115302)
		(mid 89.054407 -7.688661)
		(end 89.379044 -8.174736)
		(width 0.127)
		(layer "In2.Cu")
		(net "P3E_CPU0_PE2_SS_RXP<7>")
	)
	(arc
		(start 79.969614 -32.31261)
		(mid 79.947505 -32.610042)
		(end 79.741522 -32.82569)
		(width 0.127)
		(layer "In2.Cu")
		(net "P3E_CPU0_PE2_SS_RXP<7>")
	)
	(arc
		(start 89.462864 -12.640564)
		(mid 89.06694 -13.233296)
		(end 88.92794 -13.932408)
		(width 0.127)
		(layer "In2.Cu")
		(net "P3E_CPU0_PE2_SS_RXP<7>")
	)
	(arc
		(start 78.965552 -27.730704)
		(mid 79.218494 -28.346595)
		(end 79.648812 -28.854654)
		(width 0.127)
		(layer "In2.Cu")
		(net "P3E_CPU0_PE2_SS_RXP<7>")
	)
	(arc
		(start 96.766888 5.165852)
		(mid 97.042054 5.012447)
		(end 97.145348 4.714748)
		(width 0.127)
		(layer "In2.Cu")
		(net "P3E_CPU0_PE2_SS_RXP<7>")
	)
	(arc
		(start 79.627476 -32.882332)
		(mid 79.530602 -32.889129)
		(end 79.457296 -32.825436)
		(width 0.127)
		(layer "In2.Cu")
		(net "P3E_CPU0_PE2_SS_RXP<7>")
	)
	(via
		(at 94.176088 5.165852)
		(size 0.508)
		(drill 0.254)
		(layers "F.Cu" "B.Cu")
		(net "P3E_CPU0_PE2_SS_RXP<6>")
	)
	(segment
		(start 94.485968 7.52856)
		(end 94.511114 7.927848)
		(width 0.127)
		(layer "B.Cu")
		(net "P3E_CPU0_PE2_SS_RXP<6>")
	)
	(segment
		(start 94.51213 7.92988)
		(end 94.489016 8.361426)
		(width 0.127)
		(layer "B.Cu")
		(net "P3E_CPU0_PE2_SS_RXP<6>")
	)
	(segment
		(start 94.531688 6.554216)
		(end 94.530164 6.573266)
		(width 0.127)
		(layer "B.Cu")
		(net "P3E_CPU0_PE2_SS_RXP<6>")
	)
	(segment
		(start 94.530164 6.573266)
		(end 94.485968 7.52856)
		(width 0.127)
		(layer "B.Cu")
		(net "P3E_CPU0_PE2_SS_RXP<6>")
	)
	(segment
		(start 93.98 10.995406)
		(end 93.98 12.514072)
		(width 0.127)
		(layer "B.Cu")
		(net "P3E_CPU0_PE2_SS_RXP<6>")
	)
	(segment
		(start 94.511114 7.927848)
		(end 94.51213 7.928864)
		(width 0.127)
		(layer "B.Cu")
		(net "P3E_CPU0_PE2_SS_RXP<6>")
	)
	(segment
		(start 94.22765 10.14603)
		(end 94.22765 10.397744)
		(width 0.127)
		(layer "B.Cu")
		(net "P3E_CPU0_PE2_SS_RXP<6>")
	)
	(segment
		(start 94.51213 7.928864)
		(end 94.51213 7.92988)
		(width 0.127)
		(layer "B.Cu")
		(net "P3E_CPU0_PE2_SS_RXP<6>")
	)
	(segment
		(start 94.531688 5.775452)
		(end 94.531688 6.554216)
		(width 0.127)
		(layer "B.Cu")
		(net "P3E_CPU0_PE2_SS_RXP<6>")
	)
	(arc
		(start 94.396306 8.696706)
		(mid 94.175969 9.405548)
		(end 94.22765 10.14603)
		(width 0.127)
		(layer "B.Cu")
		(net "P3E_CPU0_PE2_SS_RXP<6>")
	)
	(arc
		(start 94.176088 5.165852)
		(mid 94.436303 5.422579)
		(end 94.531688 5.775452)
		(width 0.127)
		(layer "B.Cu")
		(net "P3E_CPU0_PE2_SS_RXP<6>")
	)
	(arc
		(start 94.103952 10.696448)
		(mid 94.012195 10.833583)
		(end 93.98 10.995406)
		(width 0.127)
		(layer "B.Cu")
		(net "P3E_CPU0_PE2_SS_RXP<6>")
	)
	(arc
		(start 94.489016 8.361426)
		(mid 94.460883 8.534102)
		(end 94.396306 8.696706)
		(width 0.127)
		(layer "B.Cu")
		(net "P3E_CPU0_PE2_SS_RXP<6>")
	)
	(arc
		(start 94.22765 10.397744)
		(mid 94.195497 10.55939)
		(end 94.103952 10.696448)
		(width 0.127)
		(layer "B.Cu")
		(net "P3E_CPU0_PE2_SS_RXP<6>")
	)
	(segment
		(start 84.993988 -6.436868)
		(end 84.94014 -6.743446)
		(width 0.127)
		(layer "In2.Cu")
		(net "P3E_CPU0_PE2_SS_RXP<6>")
	)
	(segment
		(start 90.731848 -2.031492)
		(end 85.52561 -5.677408)
		(width 0.127)
		(layer "In2.Cu")
		(net "P3E_CPU0_PE2_SS_RXP<6>")
	)
	(segment
		(start 75.742292 -32.82569)
		(end 75.6285 -32.882332)
		(width 0.127)
		(layer "In2.Cu")
		(net "P3E_CPU0_PE2_SS_RXP<6>")
	)
	(segment
		(start 84.827364 -14.439138)
		(end 84.669884 -14.68628)
		(width 0.127)
		(layer "In2.Cu")
		(net "P3E_CPU0_PE2_SS_RXP<6>")
	)
	(segment
		(start 85.68436 -12.418568)
		(end 85.462364 -12.640564)
		(width 0.127)
		(layer "In2.Cu")
		(net "P3E_CPU0_PE2_SS_RXP<6>")
	)
	(segment
		(start 76.066142 -25.608534)
		(end 76.075794 -25.83815)
		(width 0.127)
		(layer "In2.Cu")
		(net "P3E_CPU0_PE2_SS_RXP<6>")
	)
	(segment
		(start 83.222338 -16.712692)
		(end 81.77022 -18.7452)
		(width 0.127)
		(layer "In2.Cu")
		(net "P3E_CPU0_PE2_SS_RXP<6>")
	)
	(segment
		(start 85.90788 -9.298686)
		(end 85.90788 -11.87958)
		(width 0.127)
		(layer "In2.Cu")
		(net "P3E_CPU0_PE2_SS_RXP<6>")
	)
	(segment
		(start 76.075794 -25.83815)
		(end 75.817984 -26.11882)
		(width 0.127)
		(layer "In2.Cu")
		(net "P3E_CPU0_PE2_SS_RXP<6>")
	)
	(segment
		(start 84.94014 -6.743446)
		(end 84.94014 -7.115302)
		(width 0.127)
		(layer "In2.Cu")
		(net "P3E_CPU0_PE2_SS_RXP<6>")
	)
	(segment
		(start 84.92744 -13.904214)
		(end 84.827364 -14.439138)
		(width 0.127)
		(layer "In2.Cu")
		(net "P3E_CPU0_PE2_SS_RXP<6>")
	)
	(segment
		(start 81.77022 -18.7452)
		(end 78.67777 -23.005796)
		(width 0.127)
		(layer "In2.Cu")
		(net "P3E_CPU0_PE2_SS_RXP<6>")
	)
	(segment
		(start 75.330558 -26.409142)
		(end 75.340464 -26.638758)
		(width 0.127)
		(layer "In2.Cu")
		(net "P3E_CPU0_PE2_SS_RXP<6>")
	)
	(segment
		(start 76.553568 -25.318212)
		(end 76.323952 -25.327864)
		(width 0.127)
		(layer "In2.Cu")
		(net "P3E_CPU0_PE2_SS_RXP<6>")
	)
	(segment
		(start 75.588368 -26.128472)
		(end 75.330558 -26.409142)
		(width 0.127)
		(layer "In2.Cu")
		(net "P3E_CPU0_PE2_SS_RXP<6>")
	)
	(segment
		(start 94.30385 3.069844)
		(end 90.731848 -2.031492)
		(width 0.127)
		(layer "In2.Cu")
		(net "P3E_CPU0_PE2_SS_RXP<6>")
	)
	(segment
		(start 75.6285 -32.882332)
		(end 75.628246 -32.882332)
		(width 0.127)
		(layer "In2.Cu")
		(net "P3E_CPU0_PE2_SS_RXP<6>")
	)
	(segment
		(start 85.52561 -5.677408)
		(end 84.993988 -6.436868)
		(width 0.127)
		(layer "In2.Cu")
		(net "P3E_CPU0_PE2_SS_RXP<6>")
	)
	(segment
		(start 75.817984 -26.11882)
		(end 75.588368 -26.128472)
		(width 0.127)
		(layer "In2.Cu")
		(net "P3E_CPU0_PE2_SS_RXP<6>")
	)
	(segment
		(start 76.323952 -25.327864)
		(end 76.066142 -25.608534)
		(width 0.127)
		(layer "In2.Cu")
		(net "P3E_CPU0_PE2_SS_RXP<6>")
	)
	(segment
		(start 78.67777 -23.005796)
		(end 76.553568 -25.318212)
		(width 0.127)
		(layer "In2.Cu")
		(net "P3E_CPU0_PE2_SS_RXP<6>")
	)
	(segment
		(start 84.669884 -14.68628)
		(end 83.222338 -16.712692)
		(width 0.127)
		(layer "In2.Cu")
		(net "P3E_CPU0_PE2_SS_RXP<6>")
	)
	(segment
		(start 85.378544 -8.174736)
		(end 85.486748 -8.28294)
		(width 0.127)
		(layer "In2.Cu")
		(net "P3E_CPU0_PE2_SS_RXP<6>")
	)
	(segment
		(start 94.554548 4.714748)
		(end 94.549722 4.46405)
		(width 0.127)
		(layer "In2.Cu")
		(net "P3E_CPU0_PE2_SS_RXP<6>")
	)
	(segment
		(start 75.340464 -26.638758)
		(end 75.082654 -26.919428)
		(width 0.127)
		(layer "In2.Cu")
		(net "P3E_CPU0_PE2_SS_RXP<6>")
	)
	(segment
		(start 94.549722 4.46405)
		(end 94.30385 3.069844)
		(width 0.127)
		(layer "In2.Cu")
		(net "P3E_CPU0_PE2_SS_RXP<6>")
	)
	(arc
		(start 75.649582 -28.854654)
		(mid 75.896837 -29.22647)
		(end 75.916536 -29.672534)
		(width 0.127)
		(layer "In2.Cu")
		(net "P3E_CPU0_PE2_SS_RXP<6>")
	)
	(arc
		(start 85.90788 -11.87958)
		(mid 85.849755 -12.171325)
		(end 85.68436 -12.418568)
		(width 0.127)
		(layer "In2.Cu")
		(net "P3E_CPU0_PE2_SS_RXP<6>")
	)
	(arc
		(start 85.486748 -8.28294)
		(mid 85.798304 -8.748938)
		(end 85.90788 -9.298686)
		(width 0.127)
		(layer "In2.Cu")
		(net "P3E_CPU0_PE2_SS_RXP<6>")
	)
	(arc
		(start 75.628246 -32.882332)
		(mid 75.531372 -32.889129)
		(end 75.458066 -32.825436)
		(width 0.127)
		(layer "In2.Cu")
		(net "P3E_CPU0_PE2_SS_RXP<6>")
	)
	(arc
		(start 84.94014 -7.115302)
		(mid 85.053907 -7.688661)
		(end 85.378544 -8.174736)
		(width 0.127)
		(layer "In2.Cu")
		(net "P3E_CPU0_PE2_SS_RXP<6>")
	)
	(arc
		(start 75.082654 -26.919428)
		(mid 74.948451 -27.333955)
		(end 74.975974 -27.768804)
		(width 0.127)
		(layer "In2.Cu")
		(net "P3E_CPU0_PE2_SS_RXP<6>")
	)
	(arc
		(start 75.916536 -29.672534)
		(mid 75.77894 -30.995924)
		(end 75.970384 -32.31261)
		(width 0.127)
		(layer "In2.Cu")
		(net "P3E_CPU0_PE2_SS_RXP<6>")
	)
	(arc
		(start 74.975974 -27.768804)
		(mid 75.229664 -28.36329)
		(end 75.649582 -28.854654)
		(width 0.127)
		(layer "In2.Cu")
		(net "P3E_CPU0_PE2_SS_RXP<6>")
	)
	(arc
		(start 75.970384 -32.31261)
		(mid 75.948275 -32.610042)
		(end 75.742292 -32.82569)
		(width 0.127)
		(layer "In2.Cu")
		(net "P3E_CPU0_PE2_SS_RXP<6>")
	)
	(arc
		(start 85.462364 -12.640564)
		(mid 85.071749 -13.220263)
		(end 84.92744 -13.904214)
		(width 0.127)
		(layer "In2.Cu")
		(net "P3E_CPU0_PE2_SS_RXP<6>")
	)
	(arc
		(start 75.458066 -32.825436)
		(mid 75.269056 -32.447437)
		(end 75.079352 -32.069786)
		(width 0.127)
		(layer "In2.Cu")
		(net "P3E_CPU0_PE2_SS_RXP<6>")
	)
	(arc
		(start 94.176088 5.165852)
		(mid 94.451254 5.012447)
		(end 94.554548 4.714748)
		(width 0.127)
		(layer "In2.Cu")
		(net "P3E_CPU0_PE2_SS_RXP<6>")
	)
	(via
		(at 91.585288 5.165852)
		(size 0.508)
		(drill 0.254)
		(layers "F.Cu" "B.Cu")
		(net "P3E_CPU0_PE2_SS_RXP<5>")
	)
	(segment
		(start 91.936316 8.037576)
		(end 91.895168 7.54761)
		(width 0.127)
		(layer "B.Cu")
		(net "P3E_CPU0_PE2_SS_RXP<5>")
	)
	(segment
		(start 91.937586 8.05434)
		(end 91.937078 8.048244)
		(width 0.127)
		(layer "B.Cu")
		(net "P3E_CPU0_PE2_SS_RXP<5>")
	)
	(segment
		(start 91.827604 10.435336)
		(end 91.827604 10.10285)
		(width 0.127)
		(layer "B.Cu")
		(net "P3E_CPU0_PE2_SS_RXP<5>")
	)
	(segment
		(start 91.936062 8.037576)
		(end 91.936316 8.037576)
		(width 0.127)
		(layer "B.Cu")
		(net "P3E_CPU0_PE2_SS_RXP<5>")
	)
	(segment
		(start 91.579954 12.514072)
		(end 91.579954 11.033252)
		(width 0.127)
		(layer "B.Cu")
		(net "P3E_CPU0_PE2_SS_RXP<5>")
	)
	(segment
		(start 91.895168 7.54761)
		(end 91.858084 7.113778)
		(width 0.127)
		(layer "B.Cu")
		(net "P3E_CPU0_PE2_SS_RXP<5>")
	)
	(segment
		(start 91.937078 8.048244)
		(end 91.936062 8.037576)
		(width 0.127)
		(layer "B.Cu")
		(net "P3E_CPU0_PE2_SS_RXP<5>")
	)
	(segment
		(start 91.858084 7.113778)
		(end 91.940888 6.539992)
		(width 0.127)
		(layer "B.Cu")
		(net "P3E_CPU0_PE2_SS_RXP<5>")
	)
	(segment
		(start 91.940888 6.539992)
		(end 91.940888 5.775452)
		(width 0.127)
		(layer "B.Cu")
		(net "P3E_CPU0_PE2_SS_RXP<5>")
	)
	(arc
		(start 91.579954 11.033252)
		(mid 91.612107 10.871606)
		(end 91.703652 10.734548)
		(width 0.127)
		(layer "B.Cu")
		(net "P3E_CPU0_PE2_SS_RXP<5>")
	)
	(arc
		(start 91.940888 5.775452)
		(mid 91.845487 5.422589)
		(end 91.585288 5.165852)
		(width 0.127)
		(layer "B.Cu")
		(net "P3E_CPU0_PE2_SS_RXP<5>")
	)
	(arc
		(start 91.827604 10.10285)
		(mid 91.862731 9.077528)
		(end 91.937586 8.05434)
		(width 0.127)
		(layer "B.Cu")
		(net "P3E_CPU0_PE2_SS_RXP<5>")
	)
	(arc
		(start 91.703652 10.734548)
		(mid 91.795379 10.597268)
		(end 91.827604 10.435336)
		(width 0.127)
		(layer "B.Cu")
		(net "P3E_CPU0_PE2_SS_RXP<5>")
	)
	(segment
		(start 71.080122 -32.069786)
		(end 71.457566 -32.825436)
		(width 0.127)
		(layer "In2.Cu")
		(net "P3E_CPU0_PE2_SS_RXP<5>")
	)
	(segment
		(start 81.360264 -6.200394)
		(end 88.908128 -0.916178)
		(width 0.127)
		(layer "In2.Cu")
		(net "P3E_CPU0_PE2_SS_RXP<5>")
	)
	(segment
		(start 75.854052 -21.831046)
		(end 80.864964 -14.675104)
		(width 0.127)
		(layer "In2.Cu")
		(net "P3E_CPU0_PE2_SS_RXP<5>")
	)
	(segment
		(start 81.90738 -11.87958)
		(end 81.90738 -9.298686)
		(width 0.127)
		(layer "In2.Cu")
		(net "P3E_CPU0_PE2_SS_RXP<5>")
	)
	(segment
		(start 71.399146 -26.204418)
		(end 71.663814 -25.930352)
		(width 0.127)
		(layer "In2.Cu")
		(net "P3E_CPU0_PE2_SS_RXP<5>")
	)
	(segment
		(start 71.893684 -25.926542)
		(end 72.158606 -25.65273)
		(width 0.127)
		(layer "In2.Cu")
		(net "P3E_CPU0_PE2_SS_RXP<5>")
	)
	(segment
		(start 80.93964 -7.088632)
		(end 81.007458 -6.70433)
		(width 0.127)
		(layer "In2.Cu")
		(net "P3E_CPU0_PE2_SS_RXP<5>")
	)
	(segment
		(start 71.402956 -26.434288)
		(end 71.399146 -26.204418)
		(width 0.127)
		(layer "In2.Cu")
		(net "P3E_CPU0_PE2_SS_RXP<5>")
	)
	(segment
		(start 70.967346 -27.736546)
		(end 70.95363 -27.310842)
		(width 0.127)
		(layer "In2.Cu")
		(net "P3E_CPU0_PE2_SS_RXP<5>")
	)
	(segment
		(start 71.138034 -26.7081)
		(end 71.402956 -26.434288)
		(width 0.127)
		(layer "In2.Cu")
		(net "P3E_CPU0_PE2_SS_RXP<5>")
	)
	(segment
		(start 72.649334 -25.144984)
		(end 75.854052 -21.831046)
		(width 0.127)
		(layer "In2.Cu")
		(net "P3E_CPU0_PE2_SS_RXP<5>")
	)
	(segment
		(start 72.158606 -25.65273)
		(end 72.154796 -25.42286)
		(width 0.127)
		(layer "In2.Cu")
		(net "P3E_CPU0_PE2_SS_RXP<5>")
	)
	(segment
		(start 71.663814 -25.930352)
		(end 71.893684 -25.926542)
		(width 0.127)
		(layer "In2.Cu")
		(net "P3E_CPU0_PE2_SS_RXP<5>")
	)
	(segment
		(start 81.007458 -6.70433)
		(end 81.360264 -6.200394)
		(width 0.127)
		(layer "In2.Cu")
		(net "P3E_CPU0_PE2_SS_RXP<5>")
	)
	(segment
		(start 71.097394 -26.751026)
		(end 71.138034 -26.7081)
		(width 0.127)
		(layer "In2.Cu")
		(net "P3E_CPU0_PE2_SS_RXP<5>")
	)
	(segment
		(start 71.628 -32.882332)
		(end 71.741792 -32.82569)
		(width 0.127)
		(layer "In2.Cu")
		(net "P3E_CPU0_PE2_SS_RXP<5>")
	)
	(segment
		(start 72.419464 -25.149048)
		(end 72.649334 -25.144984)
		(width 0.127)
		(layer "In2.Cu")
		(net "P3E_CPU0_PE2_SS_RXP<5>")
	)
	(segment
		(start 81.486248 -8.28294)
		(end 81.378044 -8.174736)
		(width 0.127)
		(layer "In2.Cu")
		(net "P3E_CPU0_PE2_SS_RXP<5>")
	)
	(segment
		(start 80.864964 -14.675104)
		(end 80.92694 -14.325854)
		(width 0.127)
		(layer "In2.Cu")
		(net "P3E_CPU0_PE2_SS_RXP<5>")
	)
	(segment
		(start 81.461864 -12.640564)
		(end 81.68386 -12.418568)
		(width 0.127)
		(layer "In2.Cu")
		(net "P3E_CPU0_PE2_SS_RXP<5>")
	)
	(segment
		(start 70.95363 -27.310842)
		(end 71.097394 -26.751026)
		(width 0.127)
		(layer "In2.Cu")
		(net "P3E_CPU0_PE2_SS_RXP<5>")
	)
	(segment
		(start 71.627746 -32.882332)
		(end 71.628 -32.882332)
		(width 0.127)
		(layer "In2.Cu")
		(net "P3E_CPU0_PE2_SS_RXP<5>")
	)
	(segment
		(start 91.77274 3.175762)
		(end 91.947238 4.16433)
		(width 0.127)
		(layer "In2.Cu")
		(net "P3E_CPU0_PE2_SS_RXP<5>")
	)
	(segment
		(start 91.947238 4.16433)
		(end 91.947238 4.751324)
		(width 0.127)
		(layer "In2.Cu")
		(net "P3E_CPU0_PE2_SS_RXP<5>")
	)
	(segment
		(start 88.908128 -0.916178)
		(end 91.77274 3.175762)
		(width 0.127)
		(layer "In2.Cu")
		(net "P3E_CPU0_PE2_SS_RXP<5>")
	)
	(segment
		(start 72.154796 -25.42286)
		(end 72.419464 -25.149048)
		(width 0.127)
		(layer "In2.Cu")
		(net "P3E_CPU0_PE2_SS_RXP<5>")
	)
	(segment
		(start 80.92694 -14.325854)
		(end 80.92694 -13.932408)
		(width 0.127)
		(layer "In2.Cu")
		(net "P3E_CPU0_PE2_SS_RXP<5>")
	)
	(arc
		(start 71.916036 -29.672534)
		(mid 71.896253 -29.226498)
		(end 71.649082 -28.854654)
		(width 0.127)
		(layer "In2.Cu")
		(net "P3E_CPU0_PE2_SS_RXP<5>")
	)
	(arc
		(start 71.969884 -32.31261)
		(mid 71.778387 -30.995925)
		(end 71.916036 -29.672534)
		(width 0.127)
		(layer "In2.Cu")
		(net "P3E_CPU0_PE2_SS_RXP<5>")
	)
	(arc
		(start 81.378044 -8.174736)
		(mid 81.048328 -7.676304)
		(end 80.93964 -7.088632)
		(width 0.127)
		(layer "In2.Cu")
		(net "P3E_CPU0_PE2_SS_RXP<5>")
	)
	(arc
		(start 91.947238 4.751324)
		(mid 91.844015 5.026477)
		(end 91.585288 5.165852)
		(width 0.127)
		(layer "In2.Cu")
		(net "P3E_CPU0_PE2_SS_RXP<5>")
	)
	(arc
		(start 81.68386 -12.418568)
		(mid 81.849177 -12.171293)
		(end 81.90738 -11.87958)
		(width 0.127)
		(layer "In2.Cu")
		(net "P3E_CPU0_PE2_SS_RXP<5>")
	)
	(arc
		(start 71.649082 -28.854654)
		(mid 71.2204 -28.34914)
		(end 70.967346 -27.736546)
		(width 0.127)
		(layer "In2.Cu")
		(net "P3E_CPU0_PE2_SS_RXP<5>")
	)
	(arc
		(start 71.741792 -32.82569)
		(mid 71.947679 -32.609999)
		(end 71.969884 -32.31261)
		(width 0.127)
		(layer "In2.Cu")
		(net "P3E_CPU0_PE2_SS_RXP<5>")
	)
	(arc
		(start 71.457566 -32.825436)
		(mid 71.530872 -32.889129)
		(end 71.627746 -32.882332)
		(width 0.127)
		(layer "In2.Cu")
		(net "P3E_CPU0_PE2_SS_RXP<5>")
	)
	(arc
		(start 80.92694 -13.932408)
		(mid 81.065964 -13.233306)
		(end 81.461864 -12.640564)
		(width 0.127)
		(layer "In2.Cu")
		(net "P3E_CPU0_PE2_SS_RXP<5>")
	)
	(arc
		(start 81.90738 -9.298686)
		(mid 81.797838 -8.748924)
		(end 81.486248 -8.28294)
		(width 0.127)
		(layer "In2.Cu")
		(net "P3E_CPU0_PE2_SS_RXP<5>")
	)
	(via
		(at 88.994488 5.165852)
		(size 0.508)
		(drill 0.254)
		(layers "F.Cu" "B.Cu")
		(net "P3E_CPU0_PE2_SS_RXP<4>")
	)
	(segment
		(start 89.427558 10.346182)
		(end 89.427558 10.10539)
		(width 0.127)
		(layer "B.Cu")
		(net "P3E_CPU0_PE2_SS_RXP<4>")
	)
	(segment
		(start 89.327482 7.926324)
		(end 89.327482 7.92607)
		(width 0.127)
		(layer "B.Cu")
		(net "P3E_CPU0_PE2_SS_RXP<4>")
	)
	(segment
		(start 89.32799 7.89305)
		(end 89.32799 7.891526)
		(width 0.127)
		(layer "B.Cu")
		(net "P3E_CPU0_PE2_SS_RXP<4>")
	)
	(segment
		(start 89.326974 7.926832)
		(end 89.327482 7.926324)
		(width 0.127)
		(layer "B.Cu")
		(net "P3E_CPU0_PE2_SS_RXP<4>")
	)
	(segment
		(start 89.326974 7.927594)
		(end 89.326974 7.926832)
		(width 0.127)
		(layer "B.Cu")
		(net "P3E_CPU0_PE2_SS_RXP<4>")
	)
	(segment
		(start 89.321132 8.054594)
		(end 89.326974 7.927594)
		(width 0.127)
		(layer "B.Cu")
		(net "P3E_CPU0_PE2_SS_RXP<4>")
	)
	(segment
		(start 89.328498 7.281926)
		(end 89.357454 6.864096)
		(width 0.127)
		(layer "B.Cu")
		(net "P3E_CPU0_PE2_SS_RXP<4>")
	)
	(segment
		(start 89.329006 7.893304)
		(end 89.32926 7.893304)
		(width 0.127)
		(layer "B.Cu")
		(net "P3E_CPU0_PE2_SS_RXP<4>")
	)
	(segment
		(start 89.327482 7.92607)
		(end 89.329006 7.893304)
		(width 0.127)
		(layer "B.Cu")
		(net "P3E_CPU0_PE2_SS_RXP<4>")
	)
	(segment
		(start 89.427558 10.10539)
		(end 89.320878 8.068564)
		(width 0.127)
		(layer "B.Cu")
		(net "P3E_CPU0_PE2_SS_RXP<4>")
	)
	(segment
		(start 89.357454 6.864096)
		(end 89.357454 5.715)
		(width 0.127)
		(layer "B.Cu")
		(net "P3E_CPU0_PE2_SS_RXP<4>")
	)
	(segment
		(start 89.179908 12.514072)
		(end 89.179908 10.944098)
		(width 0.127)
		(layer "B.Cu")
		(net "P3E_CPU0_PE2_SS_RXP<4>")
	)
	(segment
		(start 89.32926 7.893304)
		(end 89.32799 7.89305)
		(width 0.127)
		(layer "B.Cu")
		(net "P3E_CPU0_PE2_SS_RXP<4>")
	)
	(segment
		(start 89.32799 7.891526)
		(end 89.328498 7.281926)
		(width 0.127)
		(layer "B.Cu")
		(net "P3E_CPU0_PE2_SS_RXP<4>")
	)
	(arc
		(start 89.320878 8.068564)
		(mid 89.321003 8.061579)
		(end 89.321132 8.054594)
		(width 0.127)
		(layer "B.Cu")
		(net "P3E_CPU0_PE2_SS_RXP<4>")
	)
	(arc
		(start 89.179908 10.944098)
		(mid 89.212061 10.782452)
		(end 89.303606 10.645394)
		(width 0.127)
		(layer "B.Cu")
		(net "P3E_CPU0_PE2_SS_RXP<4>")
	)
	(arc
		(start 89.357454 5.715)
		(mid 89.258512 5.385869)
		(end 88.994488 5.165852)
		(width 0.127)
		(layer "B.Cu")
		(net "P3E_CPU0_PE2_SS_RXP<4>")
	)
	(arc
		(start 89.303606 10.645394)
		(mid 89.395333 10.508114)
		(end 89.427558 10.346182)
		(width 0.127)
		(layer "B.Cu")
		(net "P3E_CPU0_PE2_SS_RXP<4>")
	)
	(segment
		(start 67.499738 -26.334974)
		(end 67.050666 -27.008582)
		(width 0.127)
		(layer "In2.Cu")
		(net "P3E_CPU0_PE2_SS_RXP<4>")
	)
	(segment
		(start 76.932536 -13.894816)
		(end 76.93279 -13.894562)
		(width 0.127)
		(layer "In2.Cu")
		(net "P3E_CPU0_PE2_SS_RXP<4>")
	)
	(segment
		(start 76.442316 -12.828778)
		(end 76.525628 -12.911836)
		(width 0.127)
		(layer "In2.Cu")
		(net "P3E_CPU0_PE2_SS_RXP<4>")
	)
	(segment
		(start 68.993512 -24.755094)
		(end 68.763642 -24.761444)
		(width 0.127)
		(layer "In2.Cu")
		(net "P3E_CPU0_PE2_SS_RXP<4>")
	)
	(segment
		(start 76.93279 -14.288008)
		(end 76.812902 -14.967458)
		(width 0.127)
		(layer "In2.Cu")
		(net "P3E_CPU0_PE2_SS_RXP<4>")
	)
	(segment
		(start 76.93406 -7.251446)
		(end 76.93406 -7.2771)
		(width 0.127)
		(layer "In2.Cu")
		(net "P3E_CPU0_PE2_SS_RXP<4>")
	)
	(segment
		(start 67.050666 -27.008582)
		(end 66.9671 -27.359356)
		(width 0.127)
		(layer "In2.Cu")
		(net "P3E_CPU0_PE2_SS_RXP<4>")
	)
	(segment
		(start 81.645252 -3.283458)
		(end 77.2541 -6.358382)
		(width 0.127)
		(layer "In2.Cu")
		(net "P3E_CPU0_PE2_SS_RXP<4>")
	)
	(segment
		(start 76.93279 -13.894562)
		(end 76.93279 -14.288008)
		(width 0.127)
		(layer "In2.Cu")
		(net "P3E_CPU0_PE2_SS_RXP<4>")
	)
	(segment
		(start 67.755008 -25.828244)
		(end 67.761612 -26.058114)
		(width 0.127)
		(layer "In2.Cu")
		(net "P3E_CPU0_PE2_SS_RXP<4>")
	)
	(segment
		(start 67.742562 -32.82569)
		(end 67.62877 -32.882332)
		(width 0.127)
		(layer "In2.Cu")
		(net "P3E_CPU0_PE2_SS_RXP<4>")
	)
	(segment
		(start 77.036422 -6.669532)
		(end 76.93406 -7.251446)
		(width 0.127)
		(layer "In2.Cu")
		(net "P3E_CPU0_PE2_SS_RXP<4>")
	)
	(segment
		(start 87.358474 0.430784)
		(end 82.190082 -3.187446)
		(width 0.127)
		(layer "In2.Cu")
		(net "P3E_CPU0_PE2_SS_RXP<4>")
	)
	(segment
		(start 68.502022 -25.038304)
		(end 68.508372 -25.268174)
		(width 0.127)
		(layer "In2.Cu")
		(net "P3E_CPU0_PE2_SS_RXP<4>")
	)
	(segment
		(start 76.702412 -7.836408)
		(end 76.5683 -7.97052)
		(width 0.127)
		(layer "In2.Cu")
		(net "P3E_CPU0_PE2_SS_RXP<4>")
	)
	(segment
		(start 82.190082 -3.187446)
		(end 81.645252 -3.283204)
		(width 0.127)
		(layer "In2.Cu")
		(net "P3E_CPU0_PE2_SS_RXP<4>")
	)
	(segment
		(start 68.508372 -25.268174)
		(end 68.246498 -25.545034)
		(width 0.127)
		(layer "In2.Cu")
		(net "P3E_CPU0_PE2_SS_RXP<4>")
	)
	(segment
		(start 88.97747 3.385312)
		(end 87.358474 0.430784)
		(width 0.127)
		(layer "In2.Cu")
		(net "P3E_CPU0_PE2_SS_RXP<4>")
	)
	(segment
		(start 66.9671 -27.359356)
		(end 66.9671 -27.731974)
		(width 0.127)
		(layer "In2.Cu")
		(net "P3E_CPU0_PE2_SS_RXP<4>")
	)
	(segment
		(start 76.812902 -14.967458)
		(end 72.717914 -20.815808)
		(width 0.127)
		(layer "In2.Cu")
		(net "P3E_CPU0_PE2_SS_RXP<4>")
	)
	(segment
		(start 75.946254 -9.472676)
		(end 75.946254 -11.63066)
		(width 0.127)
		(layer "In2.Cu")
		(net "P3E_CPU0_PE2_SS_RXP<4>")
	)
	(segment
		(start 81.645252 -3.283204)
		(end 81.645252 -3.283458)
		(width 0.127)
		(layer "In2.Cu")
		(net "P3E_CPU0_PE2_SS_RXP<4>")
	)
	(segment
		(start 68.246498 -25.545034)
		(end 68.016882 -25.551384)
		(width 0.127)
		(layer "In2.Cu")
		(net "P3E_CPU0_PE2_SS_RXP<4>")
	)
	(segment
		(start 72.717914 -20.815808)
		(end 68.993512 -24.755094)
		(width 0.127)
		(layer "In2.Cu")
		(net "P3E_CPU0_PE2_SS_RXP<4>")
	)
	(segment
		(start 67.62877 -32.882332)
		(end 67.628516 -32.882332)
		(width 0.127)
		(layer "In2.Cu")
		(net "P3E_CPU0_PE2_SS_RXP<4>")
	)
	(segment
		(start 68.016882 -25.551384)
		(end 67.755008 -25.828244)
		(width 0.127)
		(layer "In2.Cu")
		(net "P3E_CPU0_PE2_SS_RXP<4>")
	)
	(segment
		(start 67.761612 -26.058114)
		(end 67.499738 -26.334974)
		(width 0.127)
		(layer "In2.Cu")
		(net "P3E_CPU0_PE2_SS_RXP<4>")
	)
	(segment
		(start 68.763642 -24.761444)
		(end 68.502022 -25.038304)
		(width 0.127)
		(layer "In2.Cu")
		(net "P3E_CPU0_PE2_SS_RXP<4>")
	)
	(segment
		(start 77.2541 -6.358382)
		(end 77.036422 -6.669532)
		(width 0.127)
		(layer "In2.Cu")
		(net "P3E_CPU0_PE2_SS_RXP<4>")
	)
	(arc
		(start 67.916806 -29.672534)
		(mid 67.77921 -30.995924)
		(end 67.970654 -32.31261)
		(width 0.127)
		(layer "In2.Cu")
		(net "P3E_CPU0_PE2_SS_RXP<4>")
	)
	(arc
		(start 76.5683 -7.97052)
		(mid 76.107902 -8.659743)
		(end 75.946254 -9.472676)
		(width 0.127)
		(layer "In2.Cu")
		(net "P3E_CPU0_PE2_SS_RXP<4>")
	)
	(arc
		(start 88.994488 5.165852)
		(mid 89.269654 5.012447)
		(end 89.372948 4.714748)
		(width 0.127)
		(layer "In2.Cu")
		(net "P3E_CPU0_PE2_SS_RXP<4>")
	)
	(arc
		(start 89.372948 4.714748)
		(mid 89.245998 4.028971)
		(end 88.97747 3.385312)
		(width 0.127)
		(layer "In2.Cu")
		(net "P3E_CPU0_PE2_SS_RXP<4>")
	)
	(arc
		(start 67.970654 -32.31261)
		(mid 67.948545 -32.610042)
		(end 67.742562 -32.82569)
		(width 0.127)
		(layer "In2.Cu")
		(net "P3E_CPU0_PE2_SS_RXP<4>")
	)
	(arc
		(start 67.458336 -32.825436)
		(mid 67.269326 -32.447437)
		(end 67.079622 -32.069786)
		(width 0.127)
		(layer "In2.Cu")
		(net "P3E_CPU0_PE2_SS_RXP<4>")
	)
	(arc
		(start 67.628516 -32.882332)
		(mid 67.531642 -32.889129)
		(end 67.458336 -32.825436)
		(width 0.127)
		(layer "In2.Cu")
		(net "P3E_CPU0_PE2_SS_RXP<4>")
	)
	(arc
		(start 75.946254 -11.63066)
		(mid 76.075148 -12.279034)
		(end 76.442316 -12.828778)
		(width 0.127)
		(layer "In2.Cu")
		(net "P3E_CPU0_PE2_SS_RXP<4>")
	)
	(arc
		(start 67.649852 -28.854654)
		(mid 67.897107 -29.22647)
		(end 67.916806 -29.672534)
		(width 0.127)
		(layer "In2.Cu")
		(net "P3E_CPU0_PE2_SS_RXP<4>")
	)
	(arc
		(start 66.9671 -27.731974)
		(mid 67.219977 -28.347137)
		(end 67.649852 -28.854654)
		(width 0.127)
		(layer "In2.Cu")
		(net "P3E_CPU0_PE2_SS_RXP<4>")
	)
	(arc
		(start 76.525628 -12.911836)
		(mid 76.826837 -13.36286)
		(end 76.932536 -13.894816)
		(width 0.127)
		(layer "In2.Cu")
		(net "P3E_CPU0_PE2_SS_RXP<4>")
	)
	(arc
		(start 76.93406 -7.2771)
		(mid 76.873852 -7.579786)
		(end 76.702412 -7.836408)
		(width 0.127)
		(layer "In2.Cu")
		(net "P3E_CPU0_PE2_SS_RXP<4>")
	)
	(via
		(at 86.403688 5.165852)
		(size 0.508)
		(drill 0.254)
		(layers "F.Cu" "B.Cu")
		(net "P3E_CPU0_PE2_SS_RXP<3>")
	)
	(segment
		(start 86.723474 7.776464)
		(end 86.723474 7.77621)
		(width 0.127)
		(layer "B.Cu")
		(net "P3E_CPU0_PE2_SS_RXP<3>")
	)
	(segment
		(start 86.73084 7.63524)
		(end 86.759288 6.931152)
		(width 0.127)
		(layer "B.Cu")
		(net "P3E_CPU0_PE2_SS_RXP<3>")
	)
	(segment
		(start 86.723474 7.77621)
		(end 86.73084 7.63524)
		(width 0.127)
		(layer "B.Cu")
		(net "P3E_CPU0_PE2_SS_RXP<3>")
	)
	(segment
		(start 87.027512 10.49274)
		(end 87.027512 10.10539)
		(width 0.127)
		(layer "B.Cu")
		(net "P3E_CPU0_PE2_SS_RXP<3>")
	)
	(segment
		(start 86.759288 6.931152)
		(end 86.759288 5.775452)
		(width 0.127)
		(layer "B.Cu")
		(net "P3E_CPU0_PE2_SS_RXP<3>")
	)
	(segment
		(start 87.027512 10.10539)
		(end 86.772242 8.714486)
		(width 0.127)
		(layer "B.Cu")
		(net "P3E_CPU0_PE2_SS_RXP<3>")
	)
	(segment
		(start 86.779862 12.514072)
		(end 86.779862 11.090656)
		(width 0.127)
		(layer "B.Cu")
		(net "P3E_CPU0_PE2_SS_RXP<3>")
	)
	(arc
		(start 86.772242 8.714486)
		(mid 86.736552 8.246063)
		(end 86.723474 7.776464)
		(width 0.127)
		(layer "B.Cu")
		(net "P3E_CPU0_PE2_SS_RXP<3>")
	)
	(arc
		(start 86.779862 11.090656)
		(mid 86.812015 10.92901)
		(end 86.90356 10.791952)
		(width 0.127)
		(layer "B.Cu")
		(net "P3E_CPU0_PE2_SS_RXP<3>")
	)
	(arc
		(start 86.90356 10.791952)
		(mid 86.995287 10.654672)
		(end 87.027512 10.49274)
		(width 0.127)
		(layer "B.Cu")
		(net "P3E_CPU0_PE2_SS_RXP<3>")
	)
	(arc
		(start 86.759288 5.775452)
		(mid 86.663887 5.422589)
		(end 86.403688 5.165852)
		(width 0.127)
		(layer "B.Cu")
		(net "P3E_CPU0_PE2_SS_RXP<3>")
	)
	(segment
		(start 61.62802 -32.882332)
		(end 61.627766 -32.882332)
		(width 0.127)
		(layer "In2.Cu")
		(net "P3E_CPU0_PE2_SS_RXP<3>")
	)
	(segment
		(start 74.211434 -4.468114)
		(end 73.042272 -6.137656)
		(width 0.127)
		(layer "In2.Cu")
		(net "P3E_CPU0_PE2_SS_RXP<3>")
	)
	(segment
		(start 72.933814 -6.753606)
		(end 72.933814 -6.88721)
		(width 0.127)
		(layer "In2.Cu")
		(net "P3E_CPU0_PE2_SS_RXP<3>")
	)
	(segment
		(start 84.154518 0.519176)
		(end 81.954624 -1.021334)
		(width 0.127)
		(layer "In2.Cu")
		(net "P3E_CPU0_PE2_SS_RXP<3>")
	)
	(segment
		(start 62.251844 -25.906222)
		(end 62.023752 -25.877012)
		(width 0.127)
		(layer "In2.Cu")
		(net "P3E_CPU0_PE2_SS_RXP<3>")
	)
	(segment
		(start 63.111634 -25.240742)
		(end 62.883542 -25.211786)
		(width 0.127)
		(layer "In2.Cu")
		(net "P3E_CPU0_PE2_SS_RXP<3>")
	)
	(segment
		(start 73.042272 -6.137656)
		(end 72.933814 -6.753606)
		(width 0.127)
		(layer "In2.Cu")
		(net "P3E_CPU0_PE2_SS_RXP<3>")
	)
	(segment
		(start 72.932036 -13.894816)
		(end 72.93229 -13.894562)
		(width 0.127)
		(layer "In2.Cu")
		(net "P3E_CPU0_PE2_SS_RXP<3>")
	)
	(segment
		(start 61.741812 -32.82569)
		(end 61.62802 -32.882332)
		(width 0.127)
		(layer "In2.Cu")
		(net "P3E_CPU0_PE2_SS_RXP<3>")
	)
	(segment
		(start 61.722508 -26.110184)
		(end 61.693298 -26.338276)
		(width 0.127)
		(layer "In2.Cu")
		(net "P3E_CPU0_PE2_SS_RXP<3>")
	)
	(segment
		(start 72.93229 -13.894562)
		(end 72.93229 -14.830806)
		(width 0.127)
		(layer "In2.Cu")
		(net "P3E_CPU0_PE2_SS_RXP<3>")
	)
	(segment
		(start 86.67369 4.284218)
		(end 86.286086 3.561842)
		(width 0.127)
		(layer "In2.Cu")
		(net "P3E_CPU0_PE2_SS_RXP<3>")
	)
	(segment
		(start 62.553088 -25.67305)
		(end 62.251844 -25.906222)
		(width 0.127)
		(layer "In2.Cu")
		(net "P3E_CPU0_PE2_SS_RXP<3>")
	)
	(segment
		(start 78.184502 -1.685798)
		(end 74.211434 -4.468114)
		(width 0.127)
		(layer "In2.Cu")
		(net "P3E_CPU0_PE2_SS_RXP<3>")
	)
	(segment
		(start 62.582298 -25.444958)
		(end 62.553088 -25.67305)
		(width 0.127)
		(layer "In2.Cu")
		(net "P3E_CPU0_PE2_SS_RXP<3>")
	)
	(segment
		(start 81.954624 -1.021334)
		(end 78.184502 -1.685798)
		(width 0.127)
		(layer "In2.Cu")
		(net "P3E_CPU0_PE2_SS_RXP<3>")
	)
	(segment
		(start 72.354186 -15.953232)
		(end 69.620384 -20.20316)
		(width 0.127)
		(layer "In2.Cu")
		(net "P3E_CPU0_PE2_SS_RXP<3>")
	)
	(segment
		(start 61.457586 -32.825436)
		(end 61.080142 -32.069786)
		(width 0.127)
		(layer "In2.Cu")
		(net "P3E_CPU0_PE2_SS_RXP<3>")
	)
	(segment
		(start 72.93229 -14.830806)
		(end 72.453754 -15.76705)
		(width 0.127)
		(layer "In2.Cu")
		(net "P3E_CPU0_PE2_SS_RXP<3>")
	)
	(segment
		(start 60.91682 -27.522424)
		(end 60.91682 -27.525472)
		(width 0.127)
		(layer "In2.Cu")
		(net "P3E_CPU0_PE2_SS_RXP<3>")
	)
	(segment
		(start 72.93356 -6.96468)
		(end 72.93356 -7.2771)
		(width 0.127)
		(layer "In2.Cu")
		(net "P3E_CPU0_PE2_SS_RXP<3>")
	)
	(segment
		(start 62.023752 -25.877012)
		(end 61.722508 -26.110184)
		(width 0.127)
		(layer "In2.Cu")
		(net "P3E_CPU0_PE2_SS_RXP<3>")
	)
	(segment
		(start 71.945754 -9.472676)
		(end 71.945754 -11.63066)
		(width 0.127)
		(layer "In2.Cu")
		(net "P3E_CPU0_PE2_SS_RXP<3>")
	)
	(segment
		(start 69.620384 -20.20316)
		(end 63.111634 -25.240742)
		(width 0.127)
		(layer "In2.Cu")
		(net "P3E_CPU0_PE2_SS_RXP<3>")
	)
	(segment
		(start 61.080142 -26.813002)
		(end 60.903866 -27.195526)
		(width 0.127)
		(layer "In2.Cu")
		(net "P3E_CPU0_PE2_SS_RXP<3>")
	)
	(segment
		(start 60.91174 -27.395678)
		(end 60.91682 -27.522424)
		(width 0.127)
		(layer "In2.Cu")
		(net "P3E_CPU0_PE2_SS_RXP<3>")
	)
	(segment
		(start 60.913772 -27.528774)
		(end 60.975494 -27.768804)
		(width 0.127)
		(layer "In2.Cu")
		(net "P3E_CPU0_PE2_SS_RXP<3>")
	)
	(segment
		(start 61.693298 -26.338276)
		(end 61.080142 -26.813002)
		(width 0.127)
		(layer "In2.Cu")
		(net "P3E_CPU0_PE2_SS_RXP<3>")
	)
	(segment
		(start 60.903866 -27.195526)
		(end 60.91174 -27.395678)
		(width 0.127)
		(layer "In2.Cu")
		(net "P3E_CPU0_PE2_SS_RXP<3>")
	)
	(segment
		(start 72.453754 -15.76705)
		(end 72.354186 -15.953232)
		(width 0.127)
		(layer "In2.Cu")
		(net "P3E_CPU0_PE2_SS_RXP<3>")
	)
	(segment
		(start 60.91682 -27.525472)
		(end 60.913772 -27.52852)
		(width 0.127)
		(layer "In2.Cu")
		(net "P3E_CPU0_PE2_SS_RXP<3>")
	)
	(segment
		(start 72.933814 -6.88721)
		(end 72.93356 -6.96468)
		(width 0.127)
		(layer "In2.Cu")
		(net "P3E_CPU0_PE2_SS_RXP<3>")
	)
	(segment
		(start 60.913772 -27.52852)
		(end 60.913772 -27.528774)
		(width 0.127)
		(layer "In2.Cu")
		(net "P3E_CPU0_PE2_SS_RXP<3>")
	)
	(segment
		(start 86.286086 3.561842)
		(end 84.154518 0.519176)
		(width 0.127)
		(layer "In2.Cu")
		(net "P3E_CPU0_PE2_SS_RXP<3>")
	)
	(segment
		(start 62.883542 -25.211786)
		(end 62.582298 -25.444958)
		(width 0.127)
		(layer "In2.Cu")
		(net "P3E_CPU0_PE2_SS_RXP<3>")
	)
	(segment
		(start 72.441816 -12.828778)
		(end 72.525128 -12.911836)
		(width 0.127)
		(layer "In2.Cu")
		(net "P3E_CPU0_PE2_SS_RXP<3>")
	)
	(segment
		(start 72.701912 -7.836408)
		(end 72.5678 -7.97052)
		(width 0.127)
		(layer "In2.Cu")
		(net "P3E_CPU0_PE2_SS_RXP<3>")
	)
	(arc
		(start 86.782148 4.714748)
		(mid 86.781656 4.687938)
		(end 86.78037 4.661154)
		(width 0.127)
		(layer "In2.Cu")
		(net "P3E_CPU0_PE2_SS_RXP<3>")
	)
	(arc
		(start 61.969904 -32.31261)
		(mid 61.947795 -32.610042)
		(end 61.741812 -32.82569)
		(width 0.127)
		(layer "In2.Cu")
		(net "P3E_CPU0_PE2_SS_RXP<3>")
	)
	(arc
		(start 60.975494 -27.768804)
		(mid 61.229184 -28.36329)
		(end 61.649102 -28.854654)
		(width 0.127)
		(layer "In2.Cu")
		(net "P3E_CPU0_PE2_SS_RXP<3>")
	)
	(arc
		(start 72.93356 -7.2771)
		(mid 72.873352 -7.579786)
		(end 72.701912 -7.836408)
		(width 0.127)
		(layer "In2.Cu")
		(net "P3E_CPU0_PE2_SS_RXP<3>")
	)
	(arc
		(start 86.78037 4.661154)
		(mid 86.747555 4.466876)
		(end 86.67369 4.284218)
		(width 0.127)
		(layer "In2.Cu")
		(net "P3E_CPU0_PE2_SS_RXP<3>")
	)
	(arc
		(start 72.525128 -12.911836)
		(mid 72.826337 -13.36286)
		(end 72.932036 -13.894816)
		(width 0.127)
		(layer "In2.Cu")
		(net "P3E_CPU0_PE2_SS_RXP<3>")
	)
	(arc
		(start 61.649102 -28.854654)
		(mid 61.896357 -29.22647)
		(end 61.916056 -29.672534)
		(width 0.127)
		(layer "In2.Cu")
		(net "P3E_CPU0_PE2_SS_RXP<3>")
	)
	(arc
		(start 71.945754 -11.63066)
		(mid 72.074648 -12.279034)
		(end 72.441816 -12.828778)
		(width 0.127)
		(layer "In2.Cu")
		(net "P3E_CPU0_PE2_SS_RXP<3>")
	)
	(arc
		(start 72.5678 -7.97052)
		(mid 72.107402 -8.659743)
		(end 71.945754 -9.472676)
		(width 0.127)
		(layer "In2.Cu")
		(net "P3E_CPU0_PE2_SS_RXP<3>")
	)
	(arc
		(start 61.916056 -29.672534)
		(mid 61.77846 -30.995924)
		(end 61.969904 -32.31261)
		(width 0.127)
		(layer "In2.Cu")
		(net "P3E_CPU0_PE2_SS_RXP<3>")
	)
	(arc
		(start 61.627766 -32.882332)
		(mid 61.530892 -32.889129)
		(end 61.457586 -32.825436)
		(width 0.127)
		(layer "In2.Cu")
		(net "P3E_CPU0_PE2_SS_RXP<3>")
	)
	(arc
		(start 86.403688 5.165852)
		(mid 86.678854 5.012447)
		(end 86.782148 4.714748)
		(width 0.127)
		(layer "In2.Cu")
		(net "P3E_CPU0_PE2_SS_RXP<3>")
	)
	(via
		(at 83.812888 5.165852)
		(size 0.508)
		(drill 0.254)
		(layers "F.Cu" "B.Cu")
		(net "P3E_CPU0_PE2_SS_RXP<2>")
	)
	(segment
		(start 84.627466 10.10539)
		(end 84.126578 8.012938)
		(width 0.127)
		(layer "B.Cu")
		(net "P3E_CPU0_PE2_SS_RXP<2>")
	)
	(segment
		(start 84.168488 6.931152)
		(end 84.168488 5.775452)
		(width 0.127)
		(layer "B.Cu")
		(net "P3E_CPU0_PE2_SS_RXP<2>")
	)
	(segment
		(start 84.119466 7.982966)
		(end 84.119466 7.982204)
		(width 0.127)
		(layer "B.Cu")
		(net "P3E_CPU0_PE2_SS_RXP<2>")
	)
	(segment
		(start 84.119466 7.982204)
		(end 84.168488 6.931152)
		(width 0.127)
		(layer "B.Cu")
		(net "P3E_CPU0_PE2_SS_RXP<2>")
	)
	(segment
		(start 84.627466 10.447782)
		(end 84.627466 10.10539)
		(width 0.127)
		(layer "B.Cu")
		(net "P3E_CPU0_PE2_SS_RXP<2>")
	)
	(segment
		(start 84.379816 12.514072)
		(end 84.379816 11.04519)
		(width 0.127)
		(layer "B.Cu")
		(net "P3E_CPU0_PE2_SS_RXP<2>")
	)
	(segment
		(start 84.503768 10.746486)
		(end 84.504022 10.746232)
		(width 0.127)
		(layer "B.Cu")
		(net "P3E_CPU0_PE2_SS_RXP<2>")
	)
	(arc
		(start 84.168488 5.775452)
		(mid 84.073087 5.422589)
		(end 83.812888 5.165852)
		(width 0.127)
		(layer "B.Cu")
		(net "P3E_CPU0_PE2_SS_RXP<2>")
	)
	(arc
		(start 84.126578 8.012938)
		(mid 84.123016 7.997953)
		(end 84.119466 7.982966)
		(width 0.127)
		(layer "B.Cu")
		(net "P3E_CPU0_PE2_SS_RXP<2>")
	)
	(arc
		(start 84.379816 11.04519)
		(mid 84.412072 10.8835)
		(end 84.503768 10.746486)
		(width 0.127)
		(layer "B.Cu")
		(net "P3E_CPU0_PE2_SS_RXP<2>")
	)
	(arc
		(start 84.504022 10.746232)
		(mid 84.595408 10.609274)
		(end 84.627466 10.447782)
		(width 0.127)
		(layer "B.Cu")
		(net "P3E_CPU0_PE2_SS_RXP<2>")
	)
	(segment
		(start 68.56857 -7.97052)
		(end 68.702682 -7.836408)
		(width 0.127)
		(layer "In2.Cu")
		(net "P3E_CPU0_PE2_SS_RXP<2>")
	)
	(segment
		(start 58.37301 -25.354534)
		(end 58.600594 -25.38857)
		(width 0.127)
		(layer "In2.Cu")
		(net "P3E_CPU0_PE2_SS_RXP<2>")
	)
	(segment
		(start 59.4741 -24.741632)
		(end 66.411602 -19.605752)
		(width 0.127)
		(layer "In2.Cu")
		(net "P3E_CPU0_PE2_SS_RXP<2>")
	)
	(segment
		(start 57.62879 -32.882332)
		(end 57.742582 -32.82569)
		(width 0.127)
		(layer "In2.Cu")
		(net "P3E_CPU0_PE2_SS_RXP<2>")
	)
	(segment
		(start 56.965088 -27.723592)
		(end 56.98744 -27.309826)
		(width 0.127)
		(layer "In2.Cu")
		(net "P3E_CPU0_PE2_SS_RXP<2>")
	)
	(segment
		(start 84.115656 4.06273)
		(end 84.186522 4.46405)
		(width 0.127)
		(layer "In2.Cu")
		(net "P3E_CPU0_PE2_SS_RXP<2>")
	)
	(segment
		(start 68.93433 -6.96468)
		(end 68.934584 -6.88721)
		(width 0.127)
		(layer "In2.Cu")
		(net "P3E_CPU0_PE2_SS_RXP<2>")
	)
	(segment
		(start 75.892914 -0.083312)
		(end 81.005426 0.817626)
		(width 0.127)
		(layer "In2.Cu")
		(net "P3E_CPU0_PE2_SS_RXP<2>")
	)
	(segment
		(start 68.934584 -6.88721)
		(end 68.934584 -6.753606)
		(width 0.127)
		(layer "In2.Cu")
		(net "P3E_CPU0_PE2_SS_RXP<2>")
	)
	(segment
		(start 58.032904 -25.808686)
		(end 58.06694 -25.581356)
		(width 0.127)
		(layer "In2.Cu")
		(net "P3E_CPU0_PE2_SS_RXP<2>")
	)
	(segment
		(start 59.24677 -24.70785)
		(end 59.4741 -24.741632)
		(width 0.127)
		(layer "In2.Cu")
		(net "P3E_CPU0_PE2_SS_RXP<2>")
	)
	(segment
		(start 84.186522 4.46405)
		(end 84.191348 4.714748)
		(width 0.127)
		(layer "In2.Cu")
		(net "P3E_CPU0_PE2_SS_RXP<2>")
	)
	(segment
		(start 68.93433 -7.2771)
		(end 68.93433 -6.96468)
		(width 0.127)
		(layer "In2.Cu")
		(net "P3E_CPU0_PE2_SS_RXP<2>")
	)
	(segment
		(start 58.9407 -24.934418)
		(end 59.24677 -24.70785)
		(width 0.127)
		(layer "In2.Cu")
		(net "P3E_CPU0_PE2_SS_RXP<2>")
	)
	(segment
		(start 58.06694 -25.581356)
		(end 58.37301 -25.354534)
		(width 0.127)
		(layer "In2.Cu")
		(net "P3E_CPU0_PE2_SS_RXP<2>")
	)
	(segment
		(start 68.934584 -6.753606)
		(end 69.011038 -6.319012)
		(width 0.127)
		(layer "In2.Cu")
		(net "P3E_CPU0_PE2_SS_RXP<2>")
	)
	(segment
		(start 57.124346 -26.929588)
		(end 57.54751 -26.167842)
		(width 0.127)
		(layer "In2.Cu")
		(net "P3E_CPU0_PE2_SS_RXP<2>")
	)
	(segment
		(start 81.005426 0.817626)
		(end 82.649822 1.969008)
		(width 0.127)
		(layer "In2.Cu")
		(net "P3E_CPU0_PE2_SS_RXP<2>")
	)
	(segment
		(start 57.59831 -26.130504)
		(end 58.032904 -25.808686)
		(width 0.127)
		(layer "In2.Cu")
		(net "P3E_CPU0_PE2_SS_RXP<2>")
	)
	(segment
		(start 82.649822 1.969008)
		(end 84.115656 4.06273)
		(width 0.127)
		(layer "In2.Cu")
		(net "P3E_CPU0_PE2_SS_RXP<2>")
	)
	(segment
		(start 58.600594 -25.38857)
		(end 58.906664 -25.161748)
		(width 0.127)
		(layer "In2.Cu")
		(net "P3E_CPU0_PE2_SS_RXP<2>")
	)
	(segment
		(start 69.011038 -6.319012)
		(end 70.957948 -3.538728)
		(width 0.127)
		(layer "In2.Cu")
		(net "P3E_CPU0_PE2_SS_RXP<2>")
	)
	(segment
		(start 57.54751 -26.167842)
		(end 57.59831 -26.130504)
		(width 0.127)
		(layer "In2.Cu")
		(net "P3E_CPU0_PE2_SS_RXP<2>")
	)
	(segment
		(start 68.525898 -12.911836)
		(end 68.442586 -12.828778)
		(width 0.127)
		(layer "In2.Cu")
		(net "P3E_CPU0_PE2_SS_RXP<2>")
	)
	(segment
		(start 58.906664 -25.161748)
		(end 58.9407 -24.934418)
		(width 0.127)
		(layer "In2.Cu")
		(net "P3E_CPU0_PE2_SS_RXP<2>")
	)
	(segment
		(start 67.946524 -11.63066)
		(end 67.946524 -9.472676)
		(width 0.127)
		(layer "In2.Cu")
		(net "P3E_CPU0_PE2_SS_RXP<2>")
	)
	(segment
		(start 68.556632 -16.387318)
		(end 68.932806 -13.873988)
		(width 0.127)
		(layer "In2.Cu")
		(net "P3E_CPU0_PE2_SS_RXP<2>")
	)
	(segment
		(start 68.421758 -16.712692)
		(end 68.556632 -16.387318)
		(width 0.127)
		(layer "In2.Cu")
		(net "P3E_CPU0_PE2_SS_RXP<2>")
	)
	(segment
		(start 57.628536 -32.882332)
		(end 57.62879 -32.882332)
		(width 0.127)
		(layer "In2.Cu")
		(net "P3E_CPU0_PE2_SS_RXP<2>")
	)
	(segment
		(start 56.98744 -27.309826)
		(end 57.124346 -26.929588)
		(width 0.127)
		(layer "In2.Cu")
		(net "P3E_CPU0_PE2_SS_RXP<2>")
	)
	(segment
		(start 70.957948 -3.538728)
		(end 75.892914 -0.083312)
		(width 0.127)
		(layer "In2.Cu")
		(net "P3E_CPU0_PE2_SS_RXP<2>")
	)
	(segment
		(start 66.411602 -19.605752)
		(end 68.421758 -16.712692)
		(width 0.127)
		(layer "In2.Cu")
		(net "P3E_CPU0_PE2_SS_RXP<2>")
	)
	(arc
		(start 68.442586 -12.828778)
		(mid 68.075317 -12.279076)
		(end 67.946524 -11.63066)
		(width 0.127)
		(layer "In2.Cu")
		(net "P3E_CPU0_PE2_SS_RXP<2>")
	)
	(arc
		(start 57.079642 -32.069786)
		(mid 57.269346 -32.447437)
		(end 57.458356 -32.825436)
		(width 0.127)
		(layer "In2.Cu")
		(net "P3E_CPU0_PE2_SS_RXP<2>")
	)
	(arc
		(start 68.932806 -13.873988)
		(mid 68.823145 -13.353248)
		(end 68.525898 -12.911836)
		(width 0.127)
		(layer "In2.Cu")
		(net "P3E_CPU0_PE2_SS_RXP<2>")
	)
	(arc
		(start 57.742582 -32.82569)
		(mid 57.948469 -32.609999)
		(end 57.970674 -32.31261)
		(width 0.127)
		(layer "In2.Cu")
		(net "P3E_CPU0_PE2_SS_RXP<2>")
	)
	(arc
		(start 67.946524 -9.472676)
		(mid 68.108189 -8.659751)
		(end 68.56857 -7.97052)
		(width 0.127)
		(layer "In2.Cu")
		(net "P3E_CPU0_PE2_SS_RXP<2>")
	)
	(arc
		(start 57.970674 -32.31261)
		(mid 57.779177 -30.995925)
		(end 57.916826 -29.672534)
		(width 0.127)
		(layer "In2.Cu")
		(net "P3E_CPU0_PE2_SS_RXP<2>")
	)
	(arc
		(start 84.191348 4.714748)
		(mid 84.088206 5.012575)
		(end 83.812888 5.165852)
		(width 0.127)
		(layer "In2.Cu")
		(net "P3E_CPU0_PE2_SS_RXP<2>")
	)
	(arc
		(start 57.916826 -29.672534)
		(mid 57.897043 -29.226498)
		(end 57.649872 -28.854654)
		(width 0.127)
		(layer "In2.Cu")
		(net "P3E_CPU0_PE2_SS_RXP<2>")
	)
	(arc
		(start 57.649872 -28.854654)
		(mid 57.217735 -28.343454)
		(end 56.965088 -27.723592)
		(width 0.127)
		(layer "In2.Cu")
		(net "P3E_CPU0_PE2_SS_RXP<2>")
	)
	(arc
		(start 68.702682 -7.836408)
		(mid 68.874145 -7.579795)
		(end 68.93433 -7.2771)
		(width 0.127)
		(layer "In2.Cu")
		(net "P3E_CPU0_PE2_SS_RXP<2>")
	)
	(arc
		(start 57.458356 -32.825436)
		(mid 57.531662 -32.889129)
		(end 57.628536 -32.882332)
		(width 0.127)
		(layer "In2.Cu")
		(net "P3E_CPU0_PE2_SS_RXP<2>")
	)
	(via
		(at 128.70434 5.206492)
		(size 0.508)
		(drill 0.254)
		(layers "F.Cu" "B.Cu")
		(net "P3E_CPU0_PE2_SS_RXP<15>")
	)
	(segment
		(start 129.05994 7.8232)
		(end 129.05994 5.816092)
		(width 0.127)
		(layer "B.Cu")
		(net "P3E_CPU0_PE2_SS_RXP<15>")
	)
	(segment
		(start 127.622808 10.581132)
		(end 127.622808 9.986772)
		(width 0.127)
		(layer "B.Cu")
		(net "P3E_CPU0_PE2_SS_RXP<15>")
	)
	(segment
		(start 127.375158 12.615672)
		(end 127.375158 11.179048)
		(width 0.127)
		(layer "B.Cu")
		(net "P3E_CPU0_PE2_SS_RXP<15>")
	)
	(arc
		(start 128.775206 8.322818)
		(mid 128.98378 8.110736)
		(end 129.05994 7.8232)
		(width 0.127)
		(layer "B.Cu")
		(net "P3E_CPU0_PE2_SS_RXP<15>")
	)
	(arc
		(start 127.498856 10.880344)
		(mid 127.590583 10.743064)
		(end 127.622808 10.581132)
		(width 0.127)
		(layer "B.Cu")
		(net "P3E_CPU0_PE2_SS_RXP<15>")
	)
	(arc
		(start 127.375158 11.179048)
		(mid 127.407311 11.017402)
		(end 127.498856 10.880344)
		(width 0.127)
		(layer "B.Cu")
		(net "P3E_CPU0_PE2_SS_RXP<15>")
	)
	(arc
		(start 129.05994 5.816092)
		(mid 128.964539 5.463229)
		(end 128.70434 5.206492)
		(width 0.127)
		(layer "B.Cu")
		(net "P3E_CPU0_PE2_SS_RXP<15>")
	)
	(arc
		(start 127.622808 9.986772)
		(mid 127.824723 9.319495)
		(end 128.230122 8.752332)
		(width 0.127)
		(layer "B.Cu")
		(net "P3E_CPU0_PE2_SS_RXP<15>")
	)
	(arc
		(start 128.230122 8.752332)
		(mid 128.488299 8.519347)
		(end 128.775206 8.322818)
		(width 0.127)
		(layer "B.Cu")
		(net "P3E_CPU0_PE2_SS_RXP<15>")
	)
	(segment
		(start 112.903 -27.40279)
		(end 112.903 -27.183334)
		(width 0.127)
		(layer "In2.Cu")
		(net "P3E_CPU0_PE2_SS_RXP<15>")
	)
	(segment
		(start 112.899952 -27.711908)
		(end 112.899952 -27.40279)
		(width 0.127)
		(layer "In2.Cu")
		(net "P3E_CPU0_PE2_SS_RXP<15>")
	)
	(segment
		(start 114.273076 -21.046186)
		(end 120.59539 -12.016232)
		(width 0.127)
		(layer "In2.Cu")
		(net "P3E_CPU0_PE2_SS_RXP<15>")
	)
	(segment
		(start 112.75695 -28.0416)
		(end 112.899952 -27.711908)
		(width 0.127)
		(layer "In2.Cu")
		(net "P3E_CPU0_PE2_SS_RXP<15>")
	)
	(segment
		(start 128.163066 1.608328)
		(end 128.287018 2.311146)
		(width 0.127)
		(layer "In2.Cu")
		(net "P3E_CPU0_PE2_SS_RXP<15>")
	)
	(segment
		(start 112.899952 -27.40279)
		(end 112.903 -27.40279)
		(width 0.127)
		(layer "In2.Cu")
		(net "P3E_CPU0_PE2_SS_RXP<15>")
	)
	(segment
		(start 128.287018 2.311146)
		(end 128.425956 3.100324)
		(width 0.127)
		(layer "In2.Cu")
		(net "P3E_CPU0_PE2_SS_RXP<15>")
	)
	(segment
		(start 112.903 -27.183334)
		(end 112.909604 -27.153362)
		(width 0.127)
		(layer "In2.Cu")
		(net "P3E_CPU0_PE2_SS_RXP<15>")
	)
	(segment
		(start 129.035302 4.87553)
		(end 128.70434 5.206492)
		(width 0.127)
		(layer "In2.Cu")
		(net "P3E_CPU0_PE2_SS_RXP<15>")
	)
	(segment
		(start 112.40008 -33.143952)
		(end 112.399826 -33.143698)
		(width 0.127)
		(layer "In2.Cu")
		(net "P3E_CPU0_PE2_SS_RXP<15>")
	)
	(segment
		(start 112.399826 -33.143698)
		(end 112.286288 -33.087056)
		(width 0.127)
		(layer "In2.Cu")
		(net "P3E_CPU0_PE2_SS_RXP<15>")
	)
	(segment
		(start 128.990852 3.907028)
		(end 129.070354 4.35737)
		(width 0.127)
		(layer "In2.Cu")
		(net "P3E_CPU0_PE2_SS_RXP<15>")
	)
	(segment
		(start 128.425956 3.100324)
		(end 128.990852 3.907028)
		(width 0.127)
		(layer "In2.Cu")
		(net "P3E_CPU0_PE2_SS_RXP<15>")
	)
	(segment
		(start 112.909858 -27.151838)
		(end 114.273076 -21.046186)
		(width 0.127)
		(layer "In2.Cu")
		(net "P3E_CPU0_PE2_SS_RXP<15>")
	)
	(segment
		(start 112.909604 -27.153362)
		(end 112.909858 -27.151838)
		(width 0.127)
		(layer "In2.Cu")
		(net "P3E_CPU0_PE2_SS_RXP<15>")
	)
	(segment
		(start 121.259854 -8.247126)
		(end 128.163066 1.608328)
		(width 0.127)
		(layer "In2.Cu")
		(net "P3E_CPU0_PE2_SS_RXP<15>")
	)
	(segment
		(start 112.079532 -34.070036)
		(end 112.456976 -33.314132)
		(width 0.127)
		(layer "In2.Cu")
		(net "P3E_CPU0_PE2_SS_RXP<15>")
	)
	(segment
		(start 120.59539 -12.016232)
		(end 121.259854 -8.247126)
		(width 0.127)
		(layer "In2.Cu")
		(net "P3E_CPU0_PE2_SS_RXP<15>")
	)
	(segment
		(start 129.070354 4.35737)
		(end 129.0828 4.755642)
		(width 0.127)
		(layer "In2.Cu")
		(net "P3E_CPU0_PE2_SS_RXP<15>")
	)
	(segment
		(start 111.726726 -30.20822)
		(end 111.72698 -30.20822)
		(width 0.127)
		(layer "In2.Cu")
		(net "P3E_CPU0_PE2_SS_RXP<15>")
	)
	(arc
		(start 111.601758 -31.16326)
		(mid 111.573924 -30.936987)
		(end 111.580676 -30.709108)
		(width 0.127)
		(layer "In2.Cu")
		(net "P3E_CPU0_PE2_SS_RXP<15>")
	)
	(arc
		(start 111.866172 -32.274764)
		(mid 111.863334 -31.912216)
		(end 111.746792 -31.568898)
		(width 0.127)
		(layer "In2.Cu")
		(net "P3E_CPU0_PE2_SS_RXP<15>")
	)
	(arc
		(start 111.988346 -29.421836)
		(mid 112.055567 -29.150097)
		(end 112.2045 -28.913074)
		(width 0.127)
		(layer "In2.Cu")
		(net "P3E_CPU0_PE2_SS_RXP<15>")
	)
	(arc
		(start 112.286288 -33.087056)
		(mid 111.944003 -32.749286)
		(end 111.866172 -32.274764)
		(width 0.127)
		(layer "In2.Cu")
		(net "P3E_CPU0_PE2_SS_RXP<15>")
	)
	(arc
		(start 129.0828 4.755642)
		(mid 129.071472 4.82051)
		(end 129.035302 4.87553)
		(width 0.127)
		(layer "In2.Cu")
		(net "P3E_CPU0_PE2_SS_RXP<15>")
	)
	(arc
		(start 112.2045 -28.913074)
		(mid 112.514629 -28.498828)
		(end 112.75695 -28.0416)
		(width 0.127)
		(layer "In2.Cu")
		(net "P3E_CPU0_PE2_SS_RXP<15>")
	)
	(arc
		(start 112.456976 -33.314132)
		(mid 112.463773 -33.217258)
		(end 112.40008 -33.143952)
		(width 0.127)
		(layer "In2.Cu")
		(net "P3E_CPU0_PE2_SS_RXP<15>")
	)
	(arc
		(start 111.717582 -30.222698)
		(mid 111.722172 -30.21547)
		(end 111.726726 -30.20822)
		(width 0.127)
		(layer "In2.Cu")
		(net "P3E_CPU0_PE2_SS_RXP<15>")
	)
	(arc
		(start 111.746792 -31.568898)
		(mid 111.659689 -31.371294)
		(end 111.601758 -31.16326)
		(width 0.127)
		(layer "In2.Cu")
		(net "P3E_CPU0_PE2_SS_RXP<15>")
	)
	(arc
		(start 111.580676 -30.709108)
		(mid 111.628515 -30.460101)
		(end 111.717582 -30.222698)
		(width 0.127)
		(layer "In2.Cu")
		(net "P3E_CPU0_PE2_SS_RXP<15>")
	)
	(arc
		(start 111.72698 -30.20822)
		(mid 111.904494 -29.830598)
		(end 111.988346 -29.421836)
		(width 0.127)
		(layer "In2.Cu")
		(net "P3E_CPU0_PE2_SS_RXP<15>")
	)
	(via
		(at 126.11354 5.206492)
		(size 0.508)
		(drill 0.254)
		(layers "F.Cu" "B.Cu")
		(net "P3E_CPU0_PE2_SS_RXP<14>")
	)
	(segment
		(start 126.467616 6.613906)
		(end 126.46914 6.594856)
		(width 0.127)
		(layer "B.Cu")
		(net "P3E_CPU0_PE2_SS_RXP<14>")
	)
	(segment
		(start 125.099064 10.91819)
		(end 125.099318 10.917936)
		(width 0.127)
		(layer "B.Cu")
		(net "P3E_CPU0_PE2_SS_RXP<14>")
	)
	(segment
		(start 126.449582 7.97052)
		(end 126.449582 7.969504)
		(width 0.127)
		(layer "B.Cu")
		(net "P3E_CPU0_PE2_SS_RXP<14>")
	)
	(segment
		(start 125.222762 10.619486)
		(end 125.222762 9.853676)
		(width 0.127)
		(layer "B.Cu")
		(net "P3E_CPU0_PE2_SS_RXP<14>")
	)
	(segment
		(start 126.42342 7.5692)
		(end 126.467616 6.613906)
		(width 0.127)
		(layer "B.Cu")
		(net "P3E_CPU0_PE2_SS_RXP<14>")
	)
	(segment
		(start 126.449582 7.969504)
		(end 126.448566 7.968488)
		(width 0.127)
		(layer "B.Cu")
		(net "P3E_CPU0_PE2_SS_RXP<14>")
	)
	(segment
		(start 126.46914 6.594856)
		(end 126.46914 5.816092)
		(width 0.127)
		(layer "B.Cu")
		(net "P3E_CPU0_PE2_SS_RXP<14>")
	)
	(segment
		(start 124.975112 12.615672)
		(end 124.975112 11.216894)
		(width 0.127)
		(layer "B.Cu")
		(net "P3E_CPU0_PE2_SS_RXP<14>")
	)
	(segment
		(start 126.448566 7.968488)
		(end 126.42342 7.5692)
		(width 0.127)
		(layer "B.Cu")
		(net "P3E_CPU0_PE2_SS_RXP<14>")
	)
	(arc
		(start 125.099318 10.917936)
		(mid 125.190704 10.780978)
		(end 125.222762 10.619486)
		(width 0.127)
		(layer "B.Cu")
		(net "P3E_CPU0_PE2_SS_RXP<14>")
	)
	(arc
		(start 126.328424 8.383524)
		(mid 126.409368 8.196136)
		(end 126.447804 7.995666)
		(width 0.127)
		(layer "B.Cu")
		(net "P3E_CPU0_PE2_SS_RXP<14>")
	)
	(arc
		(start 126.46914 5.816092)
		(mid 126.373739 5.463229)
		(end 126.11354 5.206492)
		(width 0.127)
		(layer "B.Cu")
		(net "P3E_CPU0_PE2_SS_RXP<14>")
	)
	(arc
		(start 125.222762 9.853676)
		(mid 125.450257 9.119845)
		(end 126.045214 8.633714)
		(width 0.127)
		(layer "B.Cu")
		(net "P3E_CPU0_PE2_SS_RXP<14>")
	)
	(arc
		(start 126.447804 7.995666)
		(mid 126.448779 7.983099)
		(end 126.449582 7.97052)
		(width 0.127)
		(layer "B.Cu")
		(net "P3E_CPU0_PE2_SS_RXP<14>")
	)
	(arc
		(start 126.045214 8.633714)
		(mid 126.207665 8.532222)
		(end 126.328424 8.383524)
		(width 0.127)
		(layer "B.Cu")
		(net "P3E_CPU0_PE2_SS_RXP<14>")
	)
	(arc
		(start 124.975112 11.216894)
		(mid 125.007368 11.055204)
		(end 125.099064 10.91819)
		(width 0.127)
		(layer "B.Cu")
		(net "P3E_CPU0_PE2_SS_RXP<14>")
	)
	(segment
		(start 126.487174 4.50469)
		(end 126.021338 1.86182)
		(width 0.127)
		(layer "In2.Cu")
		(net "P3E_CPU0_PE2_SS_RXP<14>")
	)
	(segment
		(start 108.943902 -27.218386)
		(end 108.943648 -27.218386)
		(width 0.127)
		(layer "In2.Cu")
		(net "P3E_CPU0_PE2_SS_RXP<14>")
	)
	(segment
		(start 125.459744 1.059434)
		(end 122.342656 -3.391662)
		(width 0.127)
		(layer "In2.Cu")
		(net "P3E_CPU0_PE2_SS_RXP<14>")
	)
	(segment
		(start 108.970318 -27.058874)
		(end 108.951776 -27.172158)
		(width 0.127)
		(layer "In2.Cu")
		(net "P3E_CPU0_PE2_SS_RXP<14>")
	)
	(segment
		(start 122.342656 -3.391662)
		(end 119.187976 -7.896098)
		(width 0.127)
		(layer "In2.Cu")
		(net "P3E_CPU0_PE2_SS_RXP<14>")
	)
	(segment
		(start 108.944156 -27.218132)
		(end 108.943902 -27.218386)
		(width 0.127)
		(layer "In2.Cu")
		(net "P3E_CPU0_PE2_SS_RXP<14>")
	)
	(segment
		(start 108.943648 -27.218386)
		(end 108.943394 -27.21864)
		(width 0.127)
		(layer "In2.Cu")
		(net "P3E_CPU0_PE2_SS_RXP<14>")
	)
	(segment
		(start 107.72775 -30.20822)
		(end 107.727496 -30.20822)
		(width 0.127)
		(layer "In2.Cu")
		(net "P3E_CPU0_PE2_SS_RXP<14>")
	)
	(segment
		(start 119.187976 -7.896098)
		(end 118.551706 -11.504168)
		(width 0.127)
		(layer "In2.Cu")
		(net "P3E_CPU0_PE2_SS_RXP<14>")
	)
	(segment
		(start 126.021338 1.86182)
		(end 125.459744 1.059434)
		(width 0.127)
		(layer "In2.Cu")
		(net "P3E_CPU0_PE2_SS_RXP<14>")
	)
	(segment
		(start 108.90504 -27.701748)
		(end 108.75772 -28.0416)
		(width 0.127)
		(layer "In2.Cu")
		(net "P3E_CPU0_PE2_SS_RXP<14>")
	)
	(segment
		(start 108.400596 -33.143698)
		(end 108.40085 -33.143952)
		(width 0.127)
		(layer "In2.Cu")
		(net "P3E_CPU0_PE2_SS_RXP<14>")
	)
	(segment
		(start 110.92942 -22.390354)
		(end 108.970318 -27.058874)
		(width 0.127)
		(layer "In2.Cu")
		(net "P3E_CPU0_PE2_SS_RXP<14>")
	)
	(segment
		(start 118.551706 -11.504168)
		(end 110.92942 -22.390354)
		(width 0.127)
		(layer "In2.Cu")
		(net "P3E_CPU0_PE2_SS_RXP<14>")
	)
	(segment
		(start 108.287058 -33.087056)
		(end 108.400596 -33.143698)
		(width 0.127)
		(layer "In2.Cu")
		(net "P3E_CPU0_PE2_SS_RXP<14>")
	)
	(segment
		(start 108.951776 -27.172158)
		(end 108.944156 -27.218132)
		(width 0.127)
		(layer "In2.Cu")
		(net "P3E_CPU0_PE2_SS_RXP<14>")
	)
	(segment
		(start 108.924344 -27.460194)
		(end 108.90504 -27.701748)
		(width 0.127)
		(layer "In2.Cu")
		(net "P3E_CPU0_PE2_SS_RXP<14>")
	)
	(segment
		(start 126.492 4.755388)
		(end 126.487174 4.50469)
		(width 0.127)
		(layer "In2.Cu")
		(net "P3E_CPU0_PE2_SS_RXP<14>")
	)
	(segment
		(start 108.457746 -33.314132)
		(end 108.080302 -34.070036)
		(width 0.127)
		(layer "In2.Cu")
		(net "P3E_CPU0_PE2_SS_RXP<14>")
	)
	(segment
		(start 108.943394 -27.21864)
		(end 108.924344 -27.460194)
		(width 0.127)
		(layer "In2.Cu")
		(net "P3E_CPU0_PE2_SS_RXP<14>")
	)
	(arc
		(start 108.40085 -33.143952)
		(mid 108.464543 -33.217258)
		(end 108.457746 -33.314132)
		(width 0.127)
		(layer "In2.Cu")
		(net "P3E_CPU0_PE2_SS_RXP<14>")
	)
	(arc
		(start 107.989116 -29.421836)
		(mid 107.905332 -29.83062)
		(end 107.72775 -30.20822)
		(width 0.127)
		(layer "In2.Cu")
		(net "P3E_CPU0_PE2_SS_RXP<14>")
	)
	(arc
		(start 126.11354 5.206492)
		(mid 126.388706 5.053087)
		(end 126.492 4.755388)
		(width 0.127)
		(layer "In2.Cu")
		(net "P3E_CPU0_PE2_SS_RXP<14>")
	)
	(arc
		(start 107.747562 -31.568898)
		(mid 107.864105 -31.912216)
		(end 107.866942 -32.274764)
		(width 0.127)
		(layer "In2.Cu")
		(net "P3E_CPU0_PE2_SS_RXP<14>")
	)
	(arc
		(start 107.602528 -31.16326)
		(mid 107.660457 -31.371295)
		(end 107.747562 -31.568898)
		(width 0.127)
		(layer "In2.Cu")
		(net "P3E_CPU0_PE2_SS_RXP<14>")
	)
	(arc
		(start 107.581446 -30.709108)
		(mid 107.574699 -30.936986)
		(end 107.602528 -31.16326)
		(width 0.127)
		(layer "In2.Cu")
		(net "P3E_CPU0_PE2_SS_RXP<14>")
	)
	(arc
		(start 107.866942 -32.274764)
		(mid 107.944828 -32.749258)
		(end 108.287058 -33.087056)
		(width 0.127)
		(layer "In2.Cu")
		(net "P3E_CPU0_PE2_SS_RXP<14>")
	)
	(arc
		(start 107.718352 -30.222698)
		(mid 107.629291 -30.460102)
		(end 107.581446 -30.709108)
		(width 0.127)
		(layer "In2.Cu")
		(net "P3E_CPU0_PE2_SS_RXP<14>")
	)
	(arc
		(start 107.727496 -30.20822)
		(mid 107.722942 -30.21547)
		(end 107.718352 -30.222698)
		(width 0.127)
		(layer "In2.Cu")
		(net "P3E_CPU0_PE2_SS_RXP<14>")
	)
	(arc
		(start 108.20527 -28.913074)
		(mid 108.05634 -29.150098)
		(end 107.989116 -29.421836)
		(width 0.127)
		(layer "In2.Cu")
		(net "P3E_CPU0_PE2_SS_RXP<14>")
	)
	(arc
		(start 108.75772 -28.0416)
		(mid 108.515379 -28.498816)
		(end 108.20527 -28.913074)
		(width 0.127)
		(layer "In2.Cu")
		(net "P3E_CPU0_PE2_SS_RXP<14>")
	)
	(via
		(at 123.52274 5.206492)
		(size 0.508)
		(drill 0.254)
		(layers "F.Cu" "B.Cu")
		(net "P3E_CPU0_PE2_SS_RXP<13>")
	)
	(segment
		(start 123.795536 7.154418)
		(end 123.83262 7.58825)
		(width 0.127)
		(layer "B.Cu")
		(net "P3E_CPU0_PE2_SS_RXP<13>")
	)
	(segment
		(start 123.873514 8.078216)
		(end 123.87453 8.088884)
		(width 0.127)
		(layer "B.Cu")
		(net "P3E_CPU0_PE2_SS_RXP<13>")
	)
	(segment
		(start 123.873768 8.078216)
		(end 123.873514 8.078216)
		(width 0.127)
		(layer "B.Cu")
		(net "P3E_CPU0_PE2_SS_RXP<13>")
	)
	(segment
		(start 123.417838 8.718804)
		(end 123.166378 8.951976)
		(width 0.127)
		(layer "B.Cu")
		(net "P3E_CPU0_PE2_SS_RXP<13>")
	)
	(segment
		(start 123.87834 6.580632)
		(end 123.795536 7.154418)
		(width 0.127)
		(layer "B.Cu")
		(net "P3E_CPU0_PE2_SS_RXP<13>")
	)
	(segment
		(start 123.83262 7.58825)
		(end 123.873768 8.078216)
		(width 0.127)
		(layer "B.Cu")
		(net "P3E_CPU0_PE2_SS_RXP<13>")
	)
	(segment
		(start 123.87453 8.088884)
		(end 123.875038 8.09498)
		(width 0.127)
		(layer "B.Cu")
		(net "P3E_CPU0_PE2_SS_RXP<13>")
	)
	(segment
		(start 123.69419 8.463026)
		(end 123.417838 8.718804)
		(width 0.127)
		(layer "B.Cu")
		(net "P3E_CPU0_PE2_SS_RXP<13>")
	)
	(segment
		(start 123.87834 5.816092)
		(end 123.87834 6.580632)
		(width 0.127)
		(layer "B.Cu")
		(net "P3E_CPU0_PE2_SS_RXP<13>")
	)
	(segment
		(start 122.575066 11.217656)
		(end 122.575066 12.615672)
		(width 0.127)
		(layer "B.Cu")
		(net "P3E_CPU0_PE2_SS_RXP<13>")
	)
	(arc
		(start 122.698764 10.918952)
		(mid 122.607192 11.055999)
		(end 122.575066 11.217656)
		(width 0.127)
		(layer "B.Cu")
		(net "P3E_CPU0_PE2_SS_RXP<13>")
	)
	(arc
		(start 123.875038 8.09498)
		(mid 123.818796 8.295803)
		(end 123.69419 8.463026)
		(width 0.127)
		(layer "B.Cu")
		(net "P3E_CPU0_PE2_SS_RXP<13>")
	)
	(arc
		(start 122.822716 10.61974)
		(mid 122.790505 10.781678)
		(end 122.698764 10.918952)
		(width 0.127)
		(layer "B.Cu")
		(net "P3E_CPU0_PE2_SS_RXP<13>")
	)
	(arc
		(start 123.52274 5.206492)
		(mid 123.782955 5.463219)
		(end 123.87834 5.816092)
		(width 0.127)
		(layer "B.Cu")
		(net "P3E_CPU0_PE2_SS_RXP<13>")
	)
	(arc
		(start 122.826018 9.926574)
		(mid 122.823542 10.273153)
		(end 122.822716 10.61974)
		(width 0.127)
		(layer "B.Cu")
		(net "P3E_CPU0_PE2_SS_RXP<13>")
	)
	(arc
		(start 123.166378 8.951976)
		(mid 122.875088 9.396978)
		(end 122.826018 9.926574)
		(width 0.127)
		(layer "B.Cu")
		(net "P3E_CPU0_PE2_SS_RXP<13>")
	)
	(segment
		(start 118.156736 -4.759452)
		(end 123.657106 3.096006)
		(width 0.127)
		(layer "In2.Cu")
		(net "P3E_CPU0_PE2_SS_RXP<13>")
	)
	(segment
		(start 115.189762 -7.598156)
		(end 115.922298 -6.323838)
		(width 0.127)
		(layer "In2.Cu")
		(net "P3E_CPU0_PE2_SS_RXP<13>")
	)
	(segment
		(start 103.726996 -30.20822)
		(end 103.72725 -30.20822)
		(width 0.127)
		(layer "In2.Cu")
		(net "P3E_CPU0_PE2_SS_RXP<13>")
	)
	(segment
		(start 117.858032 -4.968748)
		(end 118.156736 -4.759452)
		(width 0.127)
		(layer "In2.Cu")
		(net "P3E_CPU0_PE2_SS_RXP<13>")
	)
	(segment
		(start 112.927384 -14.280896)
		(end 112.927384 -13.932154)
		(width 0.127)
		(layer "In2.Cu")
		(net "P3E_CPU0_PE2_SS_RXP<13>")
	)
	(segment
		(start 104.965246 -27.305)
		(end 104.965246 -27.25039)
		(width 0.127)
		(layer "In2.Cu")
		(net "P3E_CPU0_PE2_SS_RXP<13>")
	)
	(segment
		(start 115.186968 -7.600442)
		(end 115.189 -7.59968)
		(width 0.127)
		(layer "In2.Cu")
		(net "P3E_CPU0_PE2_SS_RXP<13>")
	)
	(segment
		(start 112.720374 -14.687296)
		(end 112.927384 -14.280896)
		(width 0.127)
		(layer "In2.Cu")
		(net "P3E_CPU0_PE2_SS_RXP<13>")
	)
	(segment
		(start 104.968294 -27.248358)
		(end 104.96804 -27.248358)
		(width 0.127)
		(layer "In2.Cu")
		(net "P3E_CPU0_PE2_SS_RXP<13>")
	)
	(segment
		(start 113.90757 -10.29589)
		(end 114.442748 -8.565134)
		(width 0.127)
		(layer "In2.Cu")
		(net "P3E_CPU0_PE2_SS_RXP<13>")
	)
	(segment
		(start 104.965246 -27.25039)
		(end 104.968294 -27.248358)
		(width 0.127)
		(layer "In2.Cu")
		(net "P3E_CPU0_PE2_SS_RXP<13>")
	)
	(segment
		(start 114.442748 -8.565134)
		(end 115.186968 -7.600442)
		(width 0.127)
		(layer "In2.Cu")
		(net "P3E_CPU0_PE2_SS_RXP<13>")
	)
	(segment
		(start 113.90757 -11.87958)
		(end 113.90757 -10.29589)
		(width 0.127)
		(layer "In2.Cu")
		(net "P3E_CPU0_PE2_SS_RXP<13>")
	)
	(segment
		(start 104.96804 -27.248358)
		(end 104.987344 -27.144726)
		(width 0.127)
		(layer "In2.Cu")
		(net "P3E_CPU0_PE2_SS_RXP<13>")
	)
	(segment
		(start 115.922298 -6.323838)
		(end 117.858032 -4.968748)
		(width 0.127)
		(layer "In2.Cu")
		(net "P3E_CPU0_PE2_SS_RXP<13>")
	)
	(segment
		(start 104.400096 -33.143698)
		(end 104.286558 -33.087056)
		(width 0.127)
		(layer "In2.Cu")
		(net "P3E_CPU0_PE2_SS_RXP<13>")
	)
	(segment
		(start 113.462054 -12.640564)
		(end 113.68405 -12.418568)
		(width 0.127)
		(layer "In2.Cu")
		(net "P3E_CPU0_PE2_SS_RXP<13>")
	)
	(segment
		(start 104.079802 -34.070036)
		(end 104.457246 -33.314132)
		(width 0.127)
		(layer "In2.Cu")
		(net "P3E_CPU0_PE2_SS_RXP<13>")
	)
	(segment
		(start 104.99725 -27.09291)
		(end 106.536744 -23.201122)
		(width 0.127)
		(layer "In2.Cu")
		(net "P3E_CPU0_PE2_SS_RXP<13>")
	)
	(segment
		(start 104.40035 -33.143952)
		(end 104.400096 -33.143698)
		(width 0.127)
		(layer "In2.Cu")
		(net "P3E_CPU0_PE2_SS_RXP<13>")
	)
	(segment
		(start 104.987344 -27.144726)
		(end 104.99725 -27.09291)
		(width 0.127)
		(layer "In2.Cu")
		(net "P3E_CPU0_PE2_SS_RXP<13>")
	)
	(segment
		(start 123.890786 4.421124)
		(end 123.9012 4.755388)
		(width 0.127)
		(layer "In2.Cu")
		(net "P3E_CPU0_PE2_SS_RXP<13>")
	)
	(segment
		(start 115.189 -7.59968)
		(end 115.189762 -7.598156)
		(width 0.127)
		(layer "In2.Cu")
		(net "P3E_CPU0_PE2_SS_RXP<13>")
	)
	(segment
		(start 106.536744 -23.201122)
		(end 112.715294 -14.6939)
		(width 0.127)
		(layer "In2.Cu")
		(net "P3E_CPU0_PE2_SS_RXP<13>")
	)
	(segment
		(start 112.715294 -14.6939)
		(end 112.720374 -14.687296)
		(width 0.127)
		(layer "In2.Cu")
		(net "P3E_CPU0_PE2_SS_RXP<13>")
	)
	(segment
		(start 104.211882 -28.9052)
		(end 104.366568 -28.75026)
		(width 0.127)
		(layer "In2.Cu")
		(net "P3E_CPU0_PE2_SS_RXP<13>")
	)
	(segment
		(start 123.657106 3.096006)
		(end 123.890786 4.421124)
		(width 0.127)
		(layer "In2.Cu")
		(net "P3E_CPU0_PE2_SS_RXP<13>")
	)
	(arc
		(start 103.988616 -29.421836)
		(mid 104.057943 -29.145233)
		(end 104.211882 -28.9052)
		(width 0.127)
		(layer "In2.Cu")
		(net "P3E_CPU0_PE2_SS_RXP<13>")
	)
	(arc
		(start 103.717852 -30.222698)
		(mid 103.722442 -30.21547)
		(end 103.726996 -30.20822)
		(width 0.127)
		(layer "In2.Cu")
		(net "P3E_CPU0_PE2_SS_RXP<13>")
	)
	(arc
		(start 103.602028 -31.16326)
		(mid 103.574194 -30.936987)
		(end 103.580946 -30.709108)
		(width 0.127)
		(layer "In2.Cu")
		(net "P3E_CPU0_PE2_SS_RXP<13>")
	)
	(arc
		(start 123.9012 4.755388)
		(mid 123.798058 5.053215)
		(end 123.52274 5.206492)
		(width 0.127)
		(layer "In2.Cu")
		(net "P3E_CPU0_PE2_SS_RXP<13>")
	)
	(arc
		(start 104.286558 -33.087056)
		(mid 103.944273 -32.749286)
		(end 103.866442 -32.274764)
		(width 0.127)
		(layer "In2.Cu")
		(net "P3E_CPU0_PE2_SS_RXP<13>")
	)
	(arc
		(start 113.68405 -12.418568)
		(mid 113.849367 -12.171293)
		(end 113.90757 -11.87958)
		(width 0.127)
		(layer "In2.Cu")
		(net "P3E_CPU0_PE2_SS_RXP<13>")
	)
	(arc
		(start 103.747062 -31.568898)
		(mid 103.659959 -31.371294)
		(end 103.602028 -31.16326)
		(width 0.127)
		(layer "In2.Cu")
		(net "P3E_CPU0_PE2_SS_RXP<13>")
	)
	(arc
		(start 103.72725 -30.20822)
		(mid 103.904764 -29.830598)
		(end 103.988616 -29.421836)
		(width 0.127)
		(layer "In2.Cu")
		(net "P3E_CPU0_PE2_SS_RXP<13>")
	)
	(arc
		(start 104.457246 -33.314132)
		(mid 104.464043 -33.217258)
		(end 104.40035 -33.143952)
		(width 0.127)
		(layer "In2.Cu")
		(net "P3E_CPU0_PE2_SS_RXP<13>")
	)
	(arc
		(start 103.866442 -32.274764)
		(mid 103.863604 -31.912216)
		(end 103.747062 -31.568898)
		(width 0.127)
		(layer "In2.Cu")
		(net "P3E_CPU0_PE2_SS_RXP<13>")
	)
	(arc
		(start 104.366568 -28.75026)
		(mid 104.809631 -28.087169)
		(end 104.965246 -27.305)
		(width 0.127)
		(layer "In2.Cu")
		(net "P3E_CPU0_PE2_SS_RXP<13>")
	)
	(arc
		(start 112.927384 -13.932154)
		(mid 113.066355 -13.233232)
		(end 113.462054 -12.640564)
		(width 0.127)
		(layer "In2.Cu")
		(net "P3E_CPU0_PE2_SS_RXP<13>")
	)
	(arc
		(start 103.580946 -30.709108)
		(mid 103.628785 -30.460101)
		(end 103.717852 -30.222698)
		(width 0.127)
		(layer "In2.Cu")
		(net "P3E_CPU0_PE2_SS_RXP<13>")
	)
	(via
		(at 120.93194 5.206492)
		(size 0.508)
		(drill 0.254)
		(layers "F.Cu" "B.Cu")
		(net "P3E_CPU0_PE2_SS_RXP<12>")
	)
	(segment
		(start 120.42267 10.590784)
		(end 120.42267 10.16)
		(width 0.127)
		(layer "B.Cu")
		(net "P3E_CPU0_PE2_SS_RXP<12>")
	)
	(segment
		(start 121.266712 7.933944)
		(end 121.265442 7.93369)
		(width 0.127)
		(layer "B.Cu")
		(net "P3E_CPU0_PE2_SS_RXP<12>")
	)
	(segment
		(start 121.294906 6.904736)
		(end 121.294906 5.6896)
		(width 0.127)
		(layer "B.Cu")
		(net "P3E_CPU0_PE2_SS_RXP<12>")
	)
	(segment
		(start 121.26595 7.322566)
		(end 121.294906 6.904736)
		(width 0.127)
		(layer "B.Cu")
		(net "P3E_CPU0_PE2_SS_RXP<12>")
	)
	(segment
		(start 121.264934 7.966964)
		(end 121.264934 7.96671)
		(width 0.127)
		(layer "B.Cu")
		(net "P3E_CPU0_PE2_SS_RXP<12>")
	)
	(segment
		(start 121.264426 7.967472)
		(end 121.264934 7.966964)
		(width 0.127)
		(layer "B.Cu")
		(net "P3E_CPU0_PE2_SS_RXP<12>")
	)
	(segment
		(start 121.264934 7.96671)
		(end 121.266458 7.933944)
		(width 0.127)
		(layer "B.Cu")
		(net "P3E_CPU0_PE2_SS_RXP<12>")
	)
	(segment
		(start 121.265442 7.932166)
		(end 121.26595 7.322566)
		(width 0.127)
		(layer "B.Cu")
		(net "P3E_CPU0_PE2_SS_RXP<12>")
	)
	(segment
		(start 121.265442 7.93369)
		(end 121.265442 7.932166)
		(width 0.127)
		(layer "B.Cu")
		(net "P3E_CPU0_PE2_SS_RXP<12>")
	)
	(segment
		(start 121.266458 7.933944)
		(end 121.266712 7.933944)
		(width 0.127)
		(layer "B.Cu")
		(net "P3E_CPU0_PE2_SS_RXP<12>")
	)
	(segment
		(start 121.258584 8.095234)
		(end 121.264426 7.968234)
		(width 0.127)
		(layer "B.Cu")
		(net "P3E_CPU0_PE2_SS_RXP<12>")
	)
	(segment
		(start 120.17502 12.615672)
		(end 120.17502 11.1887)
		(width 0.127)
		(layer "B.Cu")
		(net "P3E_CPU0_PE2_SS_RXP<12>")
	)
	(segment
		(start 121.264426 7.968234)
		(end 121.264426 7.967472)
		(width 0.127)
		(layer "B.Cu")
		(net "P3E_CPU0_PE2_SS_RXP<12>")
	)
	(arc
		(start 120.17502 11.1887)
		(mid 120.207231 11.026762)
		(end 120.298972 10.889488)
		(width 0.127)
		(layer "B.Cu")
		(net "P3E_CPU0_PE2_SS_RXP<12>")
	)
	(arc
		(start 120.298972 10.889488)
		(mid 120.390544 10.752441)
		(end 120.42267 10.590784)
		(width 0.127)
		(layer "B.Cu")
		(net "P3E_CPU0_PE2_SS_RXP<12>")
	)
	(arc
		(start 120.65 8.975344)
		(mid 120.88108 8.662039)
		(end 121.141998 8.37311)
		(width 0.127)
		(layer "B.Cu")
		(net "P3E_CPU0_PE2_SS_RXP<12>")
	)
	(arc
		(start 121.294906 5.6896)
		(mid 121.194048 5.387482)
		(end 120.93194 5.206492)
		(width 0.127)
		(layer "B.Cu")
		(net "P3E_CPU0_PE2_SS_RXP<12>")
	)
	(arc
		(start 121.141998 8.37311)
		(mid 121.224962 8.244517)
		(end 121.258584 8.095234)
		(width 0.127)
		(layer "B.Cu")
		(net "P3E_CPU0_PE2_SS_RXP<12>")
	)
	(arc
		(start 120.42267 10.16)
		(mid 120.480016 9.556865)
		(end 120.65 8.975344)
		(width 0.127)
		(layer "B.Cu")
		(net "P3E_CPU0_PE2_SS_RXP<12>")
	)
	(segment
		(start 101.261418 -25.991312)
		(end 101.273864 -25.933908)
		(width 0.127)
		(layer "In2.Cu")
		(net "P3E_CPU0_PE2_SS_RXP<12>")
	)
	(segment
		(start 109.20603 -5.582666)
		(end 109.504988 -5.155692)
		(width 0.127)
		(layer "In2.Cu")
		(net "P3E_CPU0_PE2_SS_RXP<12>")
	)
	(segment
		(start 121.190258 3.2004)
		(end 121.311162 4.571492)
		(width 0.127)
		(layer "In2.Cu")
		(net "P3E_CPU0_PE2_SS_RXP<12>")
	)
	(segment
		(start 100.399596 -33.143698)
		(end 100.286058 -33.087056)
		(width 0.127)
		(layer "In2.Cu")
		(net "P3E_CPU0_PE2_SS_RXP<12>")
	)
	(segment
		(start 108.9406 -7.088632)
		(end 109.20603 -5.582666)
		(width 0.127)
		(layer "In2.Cu")
		(net "P3E_CPU0_PE2_SS_RXP<12>")
	)
	(segment
		(start 101.086158 -26.784808)
		(end 101.261418 -25.991312)
		(width 0.127)
		(layer "In2.Cu")
		(net "P3E_CPU0_PE2_SS_RXP<12>")
	)
	(segment
		(start 108.9279 -14.323314)
		(end 108.9279 -13.932408)
		(width 0.127)
		(layer "In2.Cu")
		(net "P3E_CPU0_PE2_SS_RXP<12>")
	)
	(segment
		(start 121.310654 4.572762)
		(end 121.310654 4.573016)
		(width 0.127)
		(layer "In2.Cu")
		(net "P3E_CPU0_PE2_SS_RXP<12>")
	)
	(segment
		(start 101.273864 -25.933908)
		(end 108.729018 -15.351506)
		(width 0.127)
		(layer "In2.Cu")
		(net "P3E_CPU0_PE2_SS_RXP<12>")
	)
	(segment
		(start 99.726496 -30.20822)
		(end 99.72675 -30.20822)
		(width 0.127)
		(layer "In2.Cu")
		(net "P3E_CPU0_PE2_SS_RXP<12>")
	)
	(segment
		(start 109.487208 -8.28294)
		(end 109.379004 -8.174736)
		(width 0.127)
		(layer "In2.Cu")
		(net "P3E_CPU0_PE2_SS_RXP<12>")
	)
	(segment
		(start 110.2868 -4.608068)
		(end 114.484912 -3.867912)
		(width 0.127)
		(layer "In2.Cu")
		(net "P3E_CPU0_PE2_SS_RXP<12>")
	)
	(segment
		(start 109.504988 -5.155692)
		(end 110.2868 -4.608068)
		(width 0.127)
		(layer "In2.Cu")
		(net "P3E_CPU0_PE2_SS_RXP<12>")
	)
	(segment
		(start 114.484912 -3.867912)
		(end 117.731794 -1.594358)
		(width 0.127)
		(layer "In2.Cu")
		(net "P3E_CPU0_PE2_SS_RXP<12>")
	)
	(segment
		(start 117.731794 -1.594358)
		(end 117.734334 -1.594358)
		(width 0.127)
		(layer "In2.Cu")
		(net "P3E_CPU0_PE2_SS_RXP<12>")
	)
	(segment
		(start 109.462824 -12.640564)
		(end 109.68482 -12.418568)
		(width 0.127)
		(layer "In2.Cu")
		(net "P3E_CPU0_PE2_SS_RXP<12>")
	)
	(segment
		(start 121.311162 4.571492)
		(end 121.311162 4.572254)
		(width 0.127)
		(layer "In2.Cu")
		(net "P3E_CPU0_PE2_SS_RXP<12>")
	)
	(segment
		(start 100.75672 -28.0416)
		(end 100.861622 -27.799284)
		(width 0.127)
		(layer "In2.Cu")
		(net "P3E_CPU0_PE2_SS_RXP<12>")
	)
	(segment
		(start 109.90834 -11.87958)
		(end 109.90834 -9.298686)
		(width 0.127)
		(layer "In2.Cu")
		(net "P3E_CPU0_PE2_SS_RXP<12>")
	)
	(segment
		(start 118.019322 -1.327912)
		(end 119.91467 1.378458)
		(width 0.127)
		(layer "In2.Cu")
		(net "P3E_CPU0_PE2_SS_RXP<12>")
	)
	(segment
		(start 117.735604 -1.593088)
		(end 118.019322 -1.327912)
		(width 0.127)
		(layer "In2.Cu")
		(net "P3E_CPU0_PE2_SS_RXP<12>")
	)
	(segment
		(start 121.311162 4.572254)
		(end 121.310654 4.572762)
		(width 0.127)
		(layer "In2.Cu")
		(net "P3E_CPU0_PE2_SS_RXP<12>")
	)
	(segment
		(start 108.729018 -15.351506)
		(end 108.9279 -14.323314)
		(width 0.127)
		(layer "In2.Cu")
		(net "P3E_CPU0_PE2_SS_RXP<12>")
	)
	(segment
		(start 119.91467 1.378458)
		(end 121.190258 3.2004)
		(width 0.127)
		(layer "In2.Cu")
		(net "P3E_CPU0_PE2_SS_RXP<12>")
	)
	(segment
		(start 100.861622 -27.799284)
		(end 101.086158 -26.784808)
		(width 0.127)
		(layer "In2.Cu")
		(net "P3E_CPU0_PE2_SS_RXP<12>")
	)
	(segment
		(start 121.310654 4.573016)
		(end 121.3104 4.755642)
		(width 0.127)
		(layer "In2.Cu")
		(net "P3E_CPU0_PE2_SS_RXP<12>")
	)
	(segment
		(start 100.079302 -34.070036)
		(end 100.456746 -33.314132)
		(width 0.127)
		(layer "In2.Cu")
		(net "P3E_CPU0_PE2_SS_RXP<12>")
	)
	(segment
		(start 100.39985 -33.143952)
		(end 100.399596 -33.143698)
		(width 0.127)
		(layer "In2.Cu")
		(net "P3E_CPU0_PE2_SS_RXP<12>")
	)
	(segment
		(start 117.734334 -1.594358)
		(end 117.735604 -1.593088)
		(width 0.127)
		(layer "In2.Cu")
		(net "P3E_CPU0_PE2_SS_RXP<12>")
	)
	(arc
		(start 100.20427 -28.913074)
		(mid 100.514399 -28.498828)
		(end 100.75672 -28.0416)
		(width 0.127)
		(layer "In2.Cu")
		(net "P3E_CPU0_PE2_SS_RXP<12>")
	)
	(arc
		(start 108.9279 -13.932408)
		(mid 109.066924 -13.233306)
		(end 109.462824 -12.640564)
		(width 0.127)
		(layer "In2.Cu")
		(net "P3E_CPU0_PE2_SS_RXP<12>")
	)
	(arc
		(start 99.865942 -32.274764)
		(mid 99.863104 -31.912216)
		(end 99.746562 -31.568898)
		(width 0.127)
		(layer "In2.Cu")
		(net "P3E_CPU0_PE2_SS_RXP<12>")
	)
	(arc
		(start 109.68482 -12.418568)
		(mid 109.850137 -12.171293)
		(end 109.90834 -11.87958)
		(width 0.127)
		(layer "In2.Cu")
		(net "P3E_CPU0_PE2_SS_RXP<12>")
	)
	(arc
		(start 121.3104 4.755642)
		(mid 121.310399 4.756531)
		(end 121.3104 4.75742)
		(width 0.127)
		(layer "In2.Cu")
		(net "P3E_CPU0_PE2_SS_RXP<12>")
	)
	(arc
		(start 109.90834 -9.298686)
		(mid 109.798798 -8.748924)
		(end 109.487208 -8.28294)
		(width 0.127)
		(layer "In2.Cu")
		(net "P3E_CPU0_PE2_SS_RXP<12>")
	)
	(arc
		(start 99.580446 -30.709108)
		(mid 99.628285 -30.460101)
		(end 99.717352 -30.222698)
		(width 0.127)
		(layer "In2.Cu")
		(net "P3E_CPU0_PE2_SS_RXP<12>")
	)
	(arc
		(start 121.3104 4.75742)
		(mid 121.20656 5.053955)
		(end 120.93194 5.206492)
		(width 0.127)
		(layer "In2.Cu")
		(net "P3E_CPU0_PE2_SS_RXP<12>")
	)
	(arc
		(start 99.746562 -31.568898)
		(mid 99.659459 -31.371294)
		(end 99.601528 -31.16326)
		(width 0.127)
		(layer "In2.Cu")
		(net "P3E_CPU0_PE2_SS_RXP<12>")
	)
	(arc
		(start 100.456746 -33.314132)
		(mid 100.463543 -33.217258)
		(end 100.39985 -33.143952)
		(width 0.127)
		(layer "In2.Cu")
		(net "P3E_CPU0_PE2_SS_RXP<12>")
	)
	(arc
		(start 99.717352 -30.222698)
		(mid 99.721942 -30.21547)
		(end 99.726496 -30.20822)
		(width 0.127)
		(layer "In2.Cu")
		(net "P3E_CPU0_PE2_SS_RXP<12>")
	)
	(arc
		(start 99.72675 -30.20822)
		(mid 99.904264 -29.830598)
		(end 99.988116 -29.421836)
		(width 0.127)
		(layer "In2.Cu")
		(net "P3E_CPU0_PE2_SS_RXP<12>")
	)
	(arc
		(start 99.601528 -31.16326)
		(mid 99.573694 -30.936987)
		(end 99.580446 -30.709108)
		(width 0.127)
		(layer "In2.Cu")
		(net "P3E_CPU0_PE2_SS_RXP<12>")
	)
	(arc
		(start 99.988116 -29.421836)
		(mid 100.055337 -29.150097)
		(end 100.20427 -28.913074)
		(width 0.127)
		(layer "In2.Cu")
		(net "P3E_CPU0_PE2_SS_RXP<12>")
	)
	(arc
		(start 109.379004 -8.174736)
		(mid 109.049288 -7.676304)
		(end 108.9406 -7.088632)
		(width 0.127)
		(layer "In2.Cu")
		(net "P3E_CPU0_PE2_SS_RXP<12>")
	)
	(arc
		(start 100.286058 -33.087056)
		(mid 99.943773 -32.749286)
		(end 99.865942 -32.274764)
		(width 0.127)
		(layer "In2.Cu")
		(net "P3E_CPU0_PE2_SS_RXP<12>")
	)
	(via
		(at 118.34114 5.206492)
		(size 0.508)
		(drill 0.254)
		(layers "F.Cu" "B.Cu")
		(net "P3E_CPU0_PE2_SS_RXP<11>")
	)
	(segment
		(start 117.774974 12.615672)
		(end 117.774974 11.203432)
		(width 0.127)
		(layer "B.Cu")
		(net "P3E_CPU0_PE2_SS_RXP<11>")
	)
	(segment
		(start 118.69674 6.971792)
		(end 118.69674 5.816092)
		(width 0.127)
		(layer "B.Cu")
		(net "P3E_CPU0_PE2_SS_RXP<11>")
	)
	(segment
		(start 118.661434 7.808976)
		(end 118.66753 7.686548)
		(width 0.127)
		(layer "B.Cu")
		(net "P3E_CPU0_PE2_SS_RXP<11>")
	)
	(segment
		(start 118.668292 7.67588)
		(end 118.69674 6.971792)
		(width 0.127)
		(layer "B.Cu")
		(net "P3E_CPU0_PE2_SS_RXP<11>")
	)
	(segment
		(start 118.033292 9.392412)
		(end 118.033038 9.392412)
		(width 0.127)
		(layer "B.Cu")
		(net "P3E_CPU0_PE2_SS_RXP<11>")
	)
	(segment
		(start 118.022624 10.605516)
		(end 118.022624 9.658096)
		(width 0.127)
		(layer "B.Cu")
		(net "P3E_CPU0_PE2_SS_RXP<11>")
	)
	(segment
		(start 118.661434 7.817104)
		(end 118.661434 7.808976)
		(width 0.127)
		(layer "B.Cu")
		(net "P3E_CPU0_PE2_SS_RXP<11>")
	)
	(segment
		(start 118.66753 7.686548)
		(end 118.668292 7.67588)
		(width 0.127)
		(layer "B.Cu")
		(net "P3E_CPU0_PE2_SS_RXP<11>")
	)
	(arc
		(start 117.898672 10.904728)
		(mid 117.990399 10.767448)
		(end 118.022624 10.605516)
		(width 0.127)
		(layer "B.Cu")
		(net "P3E_CPU0_PE2_SS_RXP<11>")
	)
	(arc
		(start 118.033038 9.392412)
		(mid 118.157726 8.927905)
		(end 118.408704 8.517636)
		(width 0.127)
		(layer "B.Cu")
		(net "P3E_CPU0_PE2_SS_RXP<11>")
	)
	(arc
		(start 118.022624 9.658096)
		(mid 118.022703 9.525043)
		(end 118.033292 9.392412)
		(width 0.127)
		(layer "B.Cu")
		(net "P3E_CPU0_PE2_SS_RXP<11>")
	)
	(arc
		(start 117.774974 11.203432)
		(mid 117.807127 11.041786)
		(end 117.898672 10.904728)
		(width 0.127)
		(layer "B.Cu")
		(net "P3E_CPU0_PE2_SS_RXP<11>")
	)
	(arc
		(start 118.408704 8.517636)
		(mid 118.596315 8.189466)
		(end 118.661434 7.817104)
		(width 0.127)
		(layer "B.Cu")
		(net "P3E_CPU0_PE2_SS_RXP<11>")
	)
	(arc
		(start 118.69674 5.816092)
		(mid 118.601339 5.463229)
		(end 118.34114 5.206492)
		(width 0.127)
		(layer "B.Cu")
		(net "P3E_CPU0_PE2_SS_RXP<11>")
	)
	(segment
		(start 104.528112 -15.350998)
		(end 99.52609 -21.920962)
		(width 0.127)
		(layer "In2.Cu")
		(net "P3E_CPU0_PE2_SS_RXP<11>")
	)
	(segment
		(start 105.309416 -4.655566)
		(end 104.94137 -6.743446)
		(width 0.127)
		(layer "In2.Cu")
		(net "P3E_CPU0_PE2_SS_RXP<11>")
	)
	(segment
		(start 105.68432 -12.418568)
		(end 105.462324 -12.640564)
		(width 0.127)
		(layer "In2.Cu")
		(net "P3E_CPU0_PE2_SS_RXP<11>")
	)
	(segment
		(start 99.52609 -21.920962)
		(end 99.508818 -21.943314)
		(width 0.127)
		(layer "In2.Cu")
		(net "P3E_CPU0_PE2_SS_RXP<11>")
	)
	(segment
		(start 105.90784 -9.298686)
		(end 105.90784 -11.87958)
		(width 0.127)
		(layer "In2.Cu")
		(net "P3E_CPU0_PE2_SS_RXP<11>")
	)
	(segment
		(start 105.774236 -3.991864)
		(end 105.309416 -4.655566)
		(width 0.127)
		(layer "In2.Cu")
		(net "P3E_CPU0_PE2_SS_RXP<11>")
	)
	(segment
		(start 105.379774 -8.174736)
		(end 105.486708 -8.28294)
		(width 0.127)
		(layer "In2.Cu")
		(net "P3E_CPU0_PE2_SS_RXP<11>")
	)
	(segment
		(start 104.872282 -14.63802)
		(end 104.874314 -14.642846)
		(width 0.127)
		(layer "In2.Cu")
		(net "P3E_CPU0_PE2_SS_RXP<11>")
	)
	(segment
		(start 112.27943 -2.182368)
		(end 107.039156 -3.106166)
		(width 0.127)
		(layer "In2.Cu")
		(net "P3E_CPU0_PE2_SS_RXP<11>")
	)
	(segment
		(start 104.9274 -13.932408)
		(end 104.9274 -14.325854)
		(width 0.127)
		(layer "In2.Cu")
		(net "P3E_CPU0_PE2_SS_RXP<11>")
	)
	(segment
		(start 118.718584 4.717034)
		(end 118.71071 4.46278)
		(width 0.127)
		(layer "In2.Cu")
		(net "P3E_CPU0_PE2_SS_RXP<11>")
	)
	(segment
		(start 118.71071 4.46278)
		(end 118.479316 3.150108)
		(width 0.127)
		(layer "In2.Cu")
		(net "P3E_CPU0_PE2_SS_RXP<11>")
	)
	(segment
		(start 96.940624 -27.162252)
		(end 96.9391 -27.22118)
		(width 0.127)
		(layer "In2.Cu")
		(net "P3E_CPU0_PE2_SS_RXP<11>")
	)
	(segment
		(start 104.9274 -14.325854)
		(end 104.872282 -14.63802)
		(width 0.127)
		(layer "In2.Cu")
		(net "P3E_CPU0_PE2_SS_RXP<11>")
	)
	(segment
		(start 95.72752 -30.20822)
		(end 95.727266 -30.20822)
		(width 0.127)
		(layer "In2.Cu")
		(net "P3E_CPU0_PE2_SS_RXP<11>")
	)
	(segment
		(start 99.508818 -21.943314)
		(end 96.93529 -27.159712)
		(width 0.127)
		(layer "In2.Cu")
		(net "P3E_CPU0_PE2_SS_RXP<11>")
	)
	(segment
		(start 96.286828 -33.087056)
		(end 96.400366 -33.143698)
		(width 0.127)
		(layer "In2.Cu")
		(net "P3E_CPU0_PE2_SS_RXP<11>")
	)
	(segment
		(start 104.725724 -15.000224)
		(end 104.725978 -15.002002)
		(width 0.127)
		(layer "In2.Cu")
		(net "P3E_CPU0_PE2_SS_RXP<11>")
	)
	(segment
		(start 104.87279 -14.646148)
		(end 104.725724 -15.000224)
		(width 0.127)
		(layer "In2.Cu")
		(net "P3E_CPU0_PE2_SS_RXP<11>")
	)
	(segment
		(start 107.039156 -3.106166)
		(end 105.774236 -3.991864)
		(width 0.127)
		(layer "In2.Cu")
		(net "P3E_CPU0_PE2_SS_RXP<11>")
	)
	(segment
		(start 118.479316 3.150108)
		(end 117.116352 1.204468)
		(width 0.127)
		(layer "In2.Cu")
		(net "P3E_CPU0_PE2_SS_RXP<11>")
	)
	(segment
		(start 104.725978 -15.002002)
		(end 104.725216 -15.003272)
		(width 0.127)
		(layer "In2.Cu")
		(net "P3E_CPU0_PE2_SS_RXP<11>")
	)
	(segment
		(start 104.874314 -14.642846)
		(end 104.87279 -14.646148)
		(width 0.127)
		(layer "In2.Cu")
		(net "P3E_CPU0_PE2_SS_RXP<11>")
	)
	(segment
		(start 96.400366 -33.143698)
		(end 96.40062 -33.143952)
		(width 0.127)
		(layer "In2.Cu")
		(net "P3E_CPU0_PE2_SS_RXP<11>")
	)
	(segment
		(start 104.94137 -6.743446)
		(end 104.94137 -7.115302)
		(width 0.127)
		(layer "In2.Cu")
		(net "P3E_CPU0_PE2_SS_RXP<11>")
	)
	(segment
		(start 96.457516 -33.314132)
		(end 96.080072 -34.070036)
		(width 0.127)
		(layer "In2.Cu")
		(net "P3E_CPU0_PE2_SS_RXP<11>")
	)
	(segment
		(start 104.72547 -15.003272)
		(end 104.528112 -15.350998)
		(width 0.127)
		(layer "In2.Cu")
		(net "P3E_CPU0_PE2_SS_RXP<11>")
	)
	(segment
		(start 104.725216 -15.003272)
		(end 104.72547 -15.003272)
		(width 0.127)
		(layer "In2.Cu")
		(net "P3E_CPU0_PE2_SS_RXP<11>")
	)
	(segment
		(start 117.116352 1.204468)
		(end 112.27943 -2.182368)
		(width 0.127)
		(layer "In2.Cu")
		(net "P3E_CPU0_PE2_SS_RXP<11>")
	)
	(segment
		(start 96.93529 -27.159712)
		(end 96.940624 -27.162252)
		(width 0.127)
		(layer "In2.Cu")
		(net "P3E_CPU0_PE2_SS_RXP<11>")
	)
	(arc
		(start 118.7196 4.755388)
		(mid 118.719296 4.736206)
		(end 118.718584 4.717034)
		(width 0.127)
		(layer "In2.Cu")
		(net "P3E_CPU0_PE2_SS_RXP<11>")
	)
	(arc
		(start 105.462324 -12.640564)
		(mid 105.0664 -13.233296)
		(end 104.9274 -13.932408)
		(width 0.127)
		(layer "In2.Cu")
		(net "P3E_CPU0_PE2_SS_RXP<11>")
	)
	(arc
		(start 96.9391 -27.22118)
		(mid 96.887701 -27.640111)
		(end 96.75749 -28.0416)
		(width 0.127)
		(layer "In2.Cu")
		(net "P3E_CPU0_PE2_SS_RXP<11>")
	)
	(arc
		(start 105.486708 -8.28294)
		(mid 105.798264 -8.748938)
		(end 105.90784 -9.298686)
		(width 0.127)
		(layer "In2.Cu")
		(net "P3E_CPU0_PE2_SS_RXP<11>")
	)
	(arc
		(start 95.718122 -30.222698)
		(mid 95.629061 -30.460102)
		(end 95.581216 -30.709108)
		(width 0.127)
		(layer "In2.Cu")
		(net "P3E_CPU0_PE2_SS_RXP<11>")
	)
	(arc
		(start 95.581216 -30.709108)
		(mid 95.574469 -30.936986)
		(end 95.602298 -31.16326)
		(width 0.127)
		(layer "In2.Cu")
		(net "P3E_CPU0_PE2_SS_RXP<11>")
	)
	(arc
		(start 96.40062 -33.143952)
		(mid 96.464313 -33.217258)
		(end 96.457516 -33.314132)
		(width 0.127)
		(layer "In2.Cu")
		(net "P3E_CPU0_PE2_SS_RXP<11>")
	)
	(arc
		(start 95.747332 -31.568898)
		(mid 95.863875 -31.912216)
		(end 95.866712 -32.274764)
		(width 0.127)
		(layer "In2.Cu")
		(net "P3E_CPU0_PE2_SS_RXP<11>")
	)
	(arc
		(start 118.34114 5.206492)
		(mid 118.616306 5.053087)
		(end 118.7196 4.755388)
		(width 0.127)
		(layer "In2.Cu")
		(net "P3E_CPU0_PE2_SS_RXP<11>")
	)
	(arc
		(start 95.602298 -31.16326)
		(mid 95.660227 -31.371295)
		(end 95.747332 -31.568898)
		(width 0.127)
		(layer "In2.Cu")
		(net "P3E_CPU0_PE2_SS_RXP<11>")
	)
	(arc
		(start 96.20504 -28.913074)
		(mid 96.05611 -29.150098)
		(end 95.988886 -29.421836)
		(width 0.127)
		(layer "In2.Cu")
		(net "P3E_CPU0_PE2_SS_RXP<11>")
	)
	(arc
		(start 95.988886 -29.421836)
		(mid 95.905102 -29.83062)
		(end 95.72752 -30.20822)
		(width 0.127)
		(layer "In2.Cu")
		(net "P3E_CPU0_PE2_SS_RXP<11>")
	)
	(arc
		(start 105.90784 -11.87958)
		(mid 105.849715 -12.171325)
		(end 105.68432 -12.418568)
		(width 0.127)
		(layer "In2.Cu")
		(net "P3E_CPU0_PE2_SS_RXP<11>")
	)
	(arc
		(start 95.727266 -30.20822)
		(mid 95.722712 -30.21547)
		(end 95.718122 -30.222698)
		(width 0.127)
		(layer "In2.Cu")
		(net "P3E_CPU0_PE2_SS_RXP<11>")
	)
	(arc
		(start 96.75749 -28.0416)
		(mid 96.515149 -28.498816)
		(end 96.20504 -28.913074)
		(width 0.127)
		(layer "In2.Cu")
		(net "P3E_CPU0_PE2_SS_RXP<11>")
	)
	(arc
		(start 104.94137 -7.115302)
		(mid 105.055137 -7.688661)
		(end 105.379774 -8.174736)
		(width 0.127)
		(layer "In2.Cu")
		(net "P3E_CPU0_PE2_SS_RXP<11>")
	)
	(arc
		(start 95.866712 -32.274764)
		(mid 95.944598 -32.749258)
		(end 96.286828 -33.087056)
		(width 0.127)
		(layer "In2.Cu")
		(net "P3E_CPU0_PE2_SS_RXP<11>")
	)
	(via
		(at 115.75034 5.206492)
		(size 0.508)
		(drill 0.254)
		(layers "F.Cu" "B.Cu")
		(net "P3E_CPU0_PE2_SS_RXP<10>")
	)
	(segment
		(start 116.056918 8.023098)
		(end 116.056918 8.022844)
		(width 0.127)
		(layer "B.Cu")
		(net "P3E_CPU0_PE2_SS_RXP<10>")
	)
	(segment
		(start 115.622832 10.668508)
		(end 115.622832 9.779)
		(width 0.127)
		(layer "B.Cu")
		(net "P3E_CPU0_PE2_SS_RXP<10>")
	)
	(segment
		(start 115.375182 12.615672)
		(end 115.375182 11.266424)
		(width 0.127)
		(layer "B.Cu")
		(net "P3E_CPU0_PE2_SS_RXP<10>")
	)
	(segment
		(start 116.057426 8.023606)
		(end 116.056918 8.023098)
		(width 0.127)
		(layer "B.Cu")
		(net "P3E_CPU0_PE2_SS_RXP<10>")
	)
	(segment
		(start 116.073428 8.393176)
		(end 116.057426 8.02386)
		(width 0.127)
		(layer "B.Cu")
		(net "P3E_CPU0_PE2_SS_RXP<10>")
	)
	(segment
		(start 116.057426 8.02386)
		(end 116.057426 8.023606)
		(width 0.127)
		(layer "B.Cu")
		(net "P3E_CPU0_PE2_SS_RXP<10>")
	)
	(segment
		(start 116.10594 6.971792)
		(end 116.10594 5.816092)
		(width 0.127)
		(layer "B.Cu")
		(net "P3E_CPU0_PE2_SS_RXP<10>")
	)
	(segment
		(start 116.056918 8.022844)
		(end 116.10594 6.971792)
		(width 0.127)
		(layer "B.Cu")
		(net "P3E_CPU0_PE2_SS_RXP<10>")
	)
	(arc
		(start 115.622832 9.779)
		(mid 115.680241 9.284268)
		(end 115.919758 8.847582)
		(width 0.127)
		(layer "B.Cu")
		(net "P3E_CPU0_PE2_SS_RXP<10>")
	)
	(arc
		(start 116.10594 5.816092)
		(mid 116.010539 5.463229)
		(end 115.75034 5.206492)
		(width 0.127)
		(layer "B.Cu")
		(net "P3E_CPU0_PE2_SS_RXP<10>")
	)
	(arc
		(start 115.919758 8.847582)
		(mid 116.03899 8.634709)
		(end 116.073428 8.393176)
		(width 0.127)
		(layer "B.Cu")
		(net "P3E_CPU0_PE2_SS_RXP<10>")
	)
	(arc
		(start 115.375182 11.266424)
		(mid 115.407335 11.104778)
		(end 115.49888 10.96772)
		(width 0.127)
		(layer "B.Cu")
		(net "P3E_CPU0_PE2_SS_RXP<10>")
	)
	(arc
		(start 115.49888 10.96772)
		(mid 115.590607 10.83044)
		(end 115.622832 10.668508)
		(width 0.127)
		(layer "B.Cu")
		(net "P3E_CPU0_PE2_SS_RXP<10>")
	)
	(segment
		(start 101.379274 -8.174736)
		(end 101.486208 -8.28294)
		(width 0.127)
		(layer "In2.Cu")
		(net "P3E_CPU0_PE2_SS_RXP<10>")
	)
	(segment
		(start 92.859098 -27.805888)
		(end 92.75699 -28.0416)
		(width 0.127)
		(layer "In2.Cu")
		(net "P3E_CPU0_PE2_SS_RXP<10>")
	)
	(segment
		(start 101.578156 -5.640324)
		(end 100.97643 -6.7437)
		(width 0.127)
		(layer "In2.Cu")
		(net "P3E_CPU0_PE2_SS_RXP<10>")
	)
	(segment
		(start 100.87737 -14.448282)
		(end 95.152972 -22.623526)
		(width 0.127)
		(layer "In2.Cu")
		(net "P3E_CPU0_PE2_SS_RXP<10>")
	)
	(segment
		(start 104.947212 -1.470406)
		(end 104.896666 -1.47955)
		(width 0.127)
		(layer "In2.Cu")
		(net "P3E_CPU0_PE2_SS_RXP<10>")
	)
	(segment
		(start 103.554022 -2.65938)
		(end 103.531162 -2.691638)
		(width 0.127)
		(layer "In2.Cu")
		(net "P3E_CPU0_PE2_SS_RXP<10>")
	)
	(segment
		(start 103.531162 -2.691638)
		(end 101.578156 -5.640324)
		(width 0.127)
		(layer "In2.Cu")
		(net "P3E_CPU0_PE2_SS_RXP<10>")
	)
	(segment
		(start 93.0148 -26.895552)
		(end 92.943172 -27.313382)
		(width 0.127)
		(layer "In2.Cu")
		(net "P3E_CPU0_PE2_SS_RXP<10>")
	)
	(segment
		(start 116.123974 4.50469)
		(end 115.945158 3.49123)
		(width 0.127)
		(layer "In2.Cu")
		(net "P3E_CPU0_PE2_SS_RXP<10>")
	)
	(segment
		(start 105.145332 -1.435862)
		(end 104.947212 -1.470406)
		(width 0.127)
		(layer "In2.Cu")
		(net "P3E_CPU0_PE2_SS_RXP<10>")
	)
	(segment
		(start 101.90734 -9.298686)
		(end 101.90734 -11.87958)
		(width 0.127)
		(layer "In2.Cu")
		(net "P3E_CPU0_PE2_SS_RXP<10>")
	)
	(segment
		(start 92.457016 -33.314132)
		(end 92.079572 -34.070036)
		(width 0.127)
		(layer "In2.Cu")
		(net "P3E_CPU0_PE2_SS_RXP<10>")
	)
	(segment
		(start 92.399866 -33.143698)
		(end 92.40012 -33.143952)
		(width 0.127)
		(layer "In2.Cu")
		(net "P3E_CPU0_PE2_SS_RXP<10>")
	)
	(segment
		(start 104.56672 -1.646682)
		(end 103.554022 -2.65938)
		(width 0.127)
		(layer "In2.Cu")
		(net "P3E_CPU0_PE2_SS_RXP<10>")
	)
	(segment
		(start 104.896666 -1.47955)
		(end 104.78643 -1.499108)
		(width 0.127)
		(layer "In2.Cu")
		(net "P3E_CPU0_PE2_SS_RXP<10>")
	)
	(segment
		(start 100.94087 -6.8834)
		(end 100.94087 -7.115302)
		(width 0.127)
		(layer "In2.Cu")
		(net "P3E_CPU0_PE2_SS_RXP<10>")
	)
	(segment
		(start 92.286328 -33.087056)
		(end 92.399866 -33.143698)
		(width 0.127)
		(layer "In2.Cu")
		(net "P3E_CPU0_PE2_SS_RXP<10>")
	)
	(segment
		(start 104.78643 -1.499108)
		(end 104.56672 -1.646682)
		(width 0.127)
		(layer "In2.Cu")
		(net "P3E_CPU0_PE2_SS_RXP<10>")
	)
	(segment
		(start 100.9269 -13.932408)
		(end 100.9269 -14.19352)
		(width 0.127)
		(layer "In2.Cu")
		(net "P3E_CPU0_PE2_SS_RXP<10>")
	)
	(segment
		(start 100.9269 -14.19352)
		(end 100.87737 -14.448282)
		(width 0.127)
		(layer "In2.Cu")
		(net "P3E_CPU0_PE2_SS_RXP<10>")
	)
	(segment
		(start 100.97643 -6.7437)
		(end 100.94087 -6.8834)
		(width 0.127)
		(layer "In2.Cu")
		(net "P3E_CPU0_PE2_SS_RXP<10>")
	)
	(segment
		(start 111.69142 -0.28321)
		(end 105.145332 -1.435862)
		(width 0.127)
		(layer "In2.Cu")
		(net "P3E_CPU0_PE2_SS_RXP<10>")
	)
	(segment
		(start 91.72702 -30.20822)
		(end 91.726766 -30.20822)
		(width 0.127)
		(layer "In2.Cu")
		(net "P3E_CPU0_PE2_SS_RXP<10>")
	)
	(segment
		(start 101.68382 -12.418568)
		(end 101.461824 -12.640564)
		(width 0.127)
		(layer "In2.Cu")
		(net "P3E_CPU0_PE2_SS_RXP<10>")
	)
	(segment
		(start 115.945158 3.49123)
		(end 114.852196 1.929892)
		(width 0.127)
		(layer "In2.Cu")
		(net "P3E_CPU0_PE2_SS_RXP<10>")
	)
	(segment
		(start 116.1288 4.755388)
		(end 116.123974 4.50469)
		(width 0.127)
		(layer "In2.Cu")
		(net "P3E_CPU0_PE2_SS_RXP<10>")
	)
	(segment
		(start 114.852196 1.929892)
		(end 111.69142 -0.28321)
		(width 0.127)
		(layer "In2.Cu")
		(net "P3E_CPU0_PE2_SS_RXP<10>")
	)
	(segment
		(start 95.152972 -22.623526)
		(end 93.0148 -26.895552)
		(width 0.127)
		(layer "In2.Cu")
		(net "P3E_CPU0_PE2_SS_RXP<10>")
	)
	(segment
		(start 92.943172 -27.313382)
		(end 92.859098 -27.805888)
		(width 0.127)
		(layer "In2.Cu")
		(net "P3E_CPU0_PE2_SS_RXP<10>")
	)
	(arc
		(start 92.75699 -28.0416)
		(mid 92.514649 -28.498816)
		(end 92.20454 -28.913074)
		(width 0.127)
		(layer "In2.Cu")
		(net "P3E_CPU0_PE2_SS_RXP<10>")
	)
	(arc
		(start 92.20454 -28.913074)
		(mid 92.05561 -29.150098)
		(end 91.988386 -29.421836)
		(width 0.127)
		(layer "In2.Cu")
		(net "P3E_CPU0_PE2_SS_RXP<10>")
	)
	(arc
		(start 100.94087 -7.115302)
		(mid 101.054637 -7.688661)
		(end 101.379274 -8.174736)
		(width 0.127)
		(layer "In2.Cu")
		(net "P3E_CPU0_PE2_SS_RXP<10>")
	)
	(arc
		(start 91.866212 -32.274764)
		(mid 91.944098 -32.749258)
		(end 92.286328 -33.087056)
		(width 0.127)
		(layer "In2.Cu")
		(net "P3E_CPU0_PE2_SS_RXP<10>")
	)
	(arc
		(start 91.746832 -31.568898)
		(mid 91.863375 -31.912216)
		(end 91.866212 -32.274764)
		(width 0.127)
		(layer "In2.Cu")
		(net "P3E_CPU0_PE2_SS_RXP<10>")
	)
	(arc
		(start 101.486208 -8.28294)
		(mid 101.797764 -8.748938)
		(end 101.90734 -9.298686)
		(width 0.127)
		(layer "In2.Cu")
		(net "P3E_CPU0_PE2_SS_RXP<10>")
	)
	(arc
		(start 91.580716 -30.709108)
		(mid 91.573969 -30.936986)
		(end 91.601798 -31.16326)
		(width 0.127)
		(layer "In2.Cu")
		(net "P3E_CPU0_PE2_SS_RXP<10>")
	)
	(arc
		(start 91.601798 -31.16326)
		(mid 91.659727 -31.371295)
		(end 91.746832 -31.568898)
		(width 0.127)
		(layer "In2.Cu")
		(net "P3E_CPU0_PE2_SS_RXP<10>")
	)
	(arc
		(start 91.988386 -29.421836)
		(mid 91.904602 -29.83062)
		(end 91.72702 -30.20822)
		(width 0.127)
		(layer "In2.Cu")
		(net "P3E_CPU0_PE2_SS_RXP<10>")
	)
	(arc
		(start 115.75034 5.206492)
		(mid 116.025506 5.053087)
		(end 116.1288 4.755388)
		(width 0.127)
		(layer "In2.Cu")
		(net "P3E_CPU0_PE2_SS_RXP<10>")
	)
	(arc
		(start 91.717622 -30.222698)
		(mid 91.628561 -30.460102)
		(end 91.580716 -30.709108)
		(width 0.127)
		(layer "In2.Cu")
		(net "P3E_CPU0_PE2_SS_RXP<10>")
	)
	(arc
		(start 92.40012 -33.143952)
		(mid 92.463813 -33.217258)
		(end 92.457016 -33.314132)
		(width 0.127)
		(layer "In2.Cu")
		(net "P3E_CPU0_PE2_SS_RXP<10>")
	)
	(arc
		(start 101.461824 -12.640564)
		(mid 101.0659 -13.233296)
		(end 100.9269 -13.932408)
		(width 0.127)
		(layer "In2.Cu")
		(net "P3E_CPU0_PE2_SS_RXP<10>")
	)
	(arc
		(start 91.726766 -30.20822)
		(mid 91.722212 -30.21547)
		(end 91.717622 -30.222698)
		(width 0.127)
		(layer "In2.Cu")
		(net "P3E_CPU0_PE2_SS_RXP<10>")
	)
	(arc
		(start 101.90734 -11.87958)
		(mid 101.849215 -12.171325)
		(end 101.68382 -12.418568)
		(width 0.127)
		(layer "In2.Cu")
		(net "P3E_CPU0_PE2_SS_RXP<10>")
	)
	(via
		(at 81.222088 5.165852)
		(size 0.508)
		(drill 0.254)
		(layers "F.Cu" "B.Cu")
		(net "P3E_CPU0_PE2_SS_RXP<1>")
	)
	(segment
		(start 81.577688 6.58368)
		(end 81.577688 5.775452)
		(width 0.127)
		(layer "B.Cu")
		(net "P3E_CPU0_PE2_SS_RXP<1>")
	)
	(segment
		(start 81.551018 7.68731)
		(end 81.490058 7.084822)
		(width 0.127)
		(layer "B.Cu")
		(net "P3E_CPU0_PE2_SS_RXP<1>")
	)
	(segment
		(start 82.227674 10.383266)
		(end 82.227674 10.10539)
		(width 0.127)
		(layer "B.Cu")
		(net "P3E_CPU0_PE2_SS_RXP<1>")
	)
	(segment
		(start 81.490058 7.084822)
		(end 81.577688 6.58368)
		(width 0.127)
		(layer "B.Cu")
		(net "P3E_CPU0_PE2_SS_RXP<1>")
	)
	(segment
		(start 81.980024 12.514072)
		(end 81.980024 10.981182)
		(width 0.127)
		(layer "B.Cu")
		(net "P3E_CPU0_PE2_SS_RXP<1>")
	)
	(segment
		(start 81.60639 8.222996)
		(end 81.551018 7.68731)
		(width 0.127)
		(layer "B.Cu")
		(net "P3E_CPU0_PE2_SS_RXP<1>")
	)
	(arc
		(start 81.94802 9.247378)
		(mid 81.720946 8.753952)
		(end 81.60639 8.222996)
		(width 0.127)
		(layer "B.Cu")
		(net "P3E_CPU0_PE2_SS_RXP<1>")
	)
	(arc
		(start 82.227674 10.10539)
		(mid 82.156012 9.654161)
		(end 81.94802 9.247378)
		(width 0.127)
		(layer "B.Cu")
		(net "P3E_CPU0_PE2_SS_RXP<1>")
	)
	(arc
		(start 81.577688 5.775452)
		(mid 81.482287 5.422589)
		(end 81.222088 5.165852)
		(width 0.127)
		(layer "B.Cu")
		(net "P3E_CPU0_PE2_SS_RXP<1>")
	)
	(arc
		(start 82.103722 10.682478)
		(mid 82.195449 10.545198)
		(end 82.227674 10.383266)
		(width 0.127)
		(layer "B.Cu")
		(net "P3E_CPU0_PE2_SS_RXP<1>")
	)
	(arc
		(start 81.980024 10.981182)
		(mid 82.012177 10.819536)
		(end 82.103722 10.682478)
		(width 0.127)
		(layer "B.Cu")
		(net "P3E_CPU0_PE2_SS_RXP<1>")
	)
	(segment
		(start 62.525148 -12.911836)
		(end 62.441836 -12.828778)
		(width 0.127)
		(layer "In2.Cu")
		(net "P3E_CPU0_PE2_SS_RXP<1>")
	)
	(segment
		(start 62.992254 -6.421882)
		(end 63.037466 -6.238494)
		(width 0.127)
		(layer "In2.Cu")
		(net "P3E_CPU0_PE2_SS_RXP<1>")
	)
	(segment
		(start 53.501544 -26.03881)
		(end 53.727858 -25.998932)
		(width 0.127)
		(layer "In2.Cu")
		(net "P3E_CPU0_PE2_SS_RXP<1>")
	)
	(segment
		(start 53.946552 -25.686766)
		(end 53.90642 -25.460452)
		(width 0.127)
		(layer "In2.Cu")
		(net "P3E_CPU0_PE2_SS_RXP<1>")
	)
	(segment
		(start 62.64021 -15.16761)
		(end 62.93231 -14.267434)
		(width 0.127)
		(layer "In2.Cu")
		(net "P3E_CPU0_PE2_SS_RXP<1>")
	)
	(segment
		(start 54.351428 -25.108408)
		(end 54.686454 -24.630126)
		(width 0.127)
		(layer "In2.Cu")
		(net "P3E_CPU0_PE2_SS_RXP<1>")
	)
	(segment
		(start 63.037466 -6.238494)
		(end 63.155068 -6.006084)
		(width 0.127)
		(layer "In2.Cu")
		(net "P3E_CPU0_PE2_SS_RXP<1>")
	)
	(segment
		(start 60.263532 -20.72513)
		(end 61.043058 -19.300444)
		(width 0.127)
		(layer "In2.Cu")
		(net "P3E_CPU0_PE2_SS_RXP<1>")
	)
	(segment
		(start 81.269586 3.535934)
		(end 81.51114 3.88112)
		(width 0.127)
		(layer "In2.Cu")
		(net "P3E_CPU0_PE2_SS_RXP<1>")
	)
	(segment
		(start 53.90642 -25.460452)
		(end 54.125114 -25.148286)
		(width 0.127)
		(layer "In2.Cu")
		(net "P3E_CPU0_PE2_SS_RXP<1>")
	)
	(segment
		(start 53.322728 -26.57729)
		(end 53.28285 -26.350976)
		(width 0.127)
		(layer "In2.Cu")
		(net "P3E_CPU0_PE2_SS_RXP<1>")
	)
	(segment
		(start 62.933834 -6.88721)
		(end 62.933834 -6.753606)
		(width 0.127)
		(layer "In2.Cu")
		(net "P3E_CPU0_PE2_SS_RXP<1>")
	)
	(segment
		(start 52.96027 -27.705304)
		(end 53.104288 -26.889456)
		(width 0.127)
		(layer "In2.Cu")
		(net "P3E_CPU0_PE2_SS_RXP<1>")
	)
	(segment
		(start 63.155068 -6.006084)
		(end 63.628778 -5.47624)
		(width 0.127)
		(layer "In2.Cu")
		(net "P3E_CPU0_PE2_SS_RXP<1>")
	)
	(segment
		(start 61.043058 -19.300444)
		(end 62.64021 -15.16761)
		(width 0.127)
		(layer "In2.Cu")
		(net "P3E_CPU0_PE2_SS_RXP<1>")
	)
	(segment
		(start 81.588102 4.316984)
		(end 81.600548 4.715002)
		(width 0.127)
		(layer "In2.Cu")
		(net "P3E_CPU0_PE2_SS_RXP<1>")
	)
	(segment
		(start 62.93231 -13.894562)
		(end 62.932056 -13.894816)
		(width 0.127)
		(layer "In2.Cu")
		(net "P3E_CPU0_PE2_SS_RXP<1>")
	)
	(segment
		(start 53.727858 -25.998932)
		(end 53.946552 -25.686766)
		(width 0.127)
		(layer "In2.Cu")
		(net "P3E_CPU0_PE2_SS_RXP<1>")
	)
	(segment
		(start 72.893174 1.378458)
		(end 74.995532 1.749044)
		(width 0.127)
		(layer "In2.Cu")
		(net "P3E_CPU0_PE2_SS_RXP<1>")
	)
	(segment
		(start 67.453764 -2.430272)
		(end 72.893174 1.378458)
		(width 0.127)
		(layer "In2.Cu")
		(net "P3E_CPU0_PE2_SS_RXP<1>")
	)
	(segment
		(start 53.080412 -32.069786)
		(end 53.457856 -32.825436)
		(width 0.127)
		(layer "In2.Cu")
		(net "P3E_CPU0_PE2_SS_RXP<1>")
	)
	(segment
		(start 63.628778 -5.47624)
		(end 67.453764 -2.430272)
		(width 0.127)
		(layer "In2.Cu")
		(net "P3E_CPU0_PE2_SS_RXP<1>")
	)
	(segment
		(start 53.104288 -26.889456)
		(end 53.322728 -26.57729)
		(width 0.127)
		(layer "In2.Cu")
		(net "P3E_CPU0_PE2_SS_RXP<1>")
	)
	(segment
		(start 61.945774 -11.63066)
		(end 61.945774 -9.472676)
		(width 0.127)
		(layer "In2.Cu")
		(net "P3E_CPU0_PE2_SS_RXP<1>")
	)
	(segment
		(start 54.686454 -24.630126)
		(end 60.263532 -20.72513)
		(width 0.127)
		(layer "In2.Cu")
		(net "P3E_CPU0_PE2_SS_RXP<1>")
	)
	(segment
		(start 53.628036 -32.882332)
		(end 53.62829 -32.882332)
		(width 0.127)
		(layer "In2.Cu")
		(net "P3E_CPU0_PE2_SS_RXP<1>")
	)
	(segment
		(start 54.125114 -25.148286)
		(end 54.351428 -25.108408)
		(width 0.127)
		(layer "In2.Cu")
		(net "P3E_CPU0_PE2_SS_RXP<1>")
	)
	(segment
		(start 79.970122 2.626106)
		(end 81.269586 3.535934)
		(width 0.127)
		(layer "In2.Cu")
		(net "P3E_CPU0_PE2_SS_RXP<1>")
	)
	(segment
		(start 62.933834 -6.753606)
		(end 62.992254 -6.421882)
		(width 0.127)
		(layer "In2.Cu")
		(net "P3E_CPU0_PE2_SS_RXP<1>")
	)
	(segment
		(start 81.51114 3.88112)
		(end 81.588102 4.316984)
		(width 0.127)
		(layer "In2.Cu")
		(net "P3E_CPU0_PE2_SS_RXP<1>")
	)
	(segment
		(start 53.28285 -26.350976)
		(end 53.501544 -26.03881)
		(width 0.127)
		(layer "In2.Cu")
		(net "P3E_CPU0_PE2_SS_RXP<1>")
	)
	(segment
		(start 62.93358 -7.2771)
		(end 62.93358 -6.96468)
		(width 0.127)
		(layer "In2.Cu")
		(net "P3E_CPU0_PE2_SS_RXP<1>")
	)
	(segment
		(start 62.56782 -7.97052)
		(end 62.701932 -7.836408)
		(width 0.127)
		(layer "In2.Cu")
		(net "P3E_CPU0_PE2_SS_RXP<1>")
	)
	(segment
		(start 74.995532 1.749044)
		(end 79.970122 2.626106)
		(width 0.127)
		(layer "In2.Cu")
		(net "P3E_CPU0_PE2_SS_RXP<1>")
	)
	(segment
		(start 62.93231 -14.267434)
		(end 62.93231 -13.894562)
		(width 0.127)
		(layer "In2.Cu")
		(net "P3E_CPU0_PE2_SS_RXP<1>")
	)
	(segment
		(start 62.93358 -6.96468)
		(end 62.933834 -6.88721)
		(width 0.127)
		(layer "In2.Cu")
		(net "P3E_CPU0_PE2_SS_RXP<1>")
	)
	(segment
		(start 53.62829 -32.882332)
		(end 53.742082 -32.82569)
		(width 0.127)
		(layer "In2.Cu")
		(net "P3E_CPU0_PE2_SS_RXP<1>")
	)
	(arc
		(start 53.742082 -32.82569)
		(mid 53.947969 -32.609999)
		(end 53.970174 -32.31261)
		(width 0.127)
		(layer "In2.Cu")
		(net "P3E_CPU0_PE2_SS_RXP<1>")
	)
	(arc
		(start 81.600548 4.71678)
		(mid 81.496708 5.013315)
		(end 81.222088 5.165852)
		(width 0.127)
		(layer "In2.Cu")
		(net "P3E_CPU0_PE2_SS_RXP<1>")
	)
	(arc
		(start 53.457856 -32.825436)
		(mid 53.531162 -32.889129)
		(end 53.628036 -32.882332)
		(width 0.127)
		(layer "In2.Cu")
		(net "P3E_CPU0_PE2_SS_RXP<1>")
	)
	(arc
		(start 61.945774 -9.472676)
		(mid 62.107439 -8.659751)
		(end 62.56782 -7.97052)
		(width 0.127)
		(layer "In2.Cu")
		(net "P3E_CPU0_PE2_SS_RXP<1>")
	)
	(arc
		(start 53.916326 -29.672534)
		(mid 53.896543 -29.226498)
		(end 53.649372 -28.854654)
		(width 0.127)
		(layer "In2.Cu")
		(net "P3E_CPU0_PE2_SS_RXP<1>")
	)
	(arc
		(start 62.932056 -13.894816)
		(mid 62.826355 -13.362861)
		(end 62.525148 -12.911836)
		(width 0.127)
		(layer "In2.Cu")
		(net "P3E_CPU0_PE2_SS_RXP<1>")
	)
	(arc
		(start 53.970174 -32.31261)
		(mid 53.778677 -30.995925)
		(end 53.916326 -29.672534)
		(width 0.127)
		(layer "In2.Cu")
		(net "P3E_CPU0_PE2_SS_RXP<1>")
	)
	(arc
		(start 53.649372 -28.854654)
		(mid 53.212338 -28.335427)
		(end 52.96027 -27.705304)
		(width 0.127)
		(layer "In2.Cu")
		(net "P3E_CPU0_PE2_SS_RXP<1>")
	)
	(arc
		(start 62.701932 -7.836408)
		(mid 62.873395 -7.579795)
		(end 62.93358 -7.2771)
		(width 0.127)
		(layer "In2.Cu")
		(net "P3E_CPU0_PE2_SS_RXP<1>")
	)
	(arc
		(start 81.600548 4.715002)
		(mid 81.600547 4.715891)
		(end 81.600548 4.71678)
		(width 0.127)
		(layer "In2.Cu")
		(net "P3E_CPU0_PE2_SS_RXP<1>")
	)
	(arc
		(start 62.441836 -12.828778)
		(mid 62.074567 -12.279076)
		(end 61.945774 -11.63066)
		(width 0.127)
		(layer "In2.Cu")
		(net "P3E_CPU0_PE2_SS_RXP<1>")
	)
	(via
		(at 78.631288 5.165852)
		(size 0.508)
		(drill 0.254)
		(layers "F.Cu" "B.Cu")
		(net "P3E_CPU0_PE2_SS_RXP<0>")
	)
	(segment
		(start 78.976982 7.410958)
		(end 78.986888 6.505702)
		(width 0.127)
		(layer "B.Cu")
		(net "P3E_CPU0_PE2_SS_RXP<0>")
	)
	(segment
		(start 78.953614 7.704836)
		(end 78.976982 7.410958)
		(width 0.127)
		(layer "B.Cu")
		(net "P3E_CPU0_PE2_SS_RXP<0>")
	)
	(segment
		(start 79.827628 10.243312)
		(end 79.827628 9.706102)
		(width 0.127)
		(layer "B.Cu")
		(net "P3E_CPU0_PE2_SS_RXP<0>")
	)
	(segment
		(start 78.986888 6.505702)
		(end 78.986888 5.775452)
		(width 0.127)
		(layer "B.Cu")
		(net "P3E_CPU0_PE2_SS_RXP<0>")
	)
	(segment
		(start 79.579978 12.514072)
		(end 79.579978 10.841228)
		(width 0.127)
		(layer "B.Cu")
		(net "P3E_CPU0_PE2_SS_RXP<0>")
	)
	(arc
		(start 79.579978 10.841228)
		(mid 79.612131 10.679582)
		(end 79.703676 10.542524)
		(width 0.127)
		(layer "B.Cu")
		(net "P3E_CPU0_PE2_SS_RXP<0>")
	)
	(arc
		(start 79.001366 8.082026)
		(mid 78.958198 7.895871)
		(end 78.953614 7.704836)
		(width 0.127)
		(layer "B.Cu")
		(net "P3E_CPU0_PE2_SS_RXP<0>")
	)
	(arc
		(start 79.641954 9.258046)
		(mid 79.271845 8.697172)
		(end 79.001366 8.082026)
		(width 0.127)
		(layer "B.Cu")
		(net "P3E_CPU0_PE2_SS_RXP<0>")
	)
	(arc
		(start 79.827628 9.706102)
		(mid 79.779373 9.463598)
		(end 79.641954 9.258046)
		(width 0.127)
		(layer "B.Cu")
		(net "P3E_CPU0_PE2_SS_RXP<0>")
	)
	(arc
		(start 78.986888 5.775452)
		(mid 78.891487 5.422589)
		(end 78.631288 5.165852)
		(width 0.127)
		(layer "B.Cu")
		(net "P3E_CPU0_PE2_SS_RXP<0>")
	)
	(arc
		(start 79.703676 10.542524)
		(mid 79.795403 10.405244)
		(end 79.827628 10.243312)
		(width 0.127)
		(layer "B.Cu")
		(net "P3E_CPU0_PE2_SS_RXP<0>")
	)
	(segment
		(start 48.080422 -34.070036)
		(end 48.45812 -33.313878)
		(width 0.127)
		(layer "In2.Cu")
		(net "P3E_CPU0_PE2_SS_RXP<0>")
	)
	(segment
		(start 57.486296 -19.754596)
		(end 57.62371 -19.470116)
		(width 0.127)
		(layer "In2.Cu")
		(net "P3E_CPU0_PE2_SS_RXP<0>")
	)
	(segment
		(start 47.87138 -32.35706)
		(end 47.916592 -31.707074)
		(width 0.127)
		(layer "In2.Cu")
		(net "P3E_CPU0_PE2_SS_RXP<0>")
	)
	(segment
		(start 57.946544 -11.63066)
		(end 57.946544 -9.472676)
		(width 0.127)
		(layer "In2.Cu")
		(net "P3E_CPU0_PE2_SS_RXP<0>")
	)
	(segment
		(start 58.934604 -6.88721)
		(end 58.934604 -6.736588)
		(width 0.127)
		(layer "In2.Cu")
		(net "P3E_CPU0_PE2_SS_RXP<0>")
	)
	(segment
		(start 78.986634 4.781804)
		(end 78.992984 4.834382)
		(width 0.127)
		(layer "In2.Cu")
		(net "P3E_CPU0_PE2_SS_RXP<0>")
	)
	(segment
		(start 59.450478 -5.857748)
		(end 60.0964 -5.2578)
		(width 0.127)
		(layer "In2.Cu")
		(net "P3E_CPU0_PE2_SS_RXP<0>")
	)
	(segment
		(start 51.213766 -24.23033)
		(end 51.241452 -24.194516)
		(width 0.127)
		(layer "In2.Cu")
		(net "P3E_CPU0_PE2_SS_RXP<0>")
	)
	(segment
		(start 60.0964 -5.2578)
		(end 64.346836 -1.315466)
		(width 0.127)
		(layer "In2.Cu")
		(net "P3E_CPU0_PE2_SS_RXP<0>")
	)
	(segment
		(start 59.434222 -5.872988)
		(end 59.450478 -5.857748)
		(width 0.127)
		(layer "In2.Cu")
		(net "P3E_CPU0_PE2_SS_RXP<0>")
	)
	(segment
		(start 78.99146 4.836414)
		(end 78.99146 4.838192)
		(width 0.127)
		(layer "In2.Cu")
		(net "P3E_CPU0_PE2_SS_RXP<0>")
	)
	(segment
		(start 49.009554 -27.061922)
		(end 51.213766 -24.23033)
		(width 0.127)
		(layer "In2.Cu")
		(net "P3E_CPU0_PE2_SS_RXP<0>")
	)
	(segment
		(start 57.211722 -20.08632)
		(end 57.486296 -19.754596)
		(width 0.127)
		(layer "In2.Cu")
		(net "P3E_CPU0_PE2_SS_RXP<0>")
	)
	(segment
		(start 48.937672 -27.835352)
		(end 48.984916 -27.328876)
		(width 0.127)
		(layer "In2.Cu")
		(net "P3E_CPU0_PE2_SS_RXP<0>")
	)
	(segment
		(start 70.369938 2.902204)
		(end 78.40218 4.318508)
		(width 0.127)
		(layer "In2.Cu")
		(net "P3E_CPU0_PE2_SS_RXP<0>")
	)
	(segment
		(start 58.93435 -7.2771)
		(end 58.93435 -6.96468)
		(width 0.127)
		(layer "In2.Cu")
		(net "P3E_CPU0_PE2_SS_RXP<0>")
	)
	(segment
		(start 57.6326 -19.4564)
		(end 57.932828 -18.625312)
		(width 0.127)
		(layer "In2.Cu")
		(net "P3E_CPU0_PE2_SS_RXP<0>")
	)
	(segment
		(start 78.40218 4.318508)
		(end 78.912212 4.675378)
		(width 0.127)
		(layer "In2.Cu")
		(net "P3E_CPU0_PE2_SS_RXP<0>")
	)
	(segment
		(start 58.93308 -13.894562)
		(end 58.932826 -13.894816)
		(width 0.127)
		(layer "In2.Cu")
		(net "P3E_CPU0_PE2_SS_RXP<0>")
	)
	(segment
		(start 78.912212 4.675378)
		(end 78.912466 4.67614)
		(width 0.127)
		(layer "In2.Cu")
		(net "P3E_CPU0_PE2_SS_RXP<0>")
	)
	(segment
		(start 58.934604 -6.736588)
		(end 59.003946 -6.5024)
		(width 0.127)
		(layer "In2.Cu")
		(net "P3E_CPU0_PE2_SS_RXP<0>")
	)
	(segment
		(start 78.912974 4.676902)
		(end 78.986634 4.781804)
		(width 0.127)
		(layer "In2.Cu")
		(net "P3E_CPU0_PE2_SS_RXP<0>")
	)
	(segment
		(start 57.932828 -18.625312)
		(end 58.779156 -15.161006)
		(width 0.127)
		(layer "In2.Cu")
		(net "P3E_CPU0_PE2_SS_RXP<0>")
	)
	(segment
		(start 48.556672 -28.300934)
		(end 48.741838 -28.116022)
		(width 0.127)
		(layer "In2.Cu")
		(net "P3E_CPU0_PE2_SS_RXP<0>")
	)
	(segment
		(start 56.877204 -20.317206)
		(end 57.211722 -20.08632)
		(width 0.127)
		(layer "In2.Cu")
		(net "P3E_CPU0_PE2_SS_RXP<0>")
	)
	(segment
		(start 59.04484 -6.36524)
		(end 59.434222 -5.872988)
		(width 0.127)
		(layer "In2.Cu")
		(net "P3E_CPU0_PE2_SS_RXP<0>")
	)
	(segment
		(start 48.3997 -33.142936)
		(end 48.287686 -33.087056)
		(width 0.127)
		(layer "In2.Cu")
		(net "P3E_CPU0_PE2_SS_RXP<0>")
	)
	(segment
		(start 58.93435 -6.96468)
		(end 58.934604 -6.88721)
		(width 0.127)
		(layer "In2.Cu")
		(net "P3E_CPU0_PE2_SS_RXP<0>")
	)
	(segment
		(start 78.992984 4.83616)
		(end 78.99146 4.836414)
		(width 0.127)
		(layer "In2.Cu")
		(net "P3E_CPU0_PE2_SS_RXP<0>")
	)
	(segment
		(start 58.56859 -7.97052)
		(end 58.702702 -7.836408)
		(width 0.127)
		(layer "In2.Cu")
		(net "P3E_CPU0_PE2_SS_RXP<0>")
	)
	(segment
		(start 48.401224 -33.143444)
		(end 48.40097 -33.143444)
		(width 0.127)
		(layer "In2.Cu")
		(net "P3E_CPU0_PE2_SS_RXP<0>")
	)
	(segment
		(start 58.779156 -15.161006)
		(end 58.93308 -14.288008)
		(width 0.127)
		(layer "In2.Cu")
		(net "P3E_CPU0_PE2_SS_RXP<0>")
	)
	(segment
		(start 57.62371 -19.470116)
		(end 57.6326 -19.4564)
		(width 0.127)
		(layer "In2.Cu")
		(net "P3E_CPU0_PE2_SS_RXP<0>")
	)
	(segment
		(start 51.241452 -24.194516)
		(end 51.499008 -24.017224)
		(width 0.127)
		(layer "In2.Cu")
		(net "P3E_CPU0_PE2_SS_RXP<0>")
	)
	(segment
		(start 78.992984 4.834382)
		(end 78.992984 4.83616)
		(width 0.127)
		(layer "In2.Cu")
		(net "P3E_CPU0_PE2_SS_RXP<0>")
	)
	(segment
		(start 78.912466 4.67614)
		(end 78.912974 4.676902)
		(width 0.127)
		(layer "In2.Cu")
		(net "P3E_CPU0_PE2_SS_RXP<0>")
	)
	(segment
		(start 59.003946 -6.5024)
		(end 59.04484 -6.36524)
		(width 0.127)
		(layer "In2.Cu")
		(net "P3E_CPU0_PE2_SS_RXP<0>")
	)
	(segment
		(start 58.93308 -14.288008)
		(end 58.93308 -13.894562)
		(width 0.127)
		(layer "In2.Cu")
		(net "P3E_CPU0_PE2_SS_RXP<0>")
	)
	(segment
		(start 51.499008 -24.017224)
		(end 56.877204 -20.317206)
		(width 0.127)
		(layer "In2.Cu")
		(net "P3E_CPU0_PE2_SS_RXP<0>")
	)
	(segment
		(start 64.346836 -1.315466)
		(end 70.369938 2.902204)
		(width 0.127)
		(layer "In2.Cu")
		(net "P3E_CPU0_PE2_SS_RXP<0>")
	)
	(segment
		(start 48.40097 -33.143444)
		(end 48.3997 -33.142936)
		(width 0.127)
		(layer "In2.Cu")
		(net "P3E_CPU0_PE2_SS_RXP<0>")
	)
	(segment
		(start 48.741838 -28.116022)
		(end 48.937672 -27.835352)
		(width 0.127)
		(layer "In2.Cu")
		(net "P3E_CPU0_PE2_SS_RXP<0>")
	)
	(segment
		(start 48.984916 -27.328876)
		(end 49.009554 -27.061922)
		(width 0.127)
		(layer "In2.Cu")
		(net "P3E_CPU0_PE2_SS_RXP<0>")
	)
	(segment
		(start 58.525918 -12.911836)
		(end 58.442606 -12.828778)
		(width 0.127)
		(layer "In2.Cu")
		(net "P3E_CPU0_PE2_SS_RXP<0>")
	)
	(arc
		(start 48.287686 -33.087056)
		(mid 47.968947 -32.785128)
		(end 47.87138 -32.35706)
		(width 0.127)
		(layer "In2.Cu")
		(net "P3E_CPU0_PE2_SS_RXP<0>")
	)
	(arc
		(start 47.97298 -29.64434)
		(mid 48.108747 -28.951263)
		(end 48.495966 -28.360624)
		(width 0.127)
		(layer "In2.Cu")
		(net "P3E_CPU0_PE2_SS_RXP<0>")
	)
	(arc
		(start 78.99146 4.838192)
		(mid 78.874772 5.071734)
		(end 78.631288 5.165852)
		(width 0.127)
		(layer "In2.Cu")
		(net "P3E_CPU0_PE2_SS_RXP<0>")
	)
	(arc
		(start 58.932826 -13.894816)
		(mid 58.827125 -13.362861)
		(end 58.525918 -12.911836)
		(width 0.127)
		(layer "In2.Cu")
		(net "P3E_CPU0_PE2_SS_RXP<0>")
	)
	(arc
		(start 58.442606 -12.828778)
		(mid 58.075337 -12.279076)
		(end 57.946544 -11.63066)
		(width 0.127)
		(layer "In2.Cu")
		(net "P3E_CPU0_PE2_SS_RXP<0>")
	)
	(arc
		(start 57.946544 -9.472676)
		(mid 58.108209 -8.659751)
		(end 58.56859 -7.97052)
		(width 0.127)
		(layer "In2.Cu")
		(net "P3E_CPU0_PE2_SS_RXP<0>")
	)
	(arc
		(start 47.916592 -31.707074)
		(mid 47.966131 -30.67629)
		(end 47.97298 -29.64434)
		(width 0.127)
		(layer "In2.Cu")
		(net "P3E_CPU0_PE2_SS_RXP<0>")
	)
	(arc
		(start 48.45812 -33.313878)
		(mid 48.464879 -33.216933)
		(end 48.401224 -33.143444)
		(width 0.127)
		(layer "In2.Cu")
		(net "P3E_CPU0_PE2_SS_RXP<0>")
	)
	(arc
		(start 48.495966 -28.360624)
		(mid 48.525972 -28.330426)
		(end 48.556672 -28.300934)
		(width 0.127)
		(layer "In2.Cu")
		(net "P3E_CPU0_PE2_SS_RXP<0>")
	)
	(arc
		(start 58.702702 -7.836408)
		(mid 58.874165 -7.579795)
		(end 58.93435 -7.2771)
		(width 0.127)
		(layer "In2.Cu")
		(net "P3E_CPU0_PE2_SS_RXP<0>")
	)
	(via
		(at 114.17554 5.206492)
		(size 0.508)
		(drill 0.254)
		(layers "F.Cu" "B.Cu")
		(net "P3E_CPU0_PE2_SS_RXN<9>")
	)
	(segment
		(start 113.84407 8.201914)
		(end 113.84407 8.202168)
		(width 0.127)
		(layer "B.Cu")
		(net "P3E_CPU0_PE2_SS_RXN<9>")
	)
	(segment
		(start 113.84407 8.202168)
		(end 113.843562 8.202676)
		(width 0.127)
		(layer "B.Cu")
		(net "P3E_CPU0_PE2_SS_RXN<9>")
	)
	(segment
		(start 113.527586 10.30859)
		(end 113.527586 10.66038)
		(width 0.127)
		(layer "B.Cu")
		(net "P3E_CPU0_PE2_SS_RXN<9>")
	)
	(segment
		(start 113.81994 6.65099)
		(end 113.735104 7.136638)
		(width 0.127)
		(layer "B.Cu")
		(net "P3E_CPU0_PE2_SS_RXN<9>")
	)
	(segment
		(start 113.735104 7.136638)
		(end 113.791746 7.696962)
		(width 0.127)
		(layer "B.Cu")
		(net "P3E_CPU0_PE2_SS_RXN<9>")
	)
	(segment
		(start 113.81994 5.816092)
		(end 113.81994 6.65099)
		(width 0.127)
		(layer "B.Cu")
		(net "P3E_CPU0_PE2_SS_RXN<9>")
	)
	(segment
		(start 113.774982 11.257788)
		(end 113.774982 12.615672)
		(width 0.127)
		(layer "B.Cu")
		(net "P3E_CPU0_PE2_SS_RXN<9>")
	)
	(segment
		(start 113.791746 7.696962)
		(end 113.84407 8.201914)
		(width 0.127)
		(layer "B.Cu")
		(net "P3E_CPU0_PE2_SS_RXN<9>")
	)
	(segment
		(start 113.843562 8.202676)
		(end 113.843562 8.203438)
		(width 0.127)
		(layer "B.Cu")
		(net "P3E_CPU0_PE2_SS_RXN<9>")
	)
	(arc
		(start 113.843562 8.203438)
		(mid 113.811476 8.678038)
		(end 113.7158 9.144)
		(width 0.127)
		(layer "B.Cu")
		(net "P3E_CPU0_PE2_SS_RXN<9>")
	)
	(arc
		(start 113.527586 10.66038)
		(mid 113.559739 10.822026)
		(end 113.651284 10.959084)
		(width 0.127)
		(layer "B.Cu")
		(net "P3E_CPU0_PE2_SS_RXN<9>")
	)
	(arc
		(start 114.17554 5.206492)
		(mid 113.915325 5.463219)
		(end 113.81994 5.816092)
		(width 0.127)
		(layer "B.Cu")
		(net "P3E_CPU0_PE2_SS_RXN<9>")
	)
	(arc
		(start 113.7158 9.144)
		(mid 113.574947 9.71874)
		(end 113.527586 10.30859)
		(width 0.127)
		(layer "B.Cu")
		(net "P3E_CPU0_PE2_SS_RXN<9>")
	)
	(arc
		(start 113.651284 10.959084)
		(mid 113.742856 11.096131)
		(end 113.774982 11.257788)
		(width 0.127)
		(layer "B.Cu")
		(net "P3E_CPU0_PE2_SS_RXN<9>")
	)
	(segment
		(start 91.335606 -23.461472)
		(end 91.117166 -23.773638)
		(width 0.127)
		(layer "In2.Cu")
		(net "P3E_CPU0_PE2_SS_RXN<9>")
	)
	(segment
		(start 113.780062 4.445508)
		(end 112.677956 2.871724)
		(width 0.127)
		(layer "In2.Cu")
		(net "P3E_CPU0_PE2_SS_RXN<9>")
	)
	(segment
		(start 90.267028 -24.70404)
		(end 90.048588 -25.016206)
		(width 0.127)
		(layer "In2.Cu")
		(net "P3E_CPU0_PE2_SS_RXN<9>")
	)
	(segment
		(start 110.180374 1.122426)
		(end 102.610412 -0.211328)
		(width 0.127)
		(layer "In2.Cu")
		(net "P3E_CPU0_PE2_SS_RXN<9>")
	)
	(segment
		(start 90.088466 -25.24252)
		(end 89.870026 -25.554686)
		(width 0.127)
		(layer "In2.Cu")
		(net "P3E_CPU0_PE2_SS_RXN<9>")
	)
	(segment
		(start 89.643458 -25.594564)
		(end 89.425018 -25.90673)
		(width 0.127)
		(layer "In2.Cu")
		(net "P3E_CPU0_PE2_SS_RXN<9>")
	)
	(segment
		(start 102.610412 -0.211328)
		(end 101.411532 -0.487934)
		(width 0.127)
		(layer "In2.Cu")
		(net "P3E_CPU0_PE2_SS_RXN<9>")
	)
	(segment
		(start 113.849404 4.8387)
		(end 113.780062 4.445508)
		(width 0.127)
		(layer "In2.Cu")
		(net "P3E_CPU0_PE2_SS_RXN<9>")
	)
	(segment
		(start 98.891344 -2.8448)
		(end 97.626424 -4.651502)
		(width 0.127)
		(layer "In2.Cu")
		(net "P3E_CPU0_PE2_SS_RXN<9>")
	)
	(segment
		(start 90.712036 -24.351996)
		(end 90.493596 -24.664162)
		(width 0.127)
		(layer "In2.Cu")
		(net "P3E_CPU0_PE2_SS_RXN<9>")
	)
	(segment
		(start 96.229932 -16.188436)
		(end 91.295728 -23.235158)
		(width 0.127)
		(layer "In2.Cu")
		(net "P3E_CPU0_PE2_SS_RXN<9>")
	)
	(segment
		(start 88.5317 -32.882586)
		(end 88.531954 -32.882586)
		(width 0.127)
		(layer "In2.Cu")
		(net "P3E_CPU0_PE2_SS_RXN<9>")
	)
	(segment
		(start 97.23374 -6.87832)
		(end 97.23374 -7.115556)
		(width 0.127)
		(layer "In2.Cu")
		(net "P3E_CPU0_PE2_SS_RXN<9>")
	)
	(segment
		(start 97.21977 -13.932662)
		(end 97.21977 -14.19352)
		(width 0.127)
		(layer "In2.Cu")
		(net "P3E_CPU0_PE2_SS_RXN<9>")
	)
	(segment
		(start 98.20021 -9.29894)
		(end 98.20021 -11.87958)
		(width 0.127)
		(layer "In2.Cu")
		(net "P3E_CPU0_PE2_SS_RXN<9>")
	)
	(segment
		(start 114.17554 5.206492)
		(end 113.849404 4.85267)
		(width 0.127)
		(layer "In2.Cu")
		(net "P3E_CPU0_PE2_SS_RXN<9>")
	)
	(segment
		(start 101.411532 -0.487934)
		(end 100.6348 -0.7747)
		(width 0.127)
		(layer "In2.Cu")
		(net "P3E_CPU0_PE2_SS_RXN<9>")
	)
	(segment
		(start 91.295728 -23.235158)
		(end 91.335606 -23.461472)
		(width 0.127)
		(layer "In2.Cu")
		(net "P3E_CPU0_PE2_SS_RXN<9>")
	)
	(segment
		(start 97.626424 -4.651502)
		(end 97.23374 -6.87832)
		(width 0.127)
		(layer "In2.Cu")
		(net "P3E_CPU0_PE2_SS_RXN<9>")
	)
	(segment
		(start 113.849404 4.85267)
		(end 113.849404 4.8387)
		(width 0.127)
		(layer "In2.Cu")
		(net "P3E_CPU0_PE2_SS_RXN<9>")
	)
	(segment
		(start 97.891346 -12.625324)
		(end 97.66935 -12.84732)
		(width 0.127)
		(layer "In2.Cu")
		(net "P3E_CPU0_PE2_SS_RXN<9>")
	)
	(segment
		(start 90.672158 -24.125682)
		(end 90.712036 -24.351996)
		(width 0.127)
		(layer "In2.Cu")
		(net "P3E_CPU0_PE2_SS_RXN<9>")
	)
	(segment
		(start 88.702388 -32.82569)
		(end 89.079832 -32.069786)
		(width 0.127)
		(layer "In2.Cu")
		(net "P3E_CPU0_PE2_SS_RXN<9>")
	)
	(segment
		(start 91.117166 -23.773638)
		(end 90.890598 -23.813516)
		(width 0.127)
		(layer "In2.Cu")
		(net "P3E_CPU0_PE2_SS_RXN<9>")
	)
	(segment
		(start 97.04832 -14.81582)
		(end 96.229932 -16.188436)
		(width 0.127)
		(layer "In2.Cu")
		(net "P3E_CPU0_PE2_SS_RXN<9>")
	)
	(segment
		(start 112.677956 2.871724)
		(end 110.180374 1.122426)
		(width 0.127)
		(layer "In2.Cu")
		(net "P3E_CPU0_PE2_SS_RXN<9>")
	)
	(segment
		(start 99.6442 -1.651)
		(end 98.891344 -2.8448)
		(width 0.127)
		(layer "In2.Cu")
		(net "P3E_CPU0_PE2_SS_RXN<9>")
	)
	(segment
		(start 90.048588 -25.016206)
		(end 90.088466 -25.24252)
		(width 0.127)
		(layer "In2.Cu")
		(net "P3E_CPU0_PE2_SS_RXN<9>")
	)
	(segment
		(start 89.870026 -25.554686)
		(end 89.643458 -25.594564)
		(width 0.127)
		(layer "In2.Cu")
		(net "P3E_CPU0_PE2_SS_RXN<9>")
	)
	(segment
		(start 90.493596 -24.664162)
		(end 90.267028 -24.70404)
		(width 0.127)
		(layer "In2.Cu")
		(net "P3E_CPU0_PE2_SS_RXN<9>")
	)
	(segment
		(start 97.5868 -7.96798)
		(end 97.693734 -8.076184)
		(width 0.127)
		(layer "In2.Cu")
		(net "P3E_CPU0_PE2_SS_RXN<9>")
	)
	(segment
		(start 88.417908 -32.82569)
		(end 88.5317 -32.882586)
		(width 0.127)
		(layer "In2.Cu")
		(net "P3E_CPU0_PE2_SS_RXN<9>")
	)
	(segment
		(start 100.6348 -0.7747)
		(end 99.6442 -1.651)
		(width 0.127)
		(layer "In2.Cu")
		(net "P3E_CPU0_PE2_SS_RXN<9>")
	)
	(segment
		(start 90.890598 -23.813516)
		(end 90.672158 -24.125682)
		(width 0.127)
		(layer "In2.Cu")
		(net "P3E_CPU0_PE2_SS_RXN<9>")
	)
	(arc
		(start 89.134188 -27.225498)
		(mid 89.148781 -27.699715)
		(end 89.02573 -28.157932)
		(width 0.127)
		(layer "In2.Cu")
		(net "P3E_CPU0_PE2_SS_RXN<9>")
	)
	(arc
		(start 97.66935 -12.84732)
		(mid 97.336624 -13.345279)
		(end 97.21977 -13.932662)
		(width 0.127)
		(layer "In2.Cu")
		(net "P3E_CPU0_PE2_SS_RXN<9>")
	)
	(arc
		(start 87.97544 -30.36316)
		(mid 87.908567 -30.547309)
		(end 87.872316 -30.739842)
		(width 0.127)
		(layer "In2.Cu")
		(net "P3E_CPU0_PE2_SS_RXN<9>")
	)
	(arc
		(start 97.23374 -7.115556)
		(mid 97.325502 -7.576875)
		(end 97.5868 -7.96798)
		(width 0.127)
		(layer "In2.Cu")
		(net "P3E_CPU0_PE2_SS_RXN<9>")
	)
	(arc
		(start 87.889334 -31.105602)
		(mid 87.935834 -31.273257)
		(end 88.00592 -31.4325)
		(width 0.127)
		(layer "In2.Cu")
		(net "P3E_CPU0_PE2_SS_RXN<9>")
	)
	(arc
		(start 97.693734 -8.076184)
		(mid 98.068586 -8.637189)
		(end 98.20021 -9.29894)
		(width 0.127)
		(layer "In2.Cu")
		(net "P3E_CPU0_PE2_SS_RXN<9>")
	)
	(arc
		(start 87.872316 -30.739842)
		(mid 87.866911 -30.923369)
		(end 87.889334 -31.105602)
		(width 0.127)
		(layer "In2.Cu")
		(net "P3E_CPU0_PE2_SS_RXN<9>")
	)
	(arc
		(start 88.531954 -32.882586)
		(mid 88.62901 -32.889527)
		(end 88.702388 -32.82569)
		(width 0.127)
		(layer "In2.Cu")
		(net "P3E_CPU0_PE2_SS_RXN<9>")
	)
	(arc
		(start 89.02573 -28.157932)
		(mid 88.762237 -28.655255)
		(end 88.42502 -29.10586)
		(width 0.127)
		(layer "In2.Cu")
		(net "P3E_CPU0_PE2_SS_RXN<9>")
	)
	(arc
		(start 89.425018 -25.90673)
		(mid 89.147931 -26.537083)
		(end 89.134188 -27.225498)
		(width 0.127)
		(layer "In2.Cu")
		(net "P3E_CPU0_PE2_SS_RXN<9>")
	)
	(arc
		(start 88.00592 -31.4325)
		(mid 88.152199 -31.863665)
		(end 88.15578 -32.31896)
		(width 0.127)
		(layer "In2.Cu")
		(net "P3E_CPU0_PE2_SS_RXN<9>")
	)
	(arc
		(start 98.20021 -11.87958)
		(mid 98.119933 -12.283161)
		(end 97.891346 -12.625324)
		(width 0.127)
		(layer "In2.Cu")
		(net "P3E_CPU0_PE2_SS_RXN<9>")
	)
	(arc
		(start 88.28024 -29.44622)
		(mid 88.182526 -29.922871)
		(end 87.97544 -30.36316)
		(width 0.127)
		(layer "In2.Cu")
		(net "P3E_CPU0_PE2_SS_RXN<9>")
	)
	(arc
		(start 97.21977 -14.19352)
		(mid 97.176125 -14.516264)
		(end 97.04832 -14.81582)
		(width 0.127)
		(layer "In2.Cu")
		(net "P3E_CPU0_PE2_SS_RXN<9>")
	)
	(arc
		(start 88.42502 -29.10586)
		(mid 88.32528 -29.264407)
		(end 88.28024 -29.44622)
		(width 0.127)
		(layer "In2.Cu")
		(net "P3E_CPU0_PE2_SS_RXN<9>")
	)
	(arc
		(start 88.15578 -32.31896)
		(mid 88.204355 -32.615005)
		(end 88.417908 -32.82569)
		(width 0.127)
		(layer "In2.Cu")
		(net "P3E_CPU0_PE2_SS_RXN<9>")
	)
	(via
		(at 111.58474 5.206492)
		(size 0.508)
		(drill 0.254)
		(layers "F.Cu" "B.Cu")
		(net "P3E_CPU0_PE2_SS_RXN<8>")
	)
	(segment
		(start 111.219234 7.465314)
		(end 111.195104 7.769352)
		(width 0.127)
		(layer "B.Cu")
		(net "P3E_CPU0_PE2_SS_RXN<8>")
	)
	(segment
		(start 111.22914 6.54812)
		(end 111.219234 7.465314)
		(width 0.127)
		(layer "B.Cu")
		(net "P3E_CPU0_PE2_SS_RXN<8>")
	)
	(segment
		(start 111.2266 5.74421)
		(end 111.22914 5.816092)
		(width 0.127)
		(layer "B.Cu")
		(net "P3E_CPU0_PE2_SS_RXN<8>")
	)
	(segment
		(start 111.251492 11.022838)
		(end 111.251746 11.023092)
		(width 0.127)
		(layer "B.Cu")
		(net "P3E_CPU0_PE2_SS_RXN<8>")
	)
	(segment
		(start 111.37519 11.321542)
		(end 111.37519 12.615672)
		(width 0.127)
		(layer "B.Cu")
		(net "P3E_CPU0_PE2_SS_RXN<8>")
	)
	(segment
		(start 111.22914 5.816092)
		(end 111.22914 6.54812)
		(width 0.127)
		(layer "B.Cu")
		(net "P3E_CPU0_PE2_SS_RXN<8>")
	)
	(segment
		(start 111.12754 10.30859)
		(end 111.12754 10.724134)
		(width 0.127)
		(layer "B.Cu")
		(net "P3E_CPU0_PE2_SS_RXN<8>")
	)
	(arc
		(start 111.195104 7.769352)
		(mid 111.128458 9.038096)
		(end 111.12754 10.30859)
		(width 0.127)
		(layer "B.Cu")
		(net "P3E_CPU0_PE2_SS_RXN<8>")
	)
	(arc
		(start 111.251746 11.023092)
		(mid 111.343132 11.16005)
		(end 111.37519 11.321542)
		(width 0.127)
		(layer "B.Cu")
		(net "P3E_CPU0_PE2_SS_RXN<8>")
	)
	(arc
		(start 111.12754 10.724134)
		(mid 111.159796 10.885824)
		(end 111.251492 11.022838)
		(width 0.127)
		(layer "B.Cu")
		(net "P3E_CPU0_PE2_SS_RXN<8>")
	)
	(arc
		(start 111.58474 5.206492)
		(mid 111.319159 5.41772)
		(end 111.2266 5.74421)
		(width 0.127)
		(layer "B.Cu")
		(net "P3E_CPU0_PE2_SS_RXN<8>")
	)
	(segment
		(start 111.176816 4.419854)
		(end 111.095536 4.224274)
		(width 0.127)
		(layer "In2.Cu")
		(net "P3E_CPU0_PE2_SS_RXN<8>")
	)
	(segment
		(start 96.46031 -1.37033)
		(end 93.499178 -5.599684)
		(width 0.127)
		(layer "In2.Cu")
		(net "P3E_CPU0_PE2_SS_RXN<8>")
	)
	(segment
		(start 111.17707 4.420362)
		(end 111.176816 4.4196)
		(width 0.127)
		(layer "In2.Cu")
		(net "P3E_CPU0_PE2_SS_RXN<8>")
	)
	(segment
		(start 111.176816 4.4196)
		(end 111.176816 4.419854)
		(width 0.127)
		(layer "In2.Cu")
		(net "P3E_CPU0_PE2_SS_RXN<8>")
	)
	(segment
		(start 85.642958 -25.594564)
		(end 85.424518 -25.90673)
		(width 0.127)
		(layer "In2.Cu")
		(net "P3E_CPU0_PE2_SS_RXN<8>")
	)
	(segment
		(start 93.890846 -12.625324)
		(end 93.66885 -12.84732)
		(width 0.127)
		(layer "In2.Cu")
		(net "P3E_CPU0_PE2_SS_RXN<8>")
	)
	(segment
		(start 86.048088 -25.016206)
		(end 86.087966 -25.24252)
		(width 0.127)
		(layer "In2.Cu")
		(net "P3E_CPU0_PE2_SS_RXN<8>")
	)
	(segment
		(start 84.5312 -32.882586)
		(end 84.531454 -32.882586)
		(width 0.127)
		(layer "In2.Cu")
		(net "P3E_CPU0_PE2_SS_RXN<8>")
	)
	(segment
		(start 111.095536 4.224274)
		(end 110.45063 3.772154)
		(width 0.127)
		(layer "In2.Cu")
		(net "P3E_CPU0_PE2_SS_RXN<8>")
	)
	(segment
		(start 93.21927 -13.932662)
		(end 93.21927 -14.19352)
		(width 0.127)
		(layer "In2.Cu")
		(net "P3E_CPU0_PE2_SS_RXN<8>")
	)
	(segment
		(start 111.183166 4.425696)
		(end 111.178594 4.423664)
		(width 0.127)
		(layer "In2.Cu")
		(net "P3E_CPU0_PE2_SS_RXN<8>")
	)
	(segment
		(start 93.499178 -5.599684)
		(end 93.23197 -7.115556)
		(width 0.127)
		(layer "In2.Cu")
		(net "P3E_CPU0_PE2_SS_RXN<8>")
	)
	(segment
		(start 101.209856 2.141728)
		(end 96.716342 -1.00457)
		(width 0.127)
		(layer "In2.Cu")
		(net "P3E_CPU0_PE2_SS_RXN<8>")
	)
	(segment
		(start 111.22279 4.940808)
		(end 111.222536 4.675124)
		(width 0.127)
		(layer "In2.Cu")
		(net "P3E_CPU0_PE2_SS_RXN<8>")
	)
	(segment
		(start 85.869526 -25.554686)
		(end 85.642958 -25.594564)
		(width 0.127)
		(layer "In2.Cu")
		(net "P3E_CPU0_PE2_SS_RXN<8>")
	)
	(segment
		(start 93.04782 -14.81582)
		(end 92.229432 -16.188436)
		(width 0.127)
		(layer "In2.Cu")
		(net "P3E_CPU0_PE2_SS_RXN<8>")
	)
	(segment
		(start 84.701888 -32.82569)
		(end 85.079332 -32.069786)
		(width 0.127)
		(layer "In2.Cu")
		(net "P3E_CPU0_PE2_SS_RXN<8>")
	)
	(segment
		(start 111.222536 4.675124)
		(end 111.222536 4.649724)
		(width 0.127)
		(layer "In2.Cu")
		(net "P3E_CPU0_PE2_SS_RXN<8>")
	)
	(segment
		(start 111.222536 4.649724)
		(end 111.183166 4.425696)
		(width 0.127)
		(layer "In2.Cu")
		(net "P3E_CPU0_PE2_SS_RXN<8>")
	)
	(segment
		(start 111.58474 5.206492)
		(end 111.48187 5.206492)
		(width 0.127)
		(layer "In2.Cu")
		(net "P3E_CPU0_PE2_SS_RXN<8>")
	)
	(segment
		(start 86.493096 -24.664162)
		(end 86.266528 -24.70404)
		(width 0.127)
		(layer "In2.Cu")
		(net "P3E_CPU0_PE2_SS_RXN<8>")
	)
	(segment
		(start 111.178594 4.423664)
		(end 111.17707 4.420362)
		(width 0.127)
		(layer "In2.Cu")
		(net "P3E_CPU0_PE2_SS_RXN<8>")
	)
	(segment
		(start 86.087966 -25.24252)
		(end 85.869526 -25.554686)
		(width 0.127)
		(layer "In2.Cu")
		(net "P3E_CPU0_PE2_SS_RXN<8>")
	)
	(segment
		(start 86.711536 -24.351996)
		(end 86.493096 -24.664162)
		(width 0.127)
		(layer "In2.Cu")
		(net "P3E_CPU0_PE2_SS_RXN<8>")
	)
	(segment
		(start 86.266528 -24.70404)
		(end 86.048088 -25.016206)
		(width 0.127)
		(layer "In2.Cu")
		(net "P3E_CPU0_PE2_SS_RXN<8>")
	)
	(segment
		(start 96.716342 -1.00457)
		(end 96.46031 -1.37033)
		(width 0.127)
		(layer "In2.Cu")
		(net "P3E_CPU0_PE2_SS_RXN<8>")
	)
	(segment
		(start 84.417408 -32.82569)
		(end 84.5312 -32.882586)
		(width 0.127)
		(layer "In2.Cu")
		(net "P3E_CPU0_PE2_SS_RXN<8>")
	)
	(segment
		(start 111.305594 5.13334)
		(end 111.300768 5.128514)
		(width 0.127)
		(layer "In2.Cu")
		(net "P3E_CPU0_PE2_SS_RXN<8>")
	)
	(segment
		(start 93.58503 -7.96798)
		(end 93.693234 -8.076184)
		(width 0.127)
		(layer "In2.Cu")
		(net "P3E_CPU0_PE2_SS_RXN<8>")
	)
	(segment
		(start 110.45063 3.772154)
		(end 101.209856 2.141728)
		(width 0.127)
		(layer "In2.Cu")
		(net "P3E_CPU0_PE2_SS_RXN<8>")
	)
	(segment
		(start 94.19971 -9.29894)
		(end 94.19971 -11.87958)
		(width 0.127)
		(layer "In2.Cu")
		(net "P3E_CPU0_PE2_SS_RXN<8>")
	)
	(segment
		(start 86.671658 -24.125682)
		(end 86.711536 -24.351996)
		(width 0.127)
		(layer "In2.Cu")
		(net "P3E_CPU0_PE2_SS_RXN<8>")
	)
	(segment
		(start 92.229432 -16.188436)
		(end 86.671658 -24.125682)
		(width 0.127)
		(layer "In2.Cu")
		(net "P3E_CPU0_PE2_SS_RXN<8>")
	)
	(arc
		(start 83.888834 -31.105602)
		(mid 83.935334 -31.273257)
		(end 84.00542 -31.4325)
		(width 0.127)
		(layer "In2.Cu")
		(net "P3E_CPU0_PE2_SS_RXN<8>")
	)
	(arc
		(start 84.00542 -31.4325)
		(mid 84.151699 -31.863665)
		(end 84.15528 -32.31896)
		(width 0.127)
		(layer "In2.Cu")
		(net "P3E_CPU0_PE2_SS_RXN<8>")
	)
	(arc
		(start 111.300768 5.128514)
		(mid 111.243141 5.042409)
		(end 111.22279 4.940808)
		(width 0.127)
		(layer "In2.Cu")
		(net "P3E_CPU0_PE2_SS_RXN<8>")
	)
	(arc
		(start 84.15528 -32.31896)
		(mid 84.203855 -32.615005)
		(end 84.417408 -32.82569)
		(width 0.127)
		(layer "In2.Cu")
		(net "P3E_CPU0_PE2_SS_RXN<8>")
	)
	(arc
		(start 85.424518 -25.90673)
		(mid 85.147431 -26.537083)
		(end 85.133688 -27.225498)
		(width 0.127)
		(layer "In2.Cu")
		(net "P3E_CPU0_PE2_SS_RXN<8>")
	)
	(arc
		(start 84.42452 -29.10586)
		(mid 84.32478 -29.264407)
		(end 84.27974 -29.44622)
		(width 0.127)
		(layer "In2.Cu")
		(net "P3E_CPU0_PE2_SS_RXN<8>")
	)
	(arc
		(start 84.27974 -29.44622)
		(mid 84.182026 -29.922871)
		(end 83.97494 -30.36316)
		(width 0.127)
		(layer "In2.Cu")
		(net "P3E_CPU0_PE2_SS_RXN<8>")
	)
	(arc
		(start 84.531454 -32.882586)
		(mid 84.62851 -32.889527)
		(end 84.701888 -32.82569)
		(width 0.127)
		(layer "In2.Cu")
		(net "P3E_CPU0_PE2_SS_RXN<8>")
	)
	(arc
		(start 85.133688 -27.225498)
		(mid 85.148281 -27.699715)
		(end 85.02523 -28.157932)
		(width 0.127)
		(layer "In2.Cu")
		(net "P3E_CPU0_PE2_SS_RXN<8>")
	)
	(arc
		(start 94.19971 -11.87958)
		(mid 94.119433 -12.283161)
		(end 93.890846 -12.625324)
		(width 0.127)
		(layer "In2.Cu")
		(net "P3E_CPU0_PE2_SS_RXN<8>")
	)
	(arc
		(start 111.48187 5.206492)
		(mid 111.386447 5.187475)
		(end 111.305594 5.13334)
		(width 0.127)
		(layer "In2.Cu")
		(net "P3E_CPU0_PE2_SS_RXN<8>")
	)
	(arc
		(start 93.693234 -8.076184)
		(mid 94.068086 -8.637189)
		(end 94.19971 -9.29894)
		(width 0.127)
		(layer "In2.Cu")
		(net "P3E_CPU0_PE2_SS_RXN<8>")
	)
	(arc
		(start 83.97494 -30.36316)
		(mid 83.908067 -30.547309)
		(end 83.871816 -30.739842)
		(width 0.127)
		(layer "In2.Cu")
		(net "P3E_CPU0_PE2_SS_RXN<8>")
	)
	(arc
		(start 83.871816 -30.739842)
		(mid 83.866411 -30.923369)
		(end 83.888834 -31.105602)
		(width 0.127)
		(layer "In2.Cu")
		(net "P3E_CPU0_PE2_SS_RXN<8>")
	)
	(arc
		(start 85.02523 -28.157932)
		(mid 84.761737 -28.655255)
		(end 84.42452 -29.10586)
		(width 0.127)
		(layer "In2.Cu")
		(net "P3E_CPU0_PE2_SS_RXN<8>")
	)
	(arc
		(start 93.23197 -7.115556)
		(mid 93.323732 -7.576875)
		(end 93.58503 -7.96798)
		(width 0.127)
		(layer "In2.Cu")
		(net "P3E_CPU0_PE2_SS_RXN<8>")
	)
	(arc
		(start 93.21927 -14.19352)
		(mid 93.175625 -14.516264)
		(end 93.04782 -14.81582)
		(width 0.127)
		(layer "In2.Cu")
		(net "P3E_CPU0_PE2_SS_RXN<8>")
	)
	(arc
		(start 93.66885 -12.84732)
		(mid 93.336124 -13.345279)
		(end 93.21927 -13.932662)
		(width 0.127)
		(layer "In2.Cu")
		(net "P3E_CPU0_PE2_SS_RXN<8>")
	)
	(via
		(at 97.782888 5.165852)
		(size 0.508)
		(drill 0.254)
		(layers "F.Cu" "B.Cu")
		(net "P3E_CPU0_PE2_SS_RXN<7>")
	)
	(segment
		(start 96.932242 10.10539)
		(end 96.932242 10.371836)
		(width 0.127)
		(layer "B.Cu")
		(net "P3E_CPU0_PE2_SS_RXN<7>")
	)
	(segment
		(start 97.179892 10.969752)
		(end 97.179892 12.514072)
		(width 0.127)
		(layer "B.Cu")
		(net "P3E_CPU0_PE2_SS_RXN<7>")
	)
	(segment
		(start 97.373948 8.089392)
		(end 97.193608 8.69061)
		(width 0.127)
		(layer "B.Cu")
		(net "P3E_CPU0_PE2_SS_RXN<7>")
	)
	(segment
		(start 97.422462 7.95401)
		(end 97.421954 7.955026)
		(width 0.127)
		(layer "B.Cu")
		(net "P3E_CPU0_PE2_SS_RXN<7>")
	)
	(segment
		(start 97.427288 7.41807)
		(end 97.422462 7.95401)
		(width 0.127)
		(layer "B.Cu")
		(net "P3E_CPU0_PE2_SS_RXN<7>")
	)
	(segment
		(start 97.421954 7.955026)
		(end 97.412556 7.96036)
		(width 0.127)
		(layer "B.Cu")
		(net "P3E_CPU0_PE2_SS_RXN<7>")
	)
	(segment
		(start 97.412556 7.96036)
		(end 97.373948 8.089392)
		(width 0.127)
		(layer "B.Cu")
		(net "P3E_CPU0_PE2_SS_RXN<7>")
	)
	(segment
		(start 97.427288 5.775452)
		(end 97.427288 7.41807)
		(width 0.127)
		(layer "B.Cu")
		(net "P3E_CPU0_PE2_SS_RXN<7>")
	)
	(arc
		(start 97.05594 10.67054)
		(mid 97.147667 10.80782)
		(end 97.179892 10.969752)
		(width 0.127)
		(layer "B.Cu")
		(net "P3E_CPU0_PE2_SS_RXN<7>")
	)
	(arc
		(start 97.782888 5.165852)
		(mid 97.522673 5.422579)
		(end 97.427288 5.775452)
		(width 0.127)
		(layer "B.Cu")
		(net "P3E_CPU0_PE2_SS_RXN<7>")
	)
	(arc
		(start 96.932242 10.371836)
		(mid 96.964395 10.533482)
		(end 97.05594 10.67054)
		(width 0.127)
		(layer "B.Cu")
		(net "P3E_CPU0_PE2_SS_RXN<7>")
	)
	(arc
		(start 97.193608 8.69061)
		(mid 97.024702 9.390938)
		(end 96.932242 10.10539)
		(width 0.127)
		(layer "B.Cu")
		(net "P3E_CPU0_PE2_SS_RXN<7>")
	)
	(segment
		(start 90.20048 -9.29894)
		(end 90.20048 -11.87958)
		(width 0.127)
		(layer "In2.Cu")
		(net "P3E_CPU0_PE2_SS_RXN<7>")
	)
	(segment
		(start 92.003372 -4.113276)
		(end 89.769442 -5.677408)
		(width 0.127)
		(layer "In2.Cu")
		(net "P3E_CPU0_PE2_SS_RXN<7>")
	)
	(segment
		(start 89.22004 -13.932662)
		(end 89.22004 -14.351508)
		(width 0.127)
		(layer "In2.Cu")
		(net "P3E_CPU0_PE2_SS_RXN<7>")
	)
	(segment
		(start 79.2607 -27.3685)
		(end 79.25816 -27.69616)
		(width 0.127)
		(layer "In2.Cu")
		(net "P3E_CPU0_PE2_SS_RXN<7>")
	)
	(segment
		(start 97.428304 4.413504)
		(end 97.244662 3.37185)
		(width 0.127)
		(layer "In2.Cu")
		(net "P3E_CPU0_PE2_SS_RXN<7>")
	)
	(segment
		(start 79.758794 -33.143444)
		(end 79.75854 -33.143444)
		(width 0.127)
		(layer "In2.Cu")
		(net "P3E_CPU0_PE2_SS_RXN<7>")
	)
	(segment
		(start 89.23274 -6.7691)
		(end 89.23274 -7.115556)
		(width 0.127)
		(layer "In2.Cu")
		(net "P3E_CPU0_PE2_SS_RXN<7>")
	)
	(segment
		(start 97.244662 3.37185)
		(end 92.003372 -4.113276)
		(width 0.127)
		(layer "In2.Cu")
		(net "P3E_CPU0_PE2_SS_RXN<7>")
	)
	(segment
		(start 89.5858 -7.96798)
		(end 89.694004 -8.076184)
		(width 0.127)
		(layer "In2.Cu")
		(net "P3E_CPU0_PE2_SS_RXN<7>")
	)
	(segment
		(start 89.309448 -6.33476)
		(end 89.23274 -6.7691)
		(width 0.127)
		(layer "In2.Cu")
		(net "P3E_CPU0_PE2_SS_RXN<7>")
	)
	(segment
		(start 89.891616 -12.625324)
		(end 89.66962 -12.84732)
		(width 0.127)
		(layer "In2.Cu")
		(net "P3E_CPU0_PE2_SS_RXN<7>")
	)
	(segment
		(start 89.22004 -14.351508)
		(end 89.111074 -14.97076)
		(width 0.127)
		(layer "In2.Cu")
		(net "P3E_CPU0_PE2_SS_RXN<7>")
	)
	(segment
		(start 79.3623 -27.0383)
		(end 79.2607 -27.3685)
		(width 0.127)
		(layer "In2.Cu")
		(net "P3E_CPU0_PE2_SS_RXN<7>")
	)
	(segment
		(start 89.111074 -14.97076)
		(end 82.307176 -24.68118)
		(width 0.127)
		(layer "In2.Cu")
		(net "P3E_CPU0_PE2_SS_RXN<7>")
	)
	(segment
		(start 82.307176 -24.68118)
		(end 79.3623 -27.0383)
		(width 0.127)
		(layer "In2.Cu")
		(net "P3E_CPU0_PE2_SS_RXN<7>")
	)
	(segment
		(start 79.760064 -33.142936)
		(end 79.758794 -33.143444)
		(width 0.127)
		(layer "In2.Cu")
		(net "P3E_CPU0_PE2_SS_RXN<7>")
	)
	(segment
		(start 79.872078 -33.087056)
		(end 79.760064 -33.142936)
		(width 0.127)
		(layer "In2.Cu")
		(net "P3E_CPU0_PE2_SS_RXN<7>")
	)
	(segment
		(start 89.769442 -5.677408)
		(end 89.309448 -6.33476)
		(width 0.127)
		(layer "In2.Cu")
		(net "P3E_CPU0_PE2_SS_RXN<7>")
	)
	(segment
		(start 97.437448 4.705858)
		(end 97.428304 4.413504)
		(width 0.127)
		(layer "In2.Cu")
		(net "P3E_CPU0_PE2_SS_RXN<7>")
	)
	(segment
		(start 79.701644 -33.313878)
		(end 80.079342 -34.070036)
		(width 0.127)
		(layer "In2.Cu")
		(net "P3E_CPU0_PE2_SS_RXN<7>")
	)
	(arc
		(start 89.694004 -8.076184)
		(mid 90.068856 -8.637189)
		(end 90.20048 -9.29894)
		(width 0.127)
		(layer "In2.Cu")
		(net "P3E_CPU0_PE2_SS_RXN<7>")
	)
	(arc
		(start 89.66962 -12.84732)
		(mid 89.336894 -13.345279)
		(end 89.22004 -13.932662)
		(width 0.127)
		(layer "In2.Cu")
		(net "P3E_CPU0_PE2_SS_RXN<7>")
	)
	(arc
		(start 79.75854 -33.143444)
		(mid 79.694777 -33.216897)
		(end 79.701644 -33.313878)
		(width 0.127)
		(layer "In2.Cu")
		(net "P3E_CPU0_PE2_SS_RXN<7>")
	)
	(arc
		(start 80.2005 -29.73832)
		(mid 80.07028 -30.989895)
		(end 80.2513 -32.23514)
		(width 0.127)
		(layer "In2.Cu")
		(net "P3E_CPU0_PE2_SS_RXN<7>")
	)
	(arc
		(start 80.2513 -32.23514)
		(mid 80.21431 -32.729053)
		(end 79.872078 -33.087056)
		(width 0.127)
		(layer "In2.Cu")
		(net "P3E_CPU0_PE2_SS_RXN<7>")
	)
	(arc
		(start 79.25816 -27.69616)
		(mid 79.47724 -28.20932)
		(end 79.83982 -28.63342)
		(width 0.127)
		(layer "In2.Cu")
		(net "P3E_CPU0_PE2_SS_RXN<7>")
	)
	(arc
		(start 90.20048 -11.87958)
		(mid 90.120203 -12.283161)
		(end 89.891616 -12.625324)
		(width 0.127)
		(layer "In2.Cu")
		(net "P3E_CPU0_PE2_SS_RXN<7>")
	)
	(arc
		(start 97.782888 5.165852)
		(mid 97.537364 4.990528)
		(end 97.437448 4.705858)
		(width 0.127)
		(layer "In2.Cu")
		(net "P3E_CPU0_PE2_SS_RXN<7>")
	)
	(arc
		(start 89.23274 -7.115556)
		(mid 89.324502 -7.576875)
		(end 89.5858 -7.96798)
		(width 0.127)
		(layer "In2.Cu")
		(net "P3E_CPU0_PE2_SS_RXN<7>")
	)
	(arc
		(start 79.83982 -28.63342)
		(mid 80.173898 -29.135704)
		(end 80.2005 -29.73832)
		(width 0.127)
		(layer "In2.Cu")
		(net "P3E_CPU0_PE2_SS_RXN<7>")
	)
	(via
		(at 95.192088 5.165852)
		(size 0.508)
		(drill 0.254)
		(layers "F.Cu" "B.Cu")
		(net "P3E_CPU0_PE2_SS_RXN<6>")
	)
	(segment
		(start 94.836488 6.554216)
		(end 94.836488 5.775452)
		(width 0.127)
		(layer "B.Cu")
		(net "P3E_CPU0_PE2_SS_RXN<6>")
	)
	(segment
		(start 94.791276 7.52602)
		(end 94.83471 6.588252)
		(width 0.127)
		(layer "B.Cu")
		(net "P3E_CPU0_PE2_SS_RXN<6>")
	)
	(segment
		(start 94.816676 7.94512)
		(end 94.817692 7.944104)
		(width 0.127)
		(layer "B.Cu")
		(net "P3E_CPU0_PE2_SS_RXN<6>")
	)
	(segment
		(start 94.83471 6.588252)
		(end 94.836488 6.554216)
		(width 0.127)
		(layer "B.Cu")
		(net "P3E_CPU0_PE2_SS_RXN<6>")
	)
	(segment
		(start 94.779846 12.514072)
		(end 94.779846 10.931652)
		(width 0.127)
		(layer "B.Cu")
		(net "P3E_CPU0_PE2_SS_RXN<6>")
	)
	(segment
		(start 94.816676 7.946136)
		(end 94.816676 7.94512)
		(width 0.127)
		(layer "B.Cu")
		(net "P3E_CPU0_PE2_SS_RXN<6>")
	)
	(segment
		(start 94.793562 8.377682)
		(end 94.816676 7.946136)
		(width 0.127)
		(layer "B.Cu")
		(net "P3E_CPU0_PE2_SS_RXN<6>")
	)
	(segment
		(start 94.817692 7.944104)
		(end 94.791276 7.52602)
		(width 0.127)
		(layer "B.Cu")
		(net "P3E_CPU0_PE2_SS_RXN<6>")
	)
	(segment
		(start 94.53245 10.334244)
		(end 94.53245 10.10539)
		(width 0.127)
		(layer "B.Cu")
		(net "P3E_CPU0_PE2_SS_RXN<6>")
	)
	(arc
		(start 94.6658 8.8392)
		(mid 94.754811 8.615395)
		(end 94.793562 8.377682)
		(width 0.127)
		(layer "B.Cu")
		(net "P3E_CPU0_PE2_SS_RXN<6>")
	)
	(arc
		(start 94.53245 10.10539)
		(mid 94.47672 9.459405)
		(end 94.6658 8.8392)
		(width 0.127)
		(layer "B.Cu")
		(net "P3E_CPU0_PE2_SS_RXN<6>")
	)
	(arc
		(start 94.779846 10.931652)
		(mid 94.747693 10.770006)
		(end 94.656148 10.632948)
		(width 0.127)
		(layer "B.Cu")
		(net "P3E_CPU0_PE2_SS_RXN<6>")
	)
	(arc
		(start 94.836488 5.775452)
		(mid 94.931889 5.422589)
		(end 95.192088 5.165852)
		(width 0.127)
		(layer "B.Cu")
		(net "P3E_CPU0_PE2_SS_RXN<6>")
	)
	(arc
		(start 94.656148 10.632948)
		(mid 94.564576 10.495901)
		(end 94.53245 10.334244)
		(width 0.127)
		(layer "B.Cu")
		(net "P3E_CPU0_PE2_SS_RXN<6>")
	)
	(segment
		(start 75.760834 -33.142936)
		(end 75.759564 -33.143444)
		(width 0.127)
		(layer "In2.Cu")
		(net "P3E_CPU0_PE2_SS_RXN<6>")
	)
	(segment
		(start 94.580456 2.95529)
		(end 90.941652 -2.241296)
		(width 0.127)
		(layer "In2.Cu")
		(net "P3E_CPU0_PE2_SS_RXN<6>")
	)
	(segment
		(start 78.904338 -23.190962)
		(end 75.3237 -27.0891)
		(width 0.127)
		(layer "In2.Cu")
		(net "P3E_CPU0_PE2_SS_RXN<6>")
	)
	(segment
		(start 85.104224 -14.548612)
		(end 84.9122 -14.849856)
		(width 0.127)
		(layer "In2.Cu")
		(net "P3E_CPU0_PE2_SS_RXN<6>")
	)
	(segment
		(start 85.270594 -6.551422)
		(end 85.23224 -6.7691)
		(width 0.127)
		(layer "In2.Cu")
		(net "P3E_CPU0_PE2_SS_RXN<6>")
	)
	(segment
		(start 75.872848 -33.087056)
		(end 75.760834 -33.142936)
		(width 0.127)
		(layer "In2.Cu")
		(net "P3E_CPU0_PE2_SS_RXN<6>")
	)
	(segment
		(start 94.846648 4.705858)
		(end 94.837504 4.413504)
		(width 0.127)
		(layer "In2.Cu")
		(net "P3E_CPU0_PE2_SS_RXN<6>")
	)
	(segment
		(start 75.702414 -33.313878)
		(end 76.080112 -34.070036)
		(width 0.127)
		(layer "In2.Cu")
		(net "P3E_CPU0_PE2_SS_RXN<6>")
	)
	(segment
		(start 85.735414 -5.887212)
		(end 85.270594 -6.551422)
		(width 0.127)
		(layer "In2.Cu")
		(net "P3E_CPU0_PE2_SS_RXN<6>")
	)
	(segment
		(start 85.891116 -12.625324)
		(end 85.66912 -12.84732)
		(width 0.127)
		(layer "In2.Cu")
		(net "P3E_CPU0_PE2_SS_RXN<6>")
	)
	(segment
		(start 84.9122 -14.849856)
		(end 82.007456 -18.916142)
		(width 0.127)
		(layer "In2.Cu")
		(net "P3E_CPU0_PE2_SS_RXN<6>")
	)
	(segment
		(start 86.19998 -9.29894)
		(end 86.19998 -11.87958)
		(width 0.127)
		(layer "In2.Cu")
		(net "P3E_CPU0_PE2_SS_RXN<6>")
	)
	(segment
		(start 85.23224 -6.7691)
		(end 85.23224 -7.115556)
		(width 0.127)
		(layer "In2.Cu")
		(net "P3E_CPU0_PE2_SS_RXN<6>")
	)
	(segment
		(start 85.5853 -7.96798)
		(end 85.693504 -8.076184)
		(width 0.127)
		(layer "In2.Cu")
		(net "P3E_CPU0_PE2_SS_RXN<6>")
	)
	(segment
		(start 85.21954 -13.932662)
		(end 85.104224 -14.548612)
		(width 0.127)
		(layer "In2.Cu")
		(net "P3E_CPU0_PE2_SS_RXN<6>")
	)
	(segment
		(start 75.759564 -33.143444)
		(end 75.75931 -33.143444)
		(width 0.127)
		(layer "In2.Cu")
		(net "P3E_CPU0_PE2_SS_RXN<6>")
	)
	(segment
		(start 90.941652 -2.241296)
		(end 85.735414 -5.887212)
		(width 0.127)
		(layer "In2.Cu")
		(net "P3E_CPU0_PE2_SS_RXN<6>")
	)
	(segment
		(start 94.837504 4.413504)
		(end 94.580456 2.95529)
		(width 0.127)
		(layer "In2.Cu")
		(net "P3E_CPU0_PE2_SS_RXN<6>")
	)
	(segment
		(start 82.007456 -18.916142)
		(end 78.904338 -23.190962)
		(width 0.127)
		(layer "In2.Cu")
		(net "P3E_CPU0_PE2_SS_RXN<6>")
	)
	(arc
		(start 85.23224 -7.115556)
		(mid 85.324002 -7.576875)
		(end 85.5853 -7.96798)
		(width 0.127)
		(layer "In2.Cu")
		(net "P3E_CPU0_PE2_SS_RXN<6>")
	)
	(arc
		(start 95.192088 5.165852)
		(mid 94.946564 4.990528)
		(end 94.846648 4.705858)
		(width 0.127)
		(layer "In2.Cu")
		(net "P3E_CPU0_PE2_SS_RXN<6>")
	)
	(arc
		(start 76.20127 -29.73832)
		(mid 76.07105 -30.989895)
		(end 76.25207 -32.23514)
		(width 0.127)
		(layer "In2.Cu")
		(net "P3E_CPU0_PE2_SS_RXN<6>")
	)
	(arc
		(start 85.66912 -12.84732)
		(mid 85.336394 -13.345279)
		(end 85.21954 -13.932662)
		(width 0.127)
		(layer "In2.Cu")
		(net "P3E_CPU0_PE2_SS_RXN<6>")
	)
	(arc
		(start 76.25207 -32.23514)
		(mid 76.21508 -32.729053)
		(end 75.872848 -33.087056)
		(width 0.127)
		(layer "In2.Cu")
		(net "P3E_CPU0_PE2_SS_RXN<6>")
	)
	(arc
		(start 75.84059 -28.63342)
		(mid 76.174668 -29.135704)
		(end 76.20127 -29.73832)
		(width 0.127)
		(layer "In2.Cu")
		(net "P3E_CPU0_PE2_SS_RXN<6>")
	)
	(arc
		(start 75.25893 -27.69616)
		(mid 75.47801 -28.20932)
		(end 75.84059 -28.63342)
		(width 0.127)
		(layer "In2.Cu")
		(net "P3E_CPU0_PE2_SS_RXN<6>")
	)
	(arc
		(start 86.19998 -11.87958)
		(mid 86.119703 -12.283161)
		(end 85.891116 -12.625324)
		(width 0.127)
		(layer "In2.Cu")
		(net "P3E_CPU0_PE2_SS_RXN<6>")
	)
	(arc
		(start 85.693504 -8.076184)
		(mid 86.068356 -8.637189)
		(end 86.19998 -9.29894)
		(width 0.127)
		(layer "In2.Cu")
		(net "P3E_CPU0_PE2_SS_RXN<6>")
	)
	(arc
		(start 75.3237 -27.0891)
		(mid 75.236488 -27.386776)
		(end 75.25893 -27.69616)
		(width 0.127)
		(layer "In2.Cu")
		(net "P3E_CPU0_PE2_SS_RXN<6>")
	)
	(arc
		(start 75.75931 -33.143444)
		(mid 75.695547 -33.216897)
		(end 75.702414 -33.313878)
		(width 0.127)
		(layer "In2.Cu")
		(net "P3E_CPU0_PE2_SS_RXN<6>")
	)
	(via
		(at 92.601288 5.165852)
		(size 0.508)
		(drill 0.254)
		(layers "F.Cu" "B.Cu")
		(net "P3E_CPU0_PE2_SS_RXN<5>")
	)
	(segment
		(start 92.245434 8.075422)
		(end 92.198952 7.521956)
		(width 0.127)
		(layer "B.Cu")
		(net "P3E_CPU0_PE2_SS_RXN<5>")
	)
	(segment
		(start 92.245688 6.561836)
		(end 92.245688 5.775452)
		(width 0.127)
		(layer "B.Cu")
		(net "P3E_CPU0_PE2_SS_RXN<5>")
	)
	(segment
		(start 92.164916 7.122668)
		(end 92.245688 6.561836)
		(width 0.127)
		(layer "B.Cu")
		(net "P3E_CPU0_PE2_SS_RXN<5>")
	)
	(segment
		(start 92.3798 12.514072)
		(end 92.3798 11.046206)
		(width 0.127)
		(layer "B.Cu")
		(net "P3E_CPU0_PE2_SS_RXN<5>")
	)
	(segment
		(start 92.24137 8.081772)
		(end 92.241878 8.07847)
		(width 0.127)
		(layer "B.Cu")
		(net "P3E_CPU0_PE2_SS_RXN<5>")
	)
	(segment
		(start 92.198952 7.521956)
		(end 92.164916 7.122668)
		(width 0.127)
		(layer "B.Cu")
		(net "P3E_CPU0_PE2_SS_RXN<5>")
	)
	(segment
		(start 92.132404 10.448798)
		(end 92.132404 10.10539)
		(width 0.127)
		(layer "B.Cu")
		(net "P3E_CPU0_PE2_SS_RXN<5>")
	)
	(segment
		(start 92.241878 8.07847)
		(end 92.245434 8.075422)
		(width 0.127)
		(layer "B.Cu")
		(net "P3E_CPU0_PE2_SS_RXN<5>")
	)
	(arc
		(start 92.256102 10.747502)
		(mid 92.16453 10.610455)
		(end 92.132404 10.448798)
		(width 0.127)
		(layer "B.Cu")
		(net "P3E_CPU0_PE2_SS_RXN<5>")
	)
	(arc
		(start 92.3798 11.046206)
		(mid 92.347647 10.88456)
		(end 92.256102 10.747502)
		(width 0.127)
		(layer "B.Cu")
		(net "P3E_CPU0_PE2_SS_RXN<5>")
	)
	(arc
		(start 92.132404 10.10539)
		(mid 92.167278 9.092525)
		(end 92.24137 8.081772)
		(width 0.127)
		(layer "B.Cu")
		(net "P3E_CPU0_PE2_SS_RXN<5>")
	)
	(arc
		(start 92.245688 5.775452)
		(mid 92.341089 5.422589)
		(end 92.601288 5.165852)
		(width 0.127)
		(layer "B.Cu")
		(net "P3E_CPU0_PE2_SS_RXN<5>")
	)
	(segment
		(start 71.760334 -33.142936)
		(end 71.872348 -33.087056)
		(width 0.127)
		(layer "In2.Cu")
		(net "P3E_CPU0_PE2_SS_RXN<5>")
	)
	(segment
		(start 81.21904 -14.351508)
		(end 81.21904 -13.932662)
		(width 0.127)
		(layer "In2.Cu")
		(net "P3E_CPU0_PE2_SS_RXN<5>")
	)
	(segment
		(start 92.049346 3.061208)
		(end 92.239338 4.138676)
		(width 0.127)
		(layer "In2.Cu")
		(net "P3E_CPU0_PE2_SS_RXN<5>")
	)
	(segment
		(start 71.361554 -26.89733)
		(end 76.077318 -22.021546)
		(width 0.127)
		(layer "In2.Cu")
		(net "P3E_CPU0_PE2_SS_RXN<5>")
	)
	(segment
		(start 81.66862 -12.84732)
		(end 81.890616 -12.625324)
		(width 0.127)
		(layer "In2.Cu")
		(net "P3E_CPU0_PE2_SS_RXN<5>")
	)
	(segment
		(start 76.080112 -22.01799)
		(end 81.14157 -14.789658)
		(width 0.127)
		(layer "In2.Cu")
		(net "P3E_CPU0_PE2_SS_RXN<5>")
	)
	(segment
		(start 71.25843 -27.69616)
		(end 71.247 -27.3431)
		(width 0.127)
		(layer "In2.Cu")
		(net "P3E_CPU0_PE2_SS_RXN<5>")
	)
	(segment
		(start 81.284064 -6.818884)
		(end 81.570068 -6.410198)
		(width 0.127)
		(layer "In2.Cu")
		(net "P3E_CPU0_PE2_SS_RXN<5>")
	)
	(segment
		(start 92.239338 4.138676)
		(end 92.239338 4.751324)
		(width 0.127)
		(layer "In2.Cu")
		(net "P3E_CPU0_PE2_SS_RXN<5>")
	)
	(segment
		(start 71.759064 -33.143444)
		(end 71.760334 -33.142936)
		(width 0.127)
		(layer "In2.Cu")
		(net "P3E_CPU0_PE2_SS_RXN<5>")
	)
	(segment
		(start 81.693004 -8.076184)
		(end 81.5848 -7.96798)
		(width 0.127)
		(layer "In2.Cu")
		(net "P3E_CPU0_PE2_SS_RXN<5>")
	)
	(segment
		(start 81.14157 -14.789658)
		(end 81.21904 -14.351508)
		(width 0.127)
		(layer "In2.Cu")
		(net "P3E_CPU0_PE2_SS_RXN<5>")
	)
	(segment
		(start 71.75881 -33.143444)
		(end 71.759064 -33.143444)
		(width 0.127)
		(layer "In2.Cu")
		(net "P3E_CPU0_PE2_SS_RXN<5>")
	)
	(segment
		(start 89.117932 -1.125982)
		(end 92.049346 3.061208)
		(width 0.127)
		(layer "In2.Cu")
		(net "P3E_CPU0_PE2_SS_RXN<5>")
	)
	(segment
		(start 81.570068 -6.410198)
		(end 89.117932 -1.125982)
		(width 0.127)
		(layer "In2.Cu")
		(net "P3E_CPU0_PE2_SS_RXN<5>")
	)
	(segment
		(start 71.247 -27.3431)
		(end 71.361554 -26.89733)
		(width 0.127)
		(layer "In2.Cu")
		(net "P3E_CPU0_PE2_SS_RXN<5>")
	)
	(segment
		(start 72.079612 -34.070036)
		(end 71.701914 -33.313878)
		(width 0.127)
		(layer "In2.Cu")
		(net "P3E_CPU0_PE2_SS_RXN<5>")
	)
	(segment
		(start 82.19948 -11.87958)
		(end 82.19948 -9.29894)
		(width 0.127)
		(layer "In2.Cu")
		(net "P3E_CPU0_PE2_SS_RXN<5>")
	)
	(segment
		(start 76.077318 -22.021546)
		(end 76.080112 -22.01799)
		(width 0.127)
		(layer "In2.Cu")
		(net "P3E_CPU0_PE2_SS_RXN<5>")
	)
	(segment
		(start 81.23174 -7.115556)
		(end 81.284064 -6.818884)
		(width 0.127)
		(layer "In2.Cu")
		(net "P3E_CPU0_PE2_SS_RXN<5>")
	)
	(arc
		(start 71.84009 -28.63342)
		(mid 71.477533 -28.209306)
		(end 71.25843 -27.69616)
		(width 0.127)
		(layer "In2.Cu")
		(net "P3E_CPU0_PE2_SS_RXN<5>")
	)
	(arc
		(start 71.701914 -33.313878)
		(mid 71.695155 -33.216933)
		(end 71.75881 -33.143444)
		(width 0.127)
		(layer "In2.Cu")
		(net "P3E_CPU0_PE2_SS_RXN<5>")
	)
	(arc
		(start 72.20077 -29.73832)
		(mid 72.17404 -29.135746)
		(end 71.84009 -28.63342)
		(width 0.127)
		(layer "In2.Cu")
		(net "P3E_CPU0_PE2_SS_RXN<5>")
	)
	(arc
		(start 92.239338 4.751324)
		(mid 92.342561 5.026477)
		(end 92.601288 5.165852)
		(width 0.127)
		(layer "In2.Cu")
		(net "P3E_CPU0_PE2_SS_RXN<5>")
	)
	(arc
		(start 71.872348 -33.087056)
		(mid 72.214497 -32.729017)
		(end 72.25157 -32.23514)
		(width 0.127)
		(layer "In2.Cu")
		(net "P3E_CPU0_PE2_SS_RXN<5>")
	)
	(arc
		(start 81.5848 -7.96798)
		(mid 81.323478 -7.576885)
		(end 81.23174 -7.115556)
		(width 0.127)
		(layer "In2.Cu")
		(net "P3E_CPU0_PE2_SS_RXN<5>")
	)
	(arc
		(start 82.19948 -9.29894)
		(mid 82.06785 -8.637192)
		(end 81.693004 -8.076184)
		(width 0.127)
		(layer "In2.Cu")
		(net "P3E_CPU0_PE2_SS_RXN<5>")
	)
	(arc
		(start 81.890616 -12.625324)
		(mid 82.119233 -12.283174)
		(end 82.19948 -11.87958)
		(width 0.127)
		(layer "In2.Cu")
		(net "P3E_CPU0_PE2_SS_RXN<5>")
	)
	(arc
		(start 72.25157 -32.23514)
		(mid 72.070532 -30.989895)
		(end 72.20077 -29.73832)
		(width 0.127)
		(layer "In2.Cu")
		(net "P3E_CPU0_PE2_SS_RXN<5>")
	)
	(arc
		(start 81.21904 -13.932662)
		(mid 81.335879 -13.345273)
		(end 81.66862 -12.84732)
		(width 0.127)
		(layer "In2.Cu")
		(net "P3E_CPU0_PE2_SS_RXN<5>")
	)
	(via
		(at 90.010488 5.165852)
		(size 0.508)
		(drill 0.254)
		(layers "F.Cu" "B.Cu")
		(net "P3E_CPU0_PE2_SS_RXN<4>")
	)
	(segment
		(start 89.633298 7.292594)
		(end 89.661746 6.885178)
		(width 0.127)
		(layer "B.Cu")
		(net "P3E_CPU0_PE2_SS_RXN<4>")
	)
	(segment
		(start 89.63152 7.926832)
		(end 89.63279 7.895082)
		(width 0.127)
		(layer "B.Cu")
		(net "P3E_CPU0_PE2_SS_RXN<4>")
	)
	(segment
		(start 89.732358 10.097262)
		(end 89.625932 8.063738)
		(width 0.127)
		(layer "B.Cu")
		(net "P3E_CPU0_PE2_SS_RXN<4>")
	)
	(segment
		(start 89.63279 7.895082)
		(end 89.633298 7.292594)
		(width 0.127)
		(layer "B.Cu")
		(net "P3E_CPU0_PE2_SS_RXN<4>")
	)
	(segment
		(start 89.980008 12.514072)
		(end 89.980008 10.958068)
		(width 0.127)
		(layer "B.Cu")
		(net "P3E_CPU0_PE2_SS_RXN<4>")
	)
	(segment
		(start 89.631774 7.934706)
		(end 89.631774 7.926832)
		(width 0.127)
		(layer "B.Cu")
		(net "P3E_CPU0_PE2_SS_RXN<4>")
	)
	(segment
		(start 89.625932 8.063738)
		(end 89.631774 7.934706)
		(width 0.127)
		(layer "B.Cu")
		(net "P3E_CPU0_PE2_SS_RXN<4>")
	)
	(segment
		(start 89.631774 7.926832)
		(end 89.63152 7.926832)
		(width 0.127)
		(layer "B.Cu")
		(net "P3E_CPU0_PE2_SS_RXN<4>")
	)
	(segment
		(start 89.662254 6.898132)
		(end 89.662254 5.674106)
		(width 0.127)
		(layer "B.Cu")
		(net "P3E_CPU0_PE2_SS_RXN<4>")
	)
	(segment
		(start 89.661746 6.885178)
		(end 89.662254 6.898132)
		(width 0.127)
		(layer "B.Cu")
		(net "P3E_CPU0_PE2_SS_RXN<4>")
	)
	(segment
		(start 89.732358 10.360152)
		(end 89.732358 10.097262)
		(width 0.127)
		(layer "B.Cu")
		(net "P3E_CPU0_PE2_SS_RXN<4>")
	)
	(arc
		(start 89.856056 10.658856)
		(mid 89.764484 10.521809)
		(end 89.732358 10.360152)
		(width 0.127)
		(layer "B.Cu")
		(net "P3E_CPU0_PE2_SS_RXN<4>")
	)
	(arc
		(start 89.980008 10.958068)
		(mid 89.947797 10.79613)
		(end 89.856056 10.658856)
		(width 0.127)
		(layer "B.Cu")
		(net "P3E_CPU0_PE2_SS_RXN<4>")
	)
	(arc
		(start 89.662254 5.674106)
		(mid 89.777478 5.37963)
		(end 90.010488 5.165852)
		(width 0.127)
		(layer "B.Cu")
		(net "P3E_CPU0_PE2_SS_RXN<4>")
	)
	(segment
		(start 77.313282 -6.784086)
		(end 77.226414 -7.2771)
		(width 0.127)
		(layer "In2.Cu")
		(net "P3E_CPU0_PE2_SS_RXN<4>")
	)
	(segment
		(start 67.702684 -33.313878)
		(end 68.080382 -34.070036)
		(width 0.127)
		(layer "In2.Cu")
		(net "P3E_CPU0_PE2_SS_RXN<4>")
	)
	(segment
		(start 77.22489 -14.313662)
		(end 77.089508 -15.082012)
		(width 0.127)
		(layer "In2.Cu")
		(net "P3E_CPU0_PE2_SS_RXN<4>")
	)
	(segment
		(start 67.873118 -33.087056)
		(end 67.761104 -33.142936)
		(width 0.127)
		(layer "In2.Cu")
		(net "P3E_CPU0_PE2_SS_RXN<4>")
	)
	(segment
		(start 72.94499 -21.000974)
		(end 67.7291 -26.5176)
		(width 0.127)
		(layer "In2.Cu")
		(net "P3E_CPU0_PE2_SS_RXN<4>")
	)
	(segment
		(start 67.7291 -26.5176)
		(end 67.3227 -27.1272)
		(width 0.127)
		(layer "In2.Cu")
		(net "P3E_CPU0_PE2_SS_RXN<4>")
	)
	(segment
		(start 87.581994 0.230632)
		(end 82.304636 -3.464306)
		(width 0.127)
		(layer "In2.Cu")
		(net "P3E_CPU0_PE2_SS_RXN<4>")
	)
	(segment
		(start 76.909168 -8.043164)
		(end 76.775056 -8.177276)
		(width 0.127)
		(layer "In2.Cu")
		(net "P3E_CPU0_PE2_SS_RXN<4>")
	)
	(segment
		(start 76.238354 -9.47293)
		(end 76.238354 -11.63066)
		(width 0.127)
		(layer "In2.Cu")
		(net "P3E_CPU0_PE2_SS_RXN<4>")
	)
	(segment
		(start 77.22489 -13.894816)
		(end 77.22489 -14.313662)
		(width 0.127)
		(layer "In2.Cu")
		(net "P3E_CPU0_PE2_SS_RXN<4>")
	)
	(segment
		(start 81.759806 -3.560318)
		(end 77.464158 -6.56844)
		(width 0.127)
		(layer "In2.Cu")
		(net "P3E_CPU0_PE2_SS_RXN<4>")
	)
	(segment
		(start 67.3227 -27.1272)
		(end 67.2592 -27.3939)
		(width 0.127)
		(layer "In2.Cu")
		(net "P3E_CPU0_PE2_SS_RXN<4>")
	)
	(segment
		(start 77.464158 -6.56844)
		(end 77.313282 -6.784086)
		(width 0.127)
		(layer "In2.Cu")
		(net "P3E_CPU0_PE2_SS_RXN<4>")
	)
	(segment
		(start 77.089508 -15.082012)
		(end 72.94499 -21.000974)
		(width 0.127)
		(layer "In2.Cu")
		(net "P3E_CPU0_PE2_SS_RXN<4>")
	)
	(segment
		(start 67.761104 -33.142936)
		(end 67.759834 -33.143444)
		(width 0.127)
		(layer "In2.Cu")
		(net "P3E_CPU0_PE2_SS_RXN<4>")
	)
	(segment
		(start 82.304636 -3.464306)
		(end 81.759806 -3.560318)
		(width 0.127)
		(layer "In2.Cu")
		(net "P3E_CPU0_PE2_SS_RXN<4>")
	)
	(segment
		(start 89.233756 3.245104)
		(end 87.581994 0.230632)
		(width 0.127)
		(layer "In2.Cu")
		(net "P3E_CPU0_PE2_SS_RXN<4>")
	)
	(segment
		(start 67.2592 -27.3939)
		(end 67.2592 -27.69616)
		(width 0.127)
		(layer "In2.Cu")
		(net "P3E_CPU0_PE2_SS_RXN<4>")
	)
	(segment
		(start 76.648818 -12.622022)
		(end 76.73213 -12.70508)
		(width 0.127)
		(layer "In2.Cu")
		(net "P3E_CPU0_PE2_SS_RXN<4>")
	)
	(segment
		(start 67.759834 -33.143444)
		(end 67.75958 -33.143444)
		(width 0.127)
		(layer "In2.Cu")
		(net "P3E_CPU0_PE2_SS_RXN<4>")
	)
	(arc
		(start 67.75958 -33.143444)
		(mid 67.695817 -33.216897)
		(end 67.702684 -33.313878)
		(width 0.127)
		(layer "In2.Cu")
		(net "P3E_CPU0_PE2_SS_RXN<4>")
	)
	(arc
		(start 76.238354 -11.63066)
		(mid 76.344979 -12.167169)
		(end 76.648818 -12.622022)
		(width 0.127)
		(layer "In2.Cu")
		(net "P3E_CPU0_PE2_SS_RXN<4>")
	)
	(arc
		(start 67.84086 -28.63342)
		(mid 68.174938 -29.135704)
		(end 68.20154 -29.73832)
		(width 0.127)
		(layer "In2.Cu")
		(net "P3E_CPU0_PE2_SS_RXN<4>")
	)
	(arc
		(start 68.20154 -29.73832)
		(mid 68.07132 -30.989895)
		(end 68.25234 -32.23514)
		(width 0.127)
		(layer "In2.Cu")
		(net "P3E_CPU0_PE2_SS_RXN<4>")
	)
	(arc
		(start 77.226414 -7.2771)
		(mid 77.143967 -7.691679)
		(end 76.909168 -8.043164)
		(width 0.127)
		(layer "In2.Cu")
		(net "P3E_CPU0_PE2_SS_RXN<4>")
	)
	(arc
		(start 76.775056 -8.177276)
		(mid 76.377856 -8.771727)
		(end 76.238354 -9.47293)
		(width 0.127)
		(layer "In2.Cu")
		(net "P3E_CPU0_PE2_SS_RXN<4>")
	)
	(arc
		(start 67.2592 -27.69616)
		(mid 67.47828 -28.20932)
		(end 67.84086 -28.63342)
		(width 0.127)
		(layer "In2.Cu")
		(net "P3E_CPU0_PE2_SS_RXN<4>")
	)
	(arc
		(start 76.73213 -12.70508)
		(mid 77.096859 -13.250936)
		(end 77.22489 -13.894816)
		(width 0.127)
		(layer "In2.Cu")
		(net "P3E_CPU0_PE2_SS_RXN<4>")
	)
	(arc
		(start 68.25234 -32.23514)
		(mid 68.21535 -32.729053)
		(end 67.873118 -33.087056)
		(width 0.127)
		(layer "In2.Cu")
		(net "P3E_CPU0_PE2_SS_RXN<4>")
	)
	(arc
		(start 90.010488 5.165852)
		(mid 89.764964 4.990528)
		(end 89.665048 4.705858)
		(width 0.127)
		(layer "In2.Cu")
		(net "P3E_CPU0_PE2_SS_RXN<4>")
	)
	(arc
		(start 89.665048 4.705858)
		(mid 89.527904 3.952305)
		(end 89.233756 3.245104)
		(width 0.127)
		(layer "In2.Cu")
		(net "P3E_CPU0_PE2_SS_RXN<4>")
	)
	(via
		(at 87.419688 5.165852)
		(size 0.508)
		(drill 0.254)
		(layers "F.Cu" "B.Cu")
		(net "P3E_CPU0_PE2_SS_RXN<3>")
	)
	(segment
		(start 87.03564 7.64921)
		(end 87.035386 7.649464)
		(width 0.127)
		(layer "B.Cu")
		(net "P3E_CPU0_PE2_SS_RXN<3>")
	)
	(segment
		(start 87.074502 8.671814)
		(end 87.332312 10.07745)
		(width 0.127)
		(layer "B.Cu")
		(net "P3E_CPU0_PE2_SS_RXN<3>")
	)
	(segment
		(start 87.035386 7.649464)
		(end 87.028528 7.783576)
		(width 0.127)
		(layer "B.Cu")
		(net "P3E_CPU0_PE2_SS_RXN<3>")
	)
	(segment
		(start 87.332312 10.07745)
		(end 87.332312 10.525506)
		(width 0.127)
		(layer "B.Cu")
		(net "P3E_CPU0_PE2_SS_RXN<3>")
	)
	(segment
		(start 87.064088 5.775452)
		(end 87.064088 6.937502)
		(width 0.127)
		(layer "B.Cu")
		(net "P3E_CPU0_PE2_SS_RXN<3>")
	)
	(segment
		(start 87.064088 6.937502)
		(end 87.035386 7.64921)
		(width 0.127)
		(layer "B.Cu")
		(net "P3E_CPU0_PE2_SS_RXN<3>")
	)
	(segment
		(start 87.035386 7.64921)
		(end 87.03564 7.64921)
		(width 0.127)
		(layer "B.Cu")
		(net "P3E_CPU0_PE2_SS_RXN<3>")
	)
	(segment
		(start 87.579962 11.123168)
		(end 87.579962 12.514072)
		(width 0.127)
		(layer "B.Cu")
		(net "P3E_CPU0_PE2_SS_RXN<3>")
	)
	(arc
		(start 87.028528 7.783576)
		(mid 87.041058 8.228236)
		(end 87.074502 8.671814)
		(width 0.127)
		(layer "B.Cu")
		(net "P3E_CPU0_PE2_SS_RXN<3>")
	)
	(arc
		(start 87.419688 5.165852)
		(mid 87.159473 5.422579)
		(end 87.064088 5.775452)
		(width 0.127)
		(layer "B.Cu")
		(net "P3E_CPU0_PE2_SS_RXN<3>")
	)
	(arc
		(start 87.456264 10.824464)
		(mid 87.547836 10.961511)
		(end 87.579962 11.123168)
		(width 0.127)
		(layer "B.Cu")
		(net "P3E_CPU0_PE2_SS_RXN<3>")
	)
	(arc
		(start 87.332312 10.525506)
		(mid 87.364534 10.687318)
		(end 87.456264 10.824464)
		(width 0.127)
		(layer "B.Cu")
		(net "P3E_CPU0_PE2_SS_RXN<3>")
	)
	(segment
		(start 86.53526 3.408426)
		(end 86.931246 4.146042)
		(width 0.127)
		(layer "In2.Cu")
		(net "P3E_CPU0_PE2_SS_RXN<3>")
	)
	(segment
		(start 61.760354 -33.142936)
		(end 61.872368 -33.087056)
		(width 0.127)
		(layer "In2.Cu")
		(net "P3E_CPU0_PE2_SS_RXN<3>")
	)
	(segment
		(start 69.839078 -20.403566)
		(end 72.606408 -16.101568)
		(width 0.127)
		(layer "In2.Cu")
		(net "P3E_CPU0_PE2_SS_RXN<3>")
	)
	(segment
		(start 62.079632 -34.070036)
		(end 61.701934 -33.313878)
		(width 0.127)
		(layer "In2.Cu")
		(net "P3E_CPU0_PE2_SS_RXN<3>")
	)
	(segment
		(start 61.25845 -27.69616)
		(end 61.212476 -27.517344)
		(width 0.127)
		(layer "In2.Cu")
		(net "P3E_CPU0_PE2_SS_RXN<3>")
	)
	(segment
		(start 69.7992 -20.4343)
		(end 69.839078 -20.403566)
		(width 0.127)
		(layer "In2.Cu")
		(net "P3E_CPU0_PE2_SS_RXN<3>")
	)
	(segment
		(start 72.712834 -15.902432)
		(end 73.22439 -14.901164)
		(width 0.127)
		(layer "In2.Cu")
		(net "P3E_CPU0_PE2_SS_RXN<3>")
	)
	(segment
		(start 84.364322 0.309372)
		(end 86.53526 3.408426)
		(width 0.127)
		(layer "In2.Cu")
		(net "P3E_CPU0_PE2_SS_RXN<3>")
	)
	(segment
		(start 74.421238 -4.677918)
		(end 78.299056 -1.962404)
		(width 0.127)
		(layer "In2.Cu")
		(net "P3E_CPU0_PE2_SS_RXN<3>")
	)
	(segment
		(start 61.20892 -27.510994)
		(end 61.20384 -27.383994)
		(width 0.127)
		(layer "In2.Cu")
		(net "P3E_CPU0_PE2_SS_RXN<3>")
	)
	(segment
		(start 61.3156 -27.0002)
		(end 69.7992 -20.4343)
		(width 0.127)
		(layer "In2.Cu")
		(net "P3E_CPU0_PE2_SS_RXN<3>")
	)
	(segment
		(start 61.20384 -27.383994)
		(end 61.19876 -27.2542)
		(width 0.127)
		(layer "In2.Cu")
		(net "P3E_CPU0_PE2_SS_RXN<3>")
	)
	(segment
		(start 72.774556 -8.177276)
		(end 72.908668 -8.043164)
		(width 0.127)
		(layer "In2.Cu")
		(net "P3E_CPU0_PE2_SS_RXN<3>")
	)
	(segment
		(start 72.606408 -16.101568)
		(end 72.712834 -15.902432)
		(width 0.127)
		(layer "In2.Cu")
		(net "P3E_CPU0_PE2_SS_RXN<3>")
	)
	(segment
		(start 72.237854 -11.63066)
		(end 72.237854 -9.47293)
		(width 0.127)
		(layer "In2.Cu")
		(net "P3E_CPU0_PE2_SS_RXN<3>")
	)
	(segment
		(start 73.225914 -7.2771)
		(end 73.225914 -6.77926)
		(width 0.127)
		(layer "In2.Cu")
		(net "P3E_CPU0_PE2_SS_RXN<3>")
	)
	(segment
		(start 73.22439 -14.901164)
		(end 73.22439 -13.894816)
		(width 0.127)
		(layer "In2.Cu")
		(net "P3E_CPU0_PE2_SS_RXN<3>")
	)
	(segment
		(start 61.759084 -33.143444)
		(end 61.760354 -33.142936)
		(width 0.127)
		(layer "In2.Cu")
		(net "P3E_CPU0_PE2_SS_RXN<3>")
	)
	(segment
		(start 61.212476 -27.517344)
		(end 61.20892 -27.514296)
		(width 0.127)
		(layer "In2.Cu")
		(net "P3E_CPU0_PE2_SS_RXN<3>")
	)
	(segment
		(start 73.225914 -6.77926)
		(end 73.318878 -6.25221)
		(width 0.127)
		(layer "In2.Cu")
		(net "P3E_CPU0_PE2_SS_RXN<3>")
	)
	(segment
		(start 78.299056 -1.962404)
		(end 82.069178 -1.29794)
		(width 0.127)
		(layer "In2.Cu")
		(net "P3E_CPU0_PE2_SS_RXN<3>")
	)
	(segment
		(start 61.19876 -27.2542)
		(end 61.3156 -27.0002)
		(width 0.127)
		(layer "In2.Cu")
		(net "P3E_CPU0_PE2_SS_RXN<3>")
	)
	(segment
		(start 61.75883 -33.143444)
		(end 61.759084 -33.143444)
		(width 0.127)
		(layer "In2.Cu")
		(net "P3E_CPU0_PE2_SS_RXN<3>")
	)
	(segment
		(start 73.318878 -6.25221)
		(end 74.421238 -4.677918)
		(width 0.127)
		(layer "In2.Cu")
		(net "P3E_CPU0_PE2_SS_RXN<3>")
	)
	(segment
		(start 82.069178 -1.29794)
		(end 84.364322 0.309372)
		(width 0.127)
		(layer "In2.Cu")
		(net "P3E_CPU0_PE2_SS_RXN<3>")
	)
	(segment
		(start 61.20892 -27.514296)
		(end 61.20892 -27.510994)
		(width 0.127)
		(layer "In2.Cu")
		(net "P3E_CPU0_PE2_SS_RXN<3>")
	)
	(segment
		(start 72.73163 -12.70508)
		(end 72.648318 -12.622022)
		(width 0.127)
		(layer "In2.Cu")
		(net "P3E_CPU0_PE2_SS_RXN<3>")
	)
	(arc
		(start 87.074248 4.705858)
		(mid 87.174166 4.990527)
		(end 87.419688 5.165852)
		(width 0.127)
		(layer "In2.Cu")
		(net "P3E_CPU0_PE2_SS_RXN<3>")
	)
	(arc
		(start 61.872368 -33.087056)
		(mid 62.214517 -32.729017)
		(end 62.25159 -32.23514)
		(width 0.127)
		(layer "In2.Cu")
		(net "P3E_CPU0_PE2_SS_RXN<3>")
	)
	(arc
		(start 72.237854 -9.47293)
		(mid 72.377334 -8.771718)
		(end 72.774556 -8.177276)
		(width 0.127)
		(layer "In2.Cu")
		(net "P3E_CPU0_PE2_SS_RXN<3>")
	)
	(arc
		(start 87.072216 4.643882)
		(mid 87.073631 4.674857)
		(end 87.074248 4.705858)
		(width 0.127)
		(layer "In2.Cu")
		(net "P3E_CPU0_PE2_SS_RXN<3>")
	)
	(arc
		(start 73.22439 -13.894816)
		(mid 73.096318 -13.250953)
		(end 72.73163 -12.70508)
		(width 0.127)
		(layer "In2.Cu")
		(net "P3E_CPU0_PE2_SS_RXN<3>")
	)
	(arc
		(start 62.25159 -32.23514)
		(mid 62.070552 -30.989895)
		(end 62.20079 -29.73832)
		(width 0.127)
		(layer "In2.Cu")
		(net "P3E_CPU0_PE2_SS_RXN<3>")
	)
	(arc
		(start 72.648318 -12.622022)
		(mid 72.344486 -12.167166)
		(end 72.237854 -11.63066)
		(width 0.127)
		(layer "In2.Cu")
		(net "P3E_CPU0_PE2_SS_RXN<3>")
	)
	(arc
		(start 61.701934 -33.313878)
		(mid 61.695175 -33.216933)
		(end 61.75883 -33.143444)
		(width 0.127)
		(layer "In2.Cu")
		(net "P3E_CPU0_PE2_SS_RXN<3>")
	)
	(arc
		(start 61.84011 -28.63342)
		(mid 61.477553 -28.209306)
		(end 61.25845 -27.69616)
		(width 0.127)
		(layer "In2.Cu")
		(net "P3E_CPU0_PE2_SS_RXN<3>")
	)
	(arc
		(start 72.908668 -8.043164)
		(mid 73.143461 -7.691677)
		(end 73.225914 -7.2771)
		(width 0.127)
		(layer "In2.Cu")
		(net "P3E_CPU0_PE2_SS_RXN<3>")
	)
	(arc
		(start 62.20079 -29.73832)
		(mid 62.17406 -29.135746)
		(end 61.84011 -28.63342)
		(width 0.127)
		(layer "In2.Cu")
		(net "P3E_CPU0_PE2_SS_RXN<3>")
	)
	(arc
		(start 86.931246 4.146042)
		(mid 87.028822 4.387291)
		(end 87.072216 4.643882)
		(width 0.127)
		(layer "In2.Cu")
		(net "P3E_CPU0_PE2_SS_RXN<3>")
	)
	(via
		(at 84.828888 5.165852)
		(size 0.508)
		(drill 0.254)
		(layers "F.Cu" "B.Cu")
		(net "P3E_CPU0_PE2_SS_RXN<2>")
	)
	(segment
		(start 85.179916 11.034776)
		(end 85.179916 12.514072)
		(width 0.127)
		(layer "B.Cu")
		(net "P3E_CPU0_PE2_SS_RXN<2>")
	)
	(segment
		(start 84.473288 5.775452)
		(end 84.473288 6.938264)
		(width 0.127)
		(layer "B.Cu")
		(net "P3E_CPU0_PE2_SS_RXN<2>")
	)
	(segment
		(start 84.473288 6.938264)
		(end 84.426044 7.95401)
		(width 0.127)
		(layer "B.Cu")
		(net "P3E_CPU0_PE2_SS_RXN<2>")
	)
	(segment
		(start 84.426044 7.95401)
		(end 84.932266 10.069322)
		(width 0.127)
		(layer "B.Cu")
		(net "P3E_CPU0_PE2_SS_RXN<2>")
	)
	(segment
		(start 84.932266 10.069322)
		(end 84.932266 10.43686)
		(width 0.127)
		(layer "B.Cu")
		(net "P3E_CPU0_PE2_SS_RXN<2>")
	)
	(arc
		(start 85.055964 10.735564)
		(mid 85.147691 10.872844)
		(end 85.179916 11.034776)
		(width 0.127)
		(layer "B.Cu")
		(net "P3E_CPU0_PE2_SS_RXN<2>")
	)
	(arc
		(start 84.828888 5.165852)
		(mid 84.568673 5.422579)
		(end 84.473288 5.775452)
		(width 0.127)
		(layer "B.Cu")
		(net "P3E_CPU0_PE2_SS_RXN<2>")
	)
	(arc
		(start 84.932266 10.43686)
		(mid 84.964419 10.598506)
		(end 85.055964 10.735564)
		(width 0.127)
		(layer "B.Cu")
		(net "P3E_CPU0_PE2_SS_RXN<2>")
	)
	(segment
		(start 82.859626 1.759204)
		(end 81.11998 0.54102)
		(width 0.127)
		(layer "In2.Cu")
		(net "P3E_CPU0_PE2_SS_RXN<2>")
	)
	(segment
		(start 57.3913 -27.051)
		(end 57.277 -27.3685)
		(width 0.127)
		(layer "In2.Cu")
		(net "P3E_CPU0_PE2_SS_RXN<2>")
	)
	(segment
		(start 68.238624 -9.47293)
		(end 68.238624 -11.63066)
		(width 0.127)
		(layer "In2.Cu")
		(net "P3E_CPU0_PE2_SS_RXN<2>")
	)
	(segment
		(start 68.649088 -12.622022)
		(end 68.7324 -12.70508)
		(width 0.127)
		(layer "In2.Cu")
		(net "P3E_CPU0_PE2_SS_RXN<2>")
	)
	(segment
		(start 69.22516 -13.894816)
		(end 68.84035 -16.466058)
		(width 0.127)
		(layer "In2.Cu")
		(net "P3E_CPU0_PE2_SS_RXN<2>")
	)
	(segment
		(start 57.873138 -33.087056)
		(end 57.761124 -33.142936)
		(width 0.127)
		(layer "In2.Cu")
		(net "P3E_CPU0_PE2_SS_RXN<2>")
	)
	(segment
		(start 66.6242 -19.812)
		(end 57.7723 -26.3652)
		(width 0.127)
		(layer "In2.Cu")
		(net "P3E_CPU0_PE2_SS_RXN<2>")
	)
	(segment
		(start 68.84035 -16.466058)
		(end 68.679568 -16.853662)
		(width 0.127)
		(layer "In2.Cu")
		(net "P3E_CPU0_PE2_SS_RXN<2>")
	)
	(segment
		(start 57.759854 -33.143444)
		(end 57.7596 -33.143444)
		(width 0.127)
		(layer "In2.Cu")
		(net "P3E_CPU0_PE2_SS_RXN<2>")
	)
	(segment
		(start 84.474304 4.413504)
		(end 84.392262 3.948176)
		(width 0.127)
		(layer "In2.Cu")
		(net "P3E_CPU0_PE2_SS_RXN<2>")
	)
	(segment
		(start 57.761124 -33.142936)
		(end 57.759854 -33.143444)
		(width 0.127)
		(layer "In2.Cu")
		(net "P3E_CPU0_PE2_SS_RXN<2>")
	)
	(segment
		(start 81.11998 0.54102)
		(end 76.007468 -0.359918)
		(width 0.127)
		(layer "In2.Cu")
		(net "P3E_CPU0_PE2_SS_RXN<2>")
	)
	(segment
		(start 68.679568 -16.853662)
		(end 66.6242 -19.812)
		(width 0.127)
		(layer "In2.Cu")
		(net "P3E_CPU0_PE2_SS_RXN<2>")
	)
	(segment
		(start 57.7723 -26.3652)
		(end 57.3913 -27.051)
		(width 0.127)
		(layer "In2.Cu")
		(net "P3E_CPU0_PE2_SS_RXN<2>")
	)
	(segment
		(start 84.483448 4.705858)
		(end 84.474304 4.413504)
		(width 0.127)
		(layer "In2.Cu")
		(net "P3E_CPU0_PE2_SS_RXN<2>")
	)
	(segment
		(start 71.167752 -3.748532)
		(end 69.287644 -6.433566)
		(width 0.127)
		(layer "In2.Cu")
		(net "P3E_CPU0_PE2_SS_RXN<2>")
	)
	(segment
		(start 69.287644 -6.433566)
		(end 69.226684 -6.77926)
		(width 0.127)
		(layer "In2.Cu")
		(net "P3E_CPU0_PE2_SS_RXN<2>")
	)
	(segment
		(start 57.702704 -33.313878)
		(end 58.080402 -34.070036)
		(width 0.127)
		(layer "In2.Cu")
		(net "P3E_CPU0_PE2_SS_RXN<2>")
	)
	(segment
		(start 57.277 -27.3685)
		(end 57.25922 -27.69616)
		(width 0.127)
		(layer "In2.Cu")
		(net "P3E_CPU0_PE2_SS_RXN<2>")
	)
	(segment
		(start 84.392262 3.948176)
		(end 82.859626 1.759204)
		(width 0.127)
		(layer "In2.Cu")
		(net "P3E_CPU0_PE2_SS_RXN<2>")
	)
	(segment
		(start 76.007468 -0.359918)
		(end 71.167752 -3.748532)
		(width 0.127)
		(layer "In2.Cu")
		(net "P3E_CPU0_PE2_SS_RXN<2>")
	)
	(segment
		(start 69.226684 -6.77926)
		(end 69.226684 -7.2771)
		(width 0.127)
		(layer "In2.Cu")
		(net "P3E_CPU0_PE2_SS_RXN<2>")
	)
	(segment
		(start 68.909438 -8.043164)
		(end 68.775326 -8.177276)
		(width 0.127)
		(layer "In2.Cu")
		(net "P3E_CPU0_PE2_SS_RXN<2>")
	)
	(arc
		(start 58.20156 -29.73832)
		(mid 58.07134 -30.989895)
		(end 58.25236 -32.23514)
		(width 0.127)
		(layer "In2.Cu")
		(net "P3E_CPU0_PE2_SS_RXN<2>")
	)
	(arc
		(start 68.238624 -11.63066)
		(mid 68.345249 -12.167169)
		(end 68.649088 -12.622022)
		(width 0.127)
		(layer "In2.Cu")
		(net "P3E_CPU0_PE2_SS_RXN<2>")
	)
	(arc
		(start 57.84088 -28.63342)
		(mid 58.174958 -29.135704)
		(end 58.20156 -29.73832)
		(width 0.127)
		(layer "In2.Cu")
		(net "P3E_CPU0_PE2_SS_RXN<2>")
	)
	(arc
		(start 57.7596 -33.143444)
		(mid 57.695837 -33.216897)
		(end 57.702704 -33.313878)
		(width 0.127)
		(layer "In2.Cu")
		(net "P3E_CPU0_PE2_SS_RXN<2>")
	)
	(arc
		(start 69.226684 -7.2771)
		(mid 69.144237 -7.691679)
		(end 68.909438 -8.043164)
		(width 0.127)
		(layer "In2.Cu")
		(net "P3E_CPU0_PE2_SS_RXN<2>")
	)
	(arc
		(start 57.25922 -27.69616)
		(mid 57.4783 -28.20932)
		(end 57.84088 -28.63342)
		(width 0.127)
		(layer "In2.Cu")
		(net "P3E_CPU0_PE2_SS_RXN<2>")
	)
	(arc
		(start 58.25236 -32.23514)
		(mid 58.21537 -32.729053)
		(end 57.873138 -33.087056)
		(width 0.127)
		(layer "In2.Cu")
		(net "P3E_CPU0_PE2_SS_RXN<2>")
	)
	(arc
		(start 68.7324 -12.70508)
		(mid 69.097129 -13.250936)
		(end 69.22516 -13.894816)
		(width 0.127)
		(layer "In2.Cu")
		(net "P3E_CPU0_PE2_SS_RXN<2>")
	)
	(arc
		(start 84.828888 5.165852)
		(mid 84.583364 4.990528)
		(end 84.483448 4.705858)
		(width 0.127)
		(layer "In2.Cu")
		(net "P3E_CPU0_PE2_SS_RXN<2>")
	)
	(arc
		(start 68.775326 -8.177276)
		(mid 68.378126 -8.771727)
		(end 68.238624 -9.47293)
		(width 0.127)
		(layer "In2.Cu")
		(net "P3E_CPU0_PE2_SS_RXN<2>")
	)
	(via
		(at 129.72034 5.206492)
		(size 0.508)
		(drill 0.254)
		(layers "F.Cu" "B.Cu")
		(net "P3E_CPU0_PE2_SS_RXN<15>")
	)
	(segment
		(start 127.927608 10.633202)
		(end 127.927608 10.0076)
		(width 0.127)
		(layer "B.Cu")
		(net "P3E_CPU0_PE2_SS_RXN<15>")
	)
	(segment
		(start 129.36474 5.816092)
		(end 129.361438 5.73405)
		(width 0.127)
		(layer "B.Cu")
		(net "P3E_CPU0_PE2_SS_RXN<15>")
	)
	(segment
		(start 128.175004 12.615672)
		(end 128.175004 11.23061)
		(width 0.127)
		(layer "B.Cu")
		(net "P3E_CPU0_PE2_SS_RXN<15>")
	)
	(segment
		(start 129.36474 7.8232)
		(end 129.36474 5.816092)
		(width 0.127)
		(layer "B.Cu")
		(net "P3E_CPU0_PE2_SS_RXN<15>")
	)
	(arc
		(start 128.175004 11.23061)
		(mid 128.142851 11.068964)
		(end 128.051306 10.931906)
		(width 0.127)
		(layer "B.Cu")
		(net "P3E_CPU0_PE2_SS_RXN<15>")
	)
	(arc
		(start 127.927608 10.0076)
		(mid 128.103101 9.44464)
		(end 128.4478 8.9662)
		(width 0.127)
		(layer "B.Cu")
		(net "P3E_CPU0_PE2_SS_RXN<15>")
	)
	(arc
		(start 128.051306 10.931906)
		(mid 127.959734 10.794859)
		(end 127.927608 10.633202)
		(width 0.127)
		(layer "B.Cu")
		(net "P3E_CPU0_PE2_SS_RXN<15>")
	)
	(arc
		(start 128.4478 8.9662)
		(mid 128.676304 8.759492)
		(end 128.9304 8.5852)
		(width 0.127)
		(layer "B.Cu")
		(net "P3E_CPU0_PE2_SS_RXN<15>")
	)
	(arc
		(start 129.361438 5.73405)
		(mid 129.453815 5.411036)
		(end 129.72034 5.206492)
		(width 0.127)
		(layer "B.Cu")
		(net "P3E_CPU0_PE2_SS_RXN<15>")
	)
	(arc
		(start 128.9304 8.5852)
		(mid 129.248494 8.261734)
		(end 129.36474 7.8232)
		(width 0.127)
		(layer "B.Cu")
		(net "P3E_CPU0_PE2_SS_RXN<15>")
	)
	(segment
		(start 112.53089 -32.882586)
		(end 112.531144 -32.882586)
		(width 0.127)
		(layer "In2.Cu")
		(net "P3E_CPU0_PE2_SS_RXN<15>")
	)
	(segment
		(start 128.702562 2.98577)
		(end 128.5748 2.2606)
		(width 0.127)
		(layer "In2.Cu")
		(net "P3E_CPU0_PE2_SS_RXN<15>")
	)
	(segment
		(start 113.432082 -26.154634)
		(end 113.555272 -26.34869)
		(width 0.127)
		(layer "In2.Cu")
		(net "P3E_CPU0_PE2_SS_RXN<15>")
	)
	(segment
		(start 113.192052 -27.772614)
		(end 113.02492 -28.157932)
		(width 0.127)
		(layer "In2.Cu")
		(net "P3E_CPU0_PE2_SS_RXN<15>")
	)
	(segment
		(start 113.192052 -27.69489)
		(end 113.192052 -27.772614)
		(width 0.127)
		(layer "In2.Cu")
		(net "P3E_CPU0_PE2_SS_RXN<15>")
	)
	(segment
		(start 113.472214 -26.720546)
		(end 113.278158 -26.843736)
		(width 0.127)
		(layer "In2.Cu")
		(net "P3E_CPU0_PE2_SS_RXN<15>")
	)
	(segment
		(start 114.545618 -21.166328)
		(end 113.66881 -25.093676)
		(width 0.127)
		(layer "In2.Cu")
		(net "P3E_CPU0_PE2_SS_RXN<15>")
	)
	(segment
		(start 113.1951 -27.215592)
		(end 113.1951 -27.69489)
		(width 0.127)
		(layer "In2.Cu")
		(net "P3E_CPU0_PE2_SS_RXN<15>")
	)
	(segment
		(start 129.3749 4.746498)
		(end 129.361692 4.327398)
		(width 0.127)
		(layer "In2.Cu")
		(net "P3E_CPU0_PE2_SS_RXN<15>")
	)
	(segment
		(start 120.871996 -12.130786)
		(end 114.545618 -21.166328)
		(width 0.127)
		(layer "In2.Cu")
		(net "P3E_CPU0_PE2_SS_RXN<15>")
	)
	(segment
		(start 113.66881 -25.093676)
		(end 113.792 -25.287732)
		(width 0.127)
		(layer "In2.Cu")
		(net "P3E_CPU0_PE2_SS_RXN<15>")
	)
	(segment
		(start 113.1951 -27.69489)
		(end 113.192052 -27.69489)
		(width 0.127)
		(layer "In2.Cu")
		(net "P3E_CPU0_PE2_SS_RXN<15>")
	)
	(segment
		(start 128.439672 1.493774)
		(end 121.53646 -8.36168)
		(width 0.127)
		(layer "In2.Cu")
		(net "P3E_CPU0_PE2_SS_RXN<15>")
	)
	(segment
		(start 113.792 -25.287732)
		(end 113.708942 -25.659588)
		(width 0.127)
		(layer "In2.Cu")
		(net "P3E_CPU0_PE2_SS_RXN<15>")
	)
	(segment
		(start 113.708942 -25.659588)
		(end 113.514886 -25.782778)
		(width 0.127)
		(layer "In2.Cu")
		(net "P3E_CPU0_PE2_SS_RXN<15>")
	)
	(segment
		(start 113.278158 -26.843736)
		(end 113.1951 -27.215592)
		(width 0.127)
		(layer "In2.Cu")
		(net "P3E_CPU0_PE2_SS_RXN<15>")
	)
	(segment
		(start 113.514886 -25.782778)
		(end 113.432082 -26.154634)
		(width 0.127)
		(layer "In2.Cu")
		(net "P3E_CPU0_PE2_SS_RXN<15>")
	)
	(segment
		(start 121.53646 -8.36168)
		(end 120.871996 -12.130786)
		(width 0.127)
		(layer "In2.Cu")
		(net "P3E_CPU0_PE2_SS_RXN<15>")
	)
	(segment
		(start 128.5748 2.2606)
		(end 128.439672 1.493774)
		(width 0.127)
		(layer "In2.Cu")
		(net "P3E_CPU0_PE2_SS_RXN<15>")
	)
	(segment
		(start 129.267458 3.792474)
		(end 128.702562 2.98577)
		(width 0.127)
		(layer "In2.Cu")
		(net "P3E_CPU0_PE2_SS_RXN<15>")
	)
	(segment
		(start 112.701578 -32.82569)
		(end 113.080292 -32.069786)
		(width 0.127)
		(layer "In2.Cu")
		(net "P3E_CPU0_PE2_SS_RXN<15>")
	)
	(segment
		(start 129.361692 4.327398)
		(end 129.267458 3.792474)
		(width 0.127)
		(layer "In2.Cu")
		(net "P3E_CPU0_PE2_SS_RXN<15>")
	)
	(segment
		(start 112.417098 -32.82569)
		(end 112.53089 -32.882586)
		(width 0.127)
		(layer "In2.Cu")
		(net "P3E_CPU0_PE2_SS_RXN<15>")
	)
	(segment
		(start 113.555272 -26.34869)
		(end 113.472214 -26.720546)
		(width 0.127)
		(layer "In2.Cu")
		(net "P3E_CPU0_PE2_SS_RXN<15>")
	)
	(arc
		(start 112.531144 -32.882586)
		(mid 112.6282 -32.889527)
		(end 112.701578 -32.82569)
		(width 0.127)
		(layer "In2.Cu")
		(net "P3E_CPU0_PE2_SS_RXN<15>")
	)
	(arc
		(start 112.42421 -29.10586)
		(mid 112.32447 -29.264407)
		(end 112.27943 -29.44622)
		(width 0.127)
		(layer "In2.Cu")
		(net "P3E_CPU0_PE2_SS_RXN<15>")
	)
	(arc
		(start 112.15497 -32.31896)
		(mid 112.203545 -32.615005)
		(end 112.417098 -32.82569)
		(width 0.127)
		(layer "In2.Cu")
		(net "P3E_CPU0_PE2_SS_RXN<15>")
	)
	(arc
		(start 129.72034 5.206492)
		(mid 129.474839 5.031139)
		(end 129.3749 4.746498)
		(width 0.127)
		(layer "In2.Cu")
		(net "P3E_CPU0_PE2_SS_RXN<15>")
	)
	(arc
		(start 111.871506 -30.739842)
		(mid 111.866101 -30.923369)
		(end 111.888524 -31.105602)
		(width 0.127)
		(layer "In2.Cu")
		(net "P3E_CPU0_PE2_SS_RXN<15>")
	)
	(arc
		(start 112.00511 -31.4325)
		(mid 112.151389 -31.863665)
		(end 112.15497 -32.31896)
		(width 0.127)
		(layer "In2.Cu")
		(net "P3E_CPU0_PE2_SS_RXN<15>")
	)
	(arc
		(start 112.27943 -29.44622)
		(mid 112.181716 -29.922871)
		(end 111.97463 -30.36316)
		(width 0.127)
		(layer "In2.Cu")
		(net "P3E_CPU0_PE2_SS_RXN<15>")
	)
	(arc
		(start 113.02492 -28.157932)
		(mid 112.761427 -28.655255)
		(end 112.42421 -29.10586)
		(width 0.127)
		(layer "In2.Cu")
		(net "P3E_CPU0_PE2_SS_RXN<15>")
	)
	(arc
		(start 111.97463 -30.36316)
		(mid 111.907757 -30.547309)
		(end 111.871506 -30.739842)
		(width 0.127)
		(layer "In2.Cu")
		(net "P3E_CPU0_PE2_SS_RXN<15>")
	)
	(arc
		(start 111.888524 -31.105602)
		(mid 111.935033 -31.273253)
		(end 112.00511 -31.4325)
		(width 0.127)
		(layer "In2.Cu")
		(net "P3E_CPU0_PE2_SS_RXN<15>")
	)
	(via
		(at 127.12954 5.206492)
		(size 0.508)
		(drill 0.254)
		(layers "F.Cu" "B.Cu")
		(net "P3E_CPU0_PE2_SS_RXN<14>")
	)
	(segment
		(start 126.755144 7.984744)
		(end 126.728728 7.56666)
		(width 0.127)
		(layer "B.Cu")
		(net "P3E_CPU0_PE2_SS_RXN<14>")
	)
	(segment
		(start 126.77394 6.594856)
		(end 126.77394 5.816092)
		(width 0.127)
		(layer "B.Cu")
		(net "P3E_CPU0_PE2_SS_RXN<14>")
	)
	(segment
		(start 125.774958 12.615672)
		(end 125.774958 11.218164)
		(width 0.127)
		(layer "B.Cu")
		(net "P3E_CPU0_PE2_SS_RXN<14>")
	)
	(segment
		(start 126.728728 7.56666)
		(end 126.772162 6.628892)
		(width 0.127)
		(layer "B.Cu")
		(net "P3E_CPU0_PE2_SS_RXN<14>")
	)
	(segment
		(start 125.527562 10.620756)
		(end 125.527562 9.8552)
		(width 0.127)
		(layer "B.Cu")
		(net "P3E_CPU0_PE2_SS_RXN<14>")
	)
	(segment
		(start 126.754128 7.98576)
		(end 126.755144 7.984744)
		(width 0.127)
		(layer "B.Cu")
		(net "P3E_CPU0_PE2_SS_RXN<14>")
	)
	(segment
		(start 126.772162 6.628892)
		(end 126.77394 6.594856)
		(width 0.127)
		(layer "B.Cu")
		(net "P3E_CPU0_PE2_SS_RXN<14>")
	)
	(segment
		(start 126.754128 7.986776)
		(end 126.754128 7.98576)
		(width 0.127)
		(layer "B.Cu")
		(net "P3E_CPU0_PE2_SS_RXN<14>")
	)
	(arc
		(start 126.77394 5.816092)
		(mid 126.869341 5.463229)
		(end 127.12954 5.206492)
		(width 0.127)
		(layer "B.Cu")
		(net "P3E_CPU0_PE2_SS_RXN<14>")
	)
	(arc
		(start 126.5936 8.5344)
		(mid 126.700905 8.285897)
		(end 126.751842 8.02005)
		(width 0.127)
		(layer "B.Cu")
		(net "P3E_CPU0_PE2_SS_RXN<14>")
	)
	(arc
		(start 126.1618 8.9154)
		(mid 126.409454 8.760894)
		(end 126.5936 8.5344)
		(width 0.127)
		(layer "B.Cu")
		(net "P3E_CPU0_PE2_SS_RXN<14>")
	)
	(arc
		(start 125.65126 10.91946)
		(mid 125.559688 10.782413)
		(end 125.527562 10.620756)
		(width 0.127)
		(layer "B.Cu")
		(net "P3E_CPU0_PE2_SS_RXN<14>")
	)
	(arc
		(start 125.527562 9.8552)
		(mid 125.703243 9.289852)
		(end 126.1618 8.9154)
		(width 0.127)
		(layer "B.Cu")
		(net "P3E_CPU0_PE2_SS_RXN<14>")
	)
	(arc
		(start 126.751842 8.02005)
		(mid 126.753098 8.003421)
		(end 126.754128 7.986776)
		(width 0.127)
		(layer "B.Cu")
		(net "P3E_CPU0_PE2_SS_RXN<14>")
	)
	(arc
		(start 125.774958 11.218164)
		(mid 125.742805 11.056518)
		(end 125.65126 10.91946)
		(width 0.127)
		(layer "B.Cu")
		(net "P3E_CPU0_PE2_SS_RXN<14>")
	)
	(segment
		(start 109.2327 -27.2669)
		(end 109.192568 -27.773376)
		(width 0.127)
		(layer "In2.Cu")
		(net "P3E_CPU0_PE2_SS_RXN<14>")
	)
	(segment
		(start 110.047786 -25.6667)
		(end 109.834934 -25.753822)
		(width 0.127)
		(layer "In2.Cu")
		(net "P3E_CPU0_PE2_SS_RXN<14>")
	)
	(segment
		(start 108.417868 -32.82569)
		(end 108.53166 -32.882586)
		(width 0.127)
		(layer "In2.Cu")
		(net "P3E_CPU0_PE2_SS_RXN<14>")
	)
	(segment
		(start 110.528862 -24.100282)
		(end 110.61573 -24.31288)
		(width 0.127)
		(layer "In2.Cu")
		(net "P3E_CPU0_PE2_SS_RXN<14>")
	)
	(segment
		(start 126.297944 1.747266)
		(end 125.699012 0.891794)
		(width 0.127)
		(layer "In2.Cu")
		(net "P3E_CPU0_PE2_SS_RXN<14>")
	)
	(segment
		(start 109.232954 -27.266646)
		(end 109.2327 -27.2669)
		(width 0.127)
		(layer "In2.Cu")
		(net "P3E_CPU0_PE2_SS_RXN<14>")
	)
	(segment
		(start 109.232446 -27.266392)
		(end 109.232192 -27.266646)
		(width 0.127)
		(layer "In2.Cu")
		(net "P3E_CPU0_PE2_SS_RXN<14>")
	)
	(segment
		(start 109.253274 -27.140154)
		(end 109.232446 -27.266392)
		(width 0.127)
		(layer "In2.Cu")
		(net "P3E_CPU0_PE2_SS_RXN<14>")
	)
	(segment
		(start 109.41431 -26.756106)
		(end 109.253274 -27.140154)
		(width 0.127)
		(layer "In2.Cu")
		(net "P3E_CPU0_PE2_SS_RXN<14>")
	)
	(segment
		(start 110.255558 -24.751284)
		(end 110.108238 -25.102566)
		(width 0.127)
		(layer "In2.Cu")
		(net "P3E_CPU0_PE2_SS_RXN<14>")
	)
	(segment
		(start 108.702348 -32.82569)
		(end 109.079792 -32.069786)
		(width 0.127)
		(layer "In2.Cu")
		(net "P3E_CPU0_PE2_SS_RXN<14>")
	)
	(segment
		(start 110.46841 -24.664416)
		(end 110.255558 -24.751284)
		(width 0.127)
		(layer "In2.Cu")
		(net "P3E_CPU0_PE2_SS_RXN<14>")
	)
	(segment
		(start 109.834934 -25.753822)
		(end 109.687614 -26.105104)
		(width 0.127)
		(layer "In2.Cu")
		(net "P3E_CPU0_PE2_SS_RXN<14>")
	)
	(segment
		(start 109.232192 -27.266646)
		(end 109.232954 -27.266646)
		(width 0.127)
		(layer "In2.Cu")
		(net "P3E_CPU0_PE2_SS_RXN<14>")
	)
	(segment
		(start 110.108238 -25.102566)
		(end 110.195106 -25.315418)
		(width 0.127)
		(layer "In2.Cu")
		(net "P3E_CPU0_PE2_SS_RXN<14>")
	)
	(segment
		(start 109.627162 -26.669238)
		(end 109.41431 -26.756106)
		(width 0.127)
		(layer "In2.Cu")
		(net "P3E_CPU0_PE2_SS_RXN<14>")
	)
	(segment
		(start 111.186722 -22.53234)
		(end 110.528862 -24.100282)
		(width 0.127)
		(layer "In2.Cu")
		(net "P3E_CPU0_PE2_SS_RXN<14>")
	)
	(segment
		(start 108.53166 -32.882586)
		(end 108.531914 -32.882586)
		(width 0.127)
		(layer "In2.Cu")
		(net "P3E_CPU0_PE2_SS_RXN<14>")
	)
	(segment
		(start 109.774482 -26.317956)
		(end 109.627162 -26.669238)
		(width 0.127)
		(layer "In2.Cu")
		(net "P3E_CPU0_PE2_SS_RXN<14>")
	)
	(segment
		(start 118.828312 -11.618722)
		(end 111.186722 -22.53234)
		(width 0.127)
		(layer "In2.Cu")
		(net "P3E_CPU0_PE2_SS_RXN<14>")
	)
	(segment
		(start 119.464582 -8.010652)
		(end 118.828312 -11.618722)
		(width 0.127)
		(layer "In2.Cu")
		(net "P3E_CPU0_PE2_SS_RXN<14>")
	)
	(segment
		(start 109.192568 -27.773376)
		(end 109.02569 -28.157932)
		(width 0.127)
		(layer "In2.Cu")
		(net "P3E_CPU0_PE2_SS_RXN<14>")
	)
	(segment
		(start 110.195106 -25.315418)
		(end 110.047786 -25.6667)
		(width 0.127)
		(layer "In2.Cu")
		(net "P3E_CPU0_PE2_SS_RXN<14>")
	)
	(segment
		(start 110.61573 -24.31288)
		(end 110.46841 -24.664416)
		(width 0.127)
		(layer "In2.Cu")
		(net "P3E_CPU0_PE2_SS_RXN<14>")
	)
	(segment
		(start 109.687614 -26.105104)
		(end 109.774482 -26.317956)
		(width 0.127)
		(layer "In2.Cu")
		(net "P3E_CPU0_PE2_SS_RXN<14>")
	)
	(segment
		(start 126.7841 4.746498)
		(end 126.774956 4.454144)
		(width 0.127)
		(layer "In2.Cu")
		(net "P3E_CPU0_PE2_SS_RXN<14>")
	)
	(segment
		(start 125.699012 0.891794)
		(end 119.464582 -8.010652)
		(width 0.127)
		(layer "In2.Cu")
		(net "P3E_CPU0_PE2_SS_RXN<14>")
	)
	(segment
		(start 126.774956 4.454144)
		(end 126.297944 1.747266)
		(width 0.127)
		(layer "In2.Cu")
		(net "P3E_CPU0_PE2_SS_RXN<14>")
	)
	(arc
		(start 127.12954 5.206492)
		(mid 126.884016 5.031168)
		(end 126.7841 4.746498)
		(width 0.127)
		(layer "In2.Cu")
		(net "P3E_CPU0_PE2_SS_RXN<14>")
	)
	(arc
		(start 107.9754 -30.36316)
		(mid 107.908527 -30.547309)
		(end 107.872276 -30.739842)
		(width 0.127)
		(layer "In2.Cu")
		(net "P3E_CPU0_PE2_SS_RXN<14>")
	)
	(arc
		(start 108.531914 -32.882586)
		(mid 108.62897 -32.889527)
		(end 108.702348 -32.82569)
		(width 0.127)
		(layer "In2.Cu")
		(net "P3E_CPU0_PE2_SS_RXN<14>")
	)
	(arc
		(start 108.00588 -31.4325)
		(mid 108.152159 -31.863665)
		(end 108.15574 -32.31896)
		(width 0.127)
		(layer "In2.Cu")
		(net "P3E_CPU0_PE2_SS_RXN<14>")
	)
	(arc
		(start 108.42498 -29.10586)
		(mid 108.32524 -29.264407)
		(end 108.2802 -29.44622)
		(width 0.127)
		(layer "In2.Cu")
		(net "P3E_CPU0_PE2_SS_RXN<14>")
	)
	(arc
		(start 108.15574 -32.31896)
		(mid 108.204315 -32.615005)
		(end 108.417868 -32.82569)
		(width 0.127)
		(layer "In2.Cu")
		(net "P3E_CPU0_PE2_SS_RXN<14>")
	)
	(arc
		(start 107.872276 -30.739842)
		(mid 107.866871 -30.923369)
		(end 107.889294 -31.105602)
		(width 0.127)
		(layer "In2.Cu")
		(net "P3E_CPU0_PE2_SS_RXN<14>")
	)
	(arc
		(start 109.02569 -28.157932)
		(mid 108.762197 -28.655255)
		(end 108.42498 -29.10586)
		(width 0.127)
		(layer "In2.Cu")
		(net "P3E_CPU0_PE2_SS_RXN<14>")
	)
	(arc
		(start 108.2802 -29.44622)
		(mid 108.182486 -29.922871)
		(end 107.9754 -30.36316)
		(width 0.127)
		(layer "In2.Cu")
		(net "P3E_CPU0_PE2_SS_RXN<14>")
	)
	(arc
		(start 107.889294 -31.105602)
		(mid 107.935794 -31.273257)
		(end 108.00588 -31.4325)
		(width 0.127)
		(layer "In2.Cu")
		(net "P3E_CPU0_PE2_SS_RXN<14>")
	)
	(via
		(at 124.53874 5.206492)
		(size 0.508)
		(drill 0.254)
		(layers "F.Cu" "B.Cu")
		(net "P3E_CPU0_PE2_SS_RXN<13>")
	)
	(segment
		(start 123.127516 9.8806)
		(end 123.127516 10.60831)
		(width 0.127)
		(layer "B.Cu")
		(net "P3E_CPU0_PE2_SS_RXN<13>")
	)
	(segment
		(start 124.182886 8.116062)
		(end 124.17933 8.11911)
		(width 0.127)
		(layer "B.Cu")
		(net "P3E_CPU0_PE2_SS_RXN<13>")
	)
	(segment
		(start 124.136404 7.562596)
		(end 124.182886 8.116062)
		(width 0.127)
		(layer "B.Cu")
		(net "P3E_CPU0_PE2_SS_RXN<13>")
	)
	(segment
		(start 124.17933 8.11911)
		(end 124.178822 8.122412)
		(width 0.127)
		(layer "B.Cu")
		(net "P3E_CPU0_PE2_SS_RXN<13>")
	)
	(segment
		(start 123.9012 8.6868)
		(end 123.625102 8.942324)
		(width 0.127)
		(layer "B.Cu")
		(net "P3E_CPU0_PE2_SS_RXN<13>")
	)
	(segment
		(start 123.375166 11.206226)
		(end 123.375166 12.615672)
		(width 0.127)
		(layer "B.Cu")
		(net "P3E_CPU0_PE2_SS_RXN<13>")
	)
	(segment
		(start 124.102368 7.163308)
		(end 124.136404 7.562596)
		(width 0.127)
		(layer "B.Cu")
		(net "P3E_CPU0_PE2_SS_RXN<13>")
	)
	(segment
		(start 124.18314 5.816092)
		(end 124.18314 6.602476)
		(width 0.127)
		(layer "B.Cu")
		(net "P3E_CPU0_PE2_SS_RXN<13>")
	)
	(segment
		(start 123.625102 8.942324)
		(end 123.373642 9.175496)
		(width 0.127)
		(layer "B.Cu")
		(net "P3E_CPU0_PE2_SS_RXN<13>")
	)
	(segment
		(start 124.18314 6.602476)
		(end 124.102368 7.163308)
		(width 0.127)
		(layer "B.Cu")
		(net "P3E_CPU0_PE2_SS_RXN<13>")
	)
	(arc
		(start 123.127516 10.60831)
		(mid 123.159669 10.769956)
		(end 123.251214 10.907014)
		(width 0.127)
		(layer "B.Cu")
		(net "P3E_CPU0_PE2_SS_RXN<13>")
	)
	(arc
		(start 123.373642 9.175496)
		(mid 123.162986 9.497461)
		(end 123.127516 9.8806)
		(width 0.127)
		(layer "B.Cu")
		(net "P3E_CPU0_PE2_SS_RXN<13>")
	)
	(arc
		(start 124.178822 8.122412)
		(mid 124.092418 8.430391)
		(end 123.9012 8.6868)
		(width 0.127)
		(layer "B.Cu")
		(net "P3E_CPU0_PE2_SS_RXN<13>")
	)
	(arc
		(start 124.53874 5.206492)
		(mid 124.278525 5.463219)
		(end 124.18314 5.816092)
		(width 0.127)
		(layer "B.Cu")
		(net "P3E_CPU0_PE2_SS_RXN<13>")
	)
	(arc
		(start 123.251214 10.907014)
		(mid 123.342941 11.044294)
		(end 123.375166 11.206226)
		(width 0.127)
		(layer "B.Cu")
		(net "P3E_CPU0_PE2_SS_RXN<13>")
	)
	(segment
		(start 114.7064 -8.70204)
		(end 115.443 -7.747)
		(width 0.127)
		(layer "In2.Cu")
		(net "P3E_CPU0_PE2_SS_RXN<13>")
	)
	(segment
		(start 106.79557 -23.342346)
		(end 112.972088 -14.837918)
		(width 0.127)
		(layer "In2.Cu")
		(net "P3E_CPU0_PE2_SS_RXN<13>")
	)
	(segment
		(start 112.972088 -14.837918)
		(end 112.97285 -14.835378)
		(width 0.127)
		(layer "In2.Cu")
		(net "P3E_CPU0_PE2_SS_RXN<13>")
	)
	(segment
		(start 118.025672 -5.208016)
		(end 118.36654 -4.969256)
		(width 0.127)
		(layer "In2.Cu")
		(net "P3E_CPU0_PE2_SS_RXN<13>")
	)
	(segment
		(start 105.679494 -26.163524)
		(end 105.819448 -25.809194)
		(width 0.127)
		(layer "In2.Cu")
		(net "P3E_CPU0_PE2_SS_RXN<13>")
	)
	(segment
		(start 118.36654 -4.969256)
		(end 123.933712 2.981452)
		(width 0.127)
		(layer "In2.Cu")
		(net "P3E_CPU0_PE2_SS_RXN<13>")
	)
	(segment
		(start 116.143278 -6.526022)
		(end 118.025672 -5.208016)
		(width 0.127)
		(layer "In2.Cu")
		(net "P3E_CPU0_PE2_SS_RXN<13>")
	)
	(segment
		(start 105.279444 -27.174444)
		(end 105.419652 -26.820114)
		(width 0.127)
		(layer "In2.Cu")
		(net "P3E_CPU0_PE2_SS_RXN<13>")
	)
	(segment
		(start 115.442746 -7.744968)
		(end 115.443508 -7.743444)
		(width 0.127)
		(layer "In2.Cu")
		(net "P3E_CPU0_PE2_SS_RXN<13>")
	)
	(segment
		(start 123.933712 2.981452)
		(end 124.182124 4.391152)
		(width 0.127)
		(layer "In2.Cu")
		(net "P3E_CPU0_PE2_SS_RXN<13>")
	)
	(segment
		(start 106.219498 -24.798528)
		(end 106.430572 -24.707088)
		(width 0.127)
		(layer "In2.Cu")
		(net "P3E_CPU0_PE2_SS_RXN<13>")
	)
	(segment
		(start 115.443 -7.747)
		(end 115.443508 -7.746238)
		(width 0.127)
		(layer "In2.Cu")
		(net "P3E_CPU0_PE2_SS_RXN<13>")
	)
	(segment
		(start 105.77068 -26.374598)
		(end 105.679494 -26.163524)
		(width 0.127)
		(layer "In2.Cu")
		(net "P3E_CPU0_PE2_SS_RXN<13>")
	)
	(segment
		(start 105.079292 -32.069786)
		(end 104.701848 -32.82569)
		(width 0.127)
		(layer "In2.Cu")
		(net "P3E_CPU0_PE2_SS_RXN<13>")
	)
	(segment
		(start 104.42448 -29.10586)
		(end 104.573324 -28.957016)
		(width 0.127)
		(layer "In2.Cu")
		(net "P3E_CPU0_PE2_SS_RXN<13>")
	)
	(segment
		(start 106.07929 -25.152604)
		(end 106.219498 -24.798528)
		(width 0.127)
		(layer "In2.Cu")
		(net "P3E_CPU0_PE2_SS_RXN<13>")
	)
	(segment
		(start 105.419652 -26.820114)
		(end 105.630472 -26.728928)
		(width 0.127)
		(layer "In2.Cu")
		(net "P3E_CPU0_PE2_SS_RXN<13>")
	)
	(segment
		(start 114.19967 -11.87958)
		(end 114.19967 -10.340086)
		(width 0.127)
		(layer "In2.Cu")
		(net "P3E_CPU0_PE2_SS_RXN<13>")
	)
	(segment
		(start 106.47934 -24.141938)
		(end 106.79557 -23.342346)
		(width 0.127)
		(layer "In2.Cu")
		(net "P3E_CPU0_PE2_SS_RXN<13>")
	)
	(segment
		(start 112.97285 -14.835378)
		(end 113.219484 -14.351254)
		(width 0.127)
		(layer "In2.Cu")
		(net "P3E_CPU0_PE2_SS_RXN<13>")
	)
	(segment
		(start 106.430572 -24.707088)
		(end 106.570526 -24.352758)
		(width 0.127)
		(layer "In2.Cu")
		(net "P3E_CPU0_PE2_SS_RXN<13>")
	)
	(segment
		(start 114.19967 -10.340086)
		(end 114.7064 -8.70204)
		(width 0.127)
		(layer "In2.Cu")
		(net "P3E_CPU0_PE2_SS_RXN<13>")
	)
	(segment
		(start 124.182124 4.391152)
		(end 124.1933 4.746244)
		(width 0.127)
		(layer "In2.Cu")
		(net "P3E_CPU0_PE2_SS_RXN<13>")
	)
	(segment
		(start 105.255568 -27.301952)
		(end 105.279444 -27.174444)
		(width 0.127)
		(layer "In2.Cu")
		(net "P3E_CPU0_PE2_SS_RXN<13>")
	)
	(segment
		(start 106.570526 -24.352758)
		(end 106.47934 -24.141938)
		(width 0.127)
		(layer "In2.Cu")
		(net "P3E_CPU0_PE2_SS_RXN<13>")
	)
	(segment
		(start 105.819448 -25.809194)
		(end 106.030522 -25.718008)
		(width 0.127)
		(layer "In2.Cu")
		(net "P3E_CPU0_PE2_SS_RXN<13>")
	)
	(segment
		(start 105.630472 -26.728928)
		(end 105.77068 -26.374598)
		(width 0.127)
		(layer "In2.Cu")
		(net "P3E_CPU0_PE2_SS_RXN<13>")
	)
	(segment
		(start 104.531414 -32.882586)
		(end 104.53116 -32.882586)
		(width 0.127)
		(layer "In2.Cu")
		(net "P3E_CPU0_PE2_SS_RXN<13>")
	)
	(segment
		(start 104.53116 -32.882586)
		(end 104.417368 -32.82569)
		(width 0.127)
		(layer "In2.Cu")
		(net "P3E_CPU0_PE2_SS_RXN<13>")
	)
	(segment
		(start 113.219484 -14.351254)
		(end 113.219484 -13.932408)
		(width 0.127)
		(layer "In2.Cu")
		(net "P3E_CPU0_PE2_SS_RXN<13>")
	)
	(segment
		(start 113.66881 -12.84732)
		(end 113.890806 -12.625324)
		(width 0.127)
		(layer "In2.Cu")
		(net "P3E_CPU0_PE2_SS_RXN<13>")
	)
	(segment
		(start 106.030522 -25.718008)
		(end 106.17073 -25.363678)
		(width 0.127)
		(layer "In2.Cu")
		(net "P3E_CPU0_PE2_SS_RXN<13>")
	)
	(segment
		(start 106.17073 -25.363678)
		(end 106.07929 -25.152604)
		(width 0.127)
		(layer "In2.Cu")
		(net "P3E_CPU0_PE2_SS_RXN<13>")
	)
	(segment
		(start 115.443508 -7.746238)
		(end 115.442746 -7.744968)
		(width 0.127)
		(layer "In2.Cu")
		(net "P3E_CPU0_PE2_SS_RXN<13>")
	)
	(segment
		(start 115.443508 -7.743444)
		(end 116.143278 -6.526022)
		(width 0.127)
		(layer "In2.Cu")
		(net "P3E_CPU0_PE2_SS_RXN<13>")
	)
	(segment
		(start 105.2576 -27.305)
		(end 105.255568 -27.301952)
		(width 0.127)
		(layer "In2.Cu")
		(net "P3E_CPU0_PE2_SS_RXN<13>")
	)
	(arc
		(start 113.890806 -12.625324)
		(mid 114.119423 -12.283174)
		(end 114.19967 -11.87958)
		(width 0.127)
		(layer "In2.Cu")
		(net "P3E_CPU0_PE2_SS_RXN<13>")
	)
	(arc
		(start 104.2797 -29.44622)
		(mid 104.324749 -29.264411)
		(end 104.42448 -29.10586)
		(width 0.127)
		(layer "In2.Cu")
		(net "P3E_CPU0_PE2_SS_RXN<13>")
	)
	(arc
		(start 104.701848 -32.82569)
		(mid 104.628434 -32.889419)
		(end 104.531414 -32.882586)
		(width 0.127)
		(layer "In2.Cu")
		(net "P3E_CPU0_PE2_SS_RXN<13>")
	)
	(arc
		(start 104.573324 -28.957016)
		(mid 105.079771 -28.199065)
		(end 105.2576 -27.305)
		(width 0.127)
		(layer "In2.Cu")
		(net "P3E_CPU0_PE2_SS_RXN<13>")
	)
	(arc
		(start 113.219484 -13.932408)
		(mid 113.336254 -13.345185)
		(end 113.66881 -12.84732)
		(width 0.127)
		(layer "In2.Cu")
		(net "P3E_CPU0_PE2_SS_RXN<13>")
	)
	(arc
		(start 124.1933 4.746244)
		(mid 124.193428 4.747387)
		(end 124.193554 4.74853)
		(width 0.127)
		(layer "In2.Cu")
		(net "P3E_CPU0_PE2_SS_RXN<13>")
	)
	(arc
		(start 103.888794 -31.105602)
		(mid 103.866349 -30.92337)
		(end 103.871776 -30.739842)
		(width 0.127)
		(layer "In2.Cu")
		(net "P3E_CPU0_PE2_SS_RXN<13>")
	)
	(arc
		(start 103.871776 -30.739842)
		(mid 103.908031 -30.547311)
		(end 103.9749 -30.36316)
		(width 0.127)
		(layer "In2.Cu")
		(net "P3E_CPU0_PE2_SS_RXN<13>")
	)
	(arc
		(start 103.9749 -30.36316)
		(mid 104.181938 -29.922855)
		(end 104.2797 -29.44622)
		(width 0.127)
		(layer "In2.Cu")
		(net "P3E_CPU0_PE2_SS_RXN<13>")
	)
	(arc
		(start 124.193554 4.74853)
		(mid 124.293887 5.031985)
		(end 124.53874 5.206492)
		(width 0.127)
		(layer "In2.Cu")
		(net "P3E_CPU0_PE2_SS_RXN<13>")
	)
	(arc
		(start 104.00538 -31.4325)
		(mid 103.935301 -31.273255)
		(end 103.888794 -31.105602)
		(width 0.127)
		(layer "In2.Cu")
		(net "P3E_CPU0_PE2_SS_RXN<13>")
	)
	(arc
		(start 104.417368 -32.82569)
		(mid 104.20386 -32.614982)
		(end 104.15524 -32.31896)
		(width 0.127)
		(layer "In2.Cu")
		(net "P3E_CPU0_PE2_SS_RXN<13>")
	)
	(arc
		(start 104.15524 -32.31896)
		(mid 104.151701 -31.863658)
		(end 104.00538 -31.4325)
		(width 0.127)
		(layer "In2.Cu")
		(net "P3E_CPU0_PE2_SS_RXN<13>")
	)
	(via
		(at 121.94794 5.206492)
		(size 0.508)
		(drill 0.254)
		(layers "F.Cu" "B.Cu")
		(net "P3E_CPU0_PE2_SS_RXN<12>")
	)
	(segment
		(start 121.568972 7.981188)
		(end 121.56821 7.980426)
		(width 0.127)
		(layer "B.Cu")
		(net "P3E_CPU0_PE2_SS_RXN<12>")
	)
	(segment
		(start 121.599198 6.925818)
		(end 121.599706 6.938772)
		(width 0.127)
		(layer "B.Cu")
		(net "P3E_CPU0_PE2_SS_RXN<12>")
	)
	(segment
		(start 121.570242 7.935722)
		(end 121.57075 7.333234)
		(width 0.127)
		(layer "B.Cu")
		(net "P3E_CPU0_PE2_SS_RXN<12>")
	)
	(segment
		(start 121.599706 6.938772)
		(end 121.599706 5.714746)
		(width 0.127)
		(layer "B.Cu")
		(net "P3E_CPU0_PE2_SS_RXN<12>")
	)
	(segment
		(start 121.712736 5.441442)
		(end 121.94794 5.206492)
		(width 0.127)
		(layer "B.Cu")
		(net "P3E_CPU0_PE2_SS_RXN<12>")
	)
	(segment
		(start 121.568972 7.98195)
		(end 121.568972 7.981188)
		(width 0.127)
		(layer "B.Cu")
		(net "P3E_CPU0_PE2_SS_RXN<12>")
	)
	(segment
		(start 121.57075 7.333234)
		(end 121.599198 6.925818)
		(width 0.127)
		(layer "B.Cu")
		(net "P3E_CPU0_PE2_SS_RXN<12>")
	)
	(segment
		(start 120.97512 12.615672)
		(end 120.97512 11.18108)
		(width 0.127)
		(layer "B.Cu")
		(net "P3E_CPU0_PE2_SS_RXN<12>")
	)
	(segment
		(start 120.72747 10.583164)
		(end 120.72747 10.16)
		(width 0.127)
		(layer "B.Cu")
		(net "P3E_CPU0_PE2_SS_RXN<12>")
	)
	(segment
		(start 121.56313 8.109204)
		(end 121.568972 7.98195)
		(width 0.127)
		(layer "B.Cu")
		(net "P3E_CPU0_PE2_SS_RXN<12>")
	)
	(segment
		(start 121.56821 7.980426)
		(end 121.570242 7.935722)
		(width 0.127)
		(layer "B.Cu")
		(net "P3E_CPU0_PE2_SS_RXN<12>")
	)
	(arc
		(start 120.904 9.144)
		(mid 121.118665 8.853198)
		(end 121.3612 8.5852)
		(width 0.127)
		(layer "B.Cu")
		(net "P3E_CPU0_PE2_SS_RXN<12>")
	)
	(arc
		(start 120.72747 10.16)
		(mid 120.771932 9.644389)
		(end 120.904 9.144)
		(width 0.127)
		(layer "B.Cu")
		(net "P3E_CPU0_PE2_SS_RXN<12>")
	)
	(arc
		(start 121.599706 5.714746)
		(mid 121.629031 5.566849)
		(end 121.712736 5.441442)
		(width 0.127)
		(layer "B.Cu")
		(net "P3E_CPU0_PE2_SS_RXN<12>")
	)
	(arc
		(start 120.97512 11.18108)
		(mid 120.942909 11.019142)
		(end 120.851168 10.881868)
		(width 0.127)
		(layer "B.Cu")
		(net "P3E_CPU0_PE2_SS_RXN<12>")
	)
	(arc
		(start 121.3612 8.5852)
		(mid 121.504911 8.365336)
		(end 121.56313 8.109204)
		(width 0.127)
		(layer "B.Cu")
		(net "P3E_CPU0_PE2_SS_RXN<12>")
	)
	(arc
		(start 120.851168 10.881868)
		(mid 120.759596 10.744821)
		(end 120.72747 10.583164)
		(width 0.127)
		(layer "B.Cu")
		(net "P3E_CPU0_PE2_SS_RXN<12>")
	)
	(segment
		(start 114.599466 -4.144518)
		(end 110.401354 -4.884674)
		(width 0.127)
		(layer "In2.Cu")
		(net "P3E_CPU0_PE2_SS_RXN<12>")
	)
	(segment
		(start 102.79888 -24.276812)
		(end 102.837996 -24.50338)
		(width 0.127)
		(layer "In2.Cu")
		(net "P3E_CPU0_PE2_SS_RXN<12>")
	)
	(segment
		(start 121.602754 4.747006)
		(end 121.602754 4.651756)
		(width 0.127)
		(layer "In2.Cu")
		(net "P3E_CPU0_PE2_SS_RXN<12>")
	)
	(segment
		(start 101.992684 -25.70353)
		(end 101.766116 -25.7429)
		(width 0.127)
		(layer "In2.Cu")
		(net "P3E_CPU0_PE2_SS_RXN<12>")
	)
	(segment
		(start 101.54666 -26.054304)
		(end 101.3714 -26.8478)
		(width 0.127)
		(layer "In2.Cu")
		(net "P3E_CPU0_PE2_SS_RXN<12>")
	)
	(segment
		(start 109.58576 -7.96798)
		(end 109.693964 -8.076184)
		(width 0.127)
		(layer "In2.Cu")
		(net "P3E_CPU0_PE2_SS_RXN<12>")
	)
	(segment
		(start 102.17277 -25.165558)
		(end 102.21214 -25.392126)
		(width 0.127)
		(layer "In2.Cu")
		(net "P3E_CPU0_PE2_SS_RXN<12>")
	)
	(segment
		(start 102.21214 -25.392126)
		(end 101.992684 -25.70353)
		(width 0.127)
		(layer "In2.Cu")
		(net "P3E_CPU0_PE2_SS_RXN<12>")
	)
	(segment
		(start 109.0041 -15.4686)
		(end 103.42499 -23.388066)
		(width 0.127)
		(layer "In2.Cu")
		(net "P3E_CPU0_PE2_SS_RXN<12>")
	)
	(segment
		(start 121.603008 4.547616)
		(end 121.602246 4.546854)
		(width 0.127)
		(layer "In2.Cu")
		(net "P3E_CPU0_PE2_SS_RXN<12>")
	)
	(segment
		(start 102.618794 -24.814784)
		(end 102.392226 -24.854154)
		(width 0.127)
		(layer "In2.Cu")
		(net "P3E_CPU0_PE2_SS_RXN<12>")
	)
	(segment
		(start 103.018336 -23.965408)
		(end 102.79888 -24.276812)
		(width 0.127)
		(layer "In2.Cu")
		(net "P3E_CPU0_PE2_SS_RXN<12>")
	)
	(segment
		(start 101.766116 -25.7429)
		(end 101.54666 -26.054304)
		(width 0.127)
		(layer "In2.Cu")
		(net "P3E_CPU0_PE2_SS_RXN<12>")
	)
	(segment
		(start 120.153938 1.210818)
		(end 118.241318 -1.520698)
		(width 0.127)
		(layer "In2.Cu")
		(net "P3E_CPU0_PE2_SS_RXN<12>")
	)
	(segment
		(start 100.53066 -32.882586)
		(end 100.530914 -32.882586)
		(width 0.127)
		(layer "In2.Cu")
		(net "P3E_CPU0_PE2_SS_RXN<12>")
	)
	(segment
		(start 102.837996 -24.50338)
		(end 102.618794 -24.814784)
		(width 0.127)
		(layer "In2.Cu")
		(net "P3E_CPU0_PE2_SS_RXN<12>")
	)
	(segment
		(start 121.602246 4.546854)
		(end 121.602246 4.546092)
		(width 0.127)
		(layer "In2.Cu")
		(net "P3E_CPU0_PE2_SS_RXN<12>")
	)
	(segment
		(start 109.891576 -12.625324)
		(end 109.66958 -12.84732)
		(width 0.127)
		(layer "In2.Cu")
		(net "P3E_CPU0_PE2_SS_RXN<12>")
	)
	(segment
		(start 109.714792 -5.365496)
		(end 109.482636 -5.69722)
		(width 0.127)
		(layer "In2.Cu")
		(net "P3E_CPU0_PE2_SS_RXN<12>")
	)
	(segment
		(start 121.602246 4.546092)
		(end 121.474484 3.096768)
		(width 0.127)
		(layer "In2.Cu")
		(net "P3E_CPU0_PE2_SS_RXN<12>")
	)
	(segment
		(start 102.392226 -24.854154)
		(end 102.17277 -25.165558)
		(width 0.127)
		(layer "In2.Cu")
		(net "P3E_CPU0_PE2_SS_RXN<12>")
	)
	(segment
		(start 109.22 -13.932662)
		(end 109.22 -14.351508)
		(width 0.127)
		(layer "In2.Cu")
		(net "P3E_CPU0_PE2_SS_RXN<12>")
	)
	(segment
		(start 100.701348 -32.82569)
		(end 101.080062 -32.069786)
		(width 0.127)
		(layer "In2.Cu")
		(net "P3E_CPU0_PE2_SS_RXN<12>")
	)
	(segment
		(start 110.401354 -4.884674)
		(end 109.714792 -5.365496)
		(width 0.127)
		(layer "In2.Cu")
		(net "P3E_CPU0_PE2_SS_RXN<12>")
	)
	(segment
		(start 103.244904 -23.926038)
		(end 103.018336 -23.965408)
		(width 0.127)
		(layer "In2.Cu")
		(net "P3E_CPU0_PE2_SS_RXN<12>")
	)
	(segment
		(start 101.141022 -27.889962)
		(end 101.02469 -28.157932)
		(width 0.127)
		(layer "In2.Cu")
		(net "P3E_CPU0_PE2_SS_RXN<12>")
	)
	(segment
		(start 118.241318 -1.520698)
		(end 117.93474 -1.806956)
		(width 0.127)
		(layer "In2.Cu")
		(net "P3E_CPU0_PE2_SS_RXN<12>")
	)
	(segment
		(start 110.20044 -9.29894)
		(end 110.20044 -11.87958)
		(width 0.127)
		(layer "In2.Cu")
		(net "P3E_CPU0_PE2_SS_RXN<12>")
	)
	(segment
		(start 121.602754 4.651756)
		(end 121.603008 4.547616)
		(width 0.127)
		(layer "In2.Cu")
		(net "P3E_CPU0_PE2_SS_RXN<12>")
	)
	(segment
		(start 117.93347 -1.808226)
		(end 117.93347 -1.80975)
		(width 0.127)
		(layer "In2.Cu")
		(net "P3E_CPU0_PE2_SS_RXN<12>")
	)
	(segment
		(start 103.464106 -23.614634)
		(end 103.244904 -23.926038)
		(width 0.127)
		(layer "In2.Cu")
		(net "P3E_CPU0_PE2_SS_RXN<12>")
	)
	(segment
		(start 109.482636 -5.69722)
		(end 109.2327 -7.115556)
		(width 0.127)
		(layer "In2.Cu")
		(net "P3E_CPU0_PE2_SS_RXN<12>")
	)
	(segment
		(start 103.42499 -23.388066)
		(end 103.464106 -23.614634)
		(width 0.127)
		(layer "In2.Cu")
		(net "P3E_CPU0_PE2_SS_RXN<12>")
	)
	(segment
		(start 100.416868 -32.82569)
		(end 100.53066 -32.882586)
		(width 0.127)
		(layer "In2.Cu")
		(net "P3E_CPU0_PE2_SS_RXN<12>")
	)
	(segment
		(start 121.474484 3.096768)
		(end 120.153938 1.210818)
		(width 0.127)
		(layer "In2.Cu")
		(net "P3E_CPU0_PE2_SS_RXN<12>")
	)
	(segment
		(start 101.3714 -26.8478)
		(end 101.141022 -27.889962)
		(width 0.127)
		(layer "In2.Cu")
		(net "P3E_CPU0_PE2_SS_RXN<12>")
	)
	(segment
		(start 109.22 -14.351508)
		(end 109.0041 -15.4686)
		(width 0.127)
		(layer "In2.Cu")
		(net "P3E_CPU0_PE2_SS_RXN<12>")
	)
	(segment
		(start 117.93347 -1.80975)
		(end 117.932962 -1.810258)
		(width 0.127)
		(layer "In2.Cu")
		(net "P3E_CPU0_PE2_SS_RXN<12>")
	)
	(segment
		(start 117.932962 -1.810258)
		(end 114.599466 -4.144518)
		(width 0.127)
		(layer "In2.Cu")
		(net "P3E_CPU0_PE2_SS_RXN<12>")
	)
	(segment
		(start 117.93474 -1.806956)
		(end 117.93347 -1.808226)
		(width 0.127)
		(layer "In2.Cu")
		(net "P3E_CPU0_PE2_SS_RXN<12>")
	)
	(arc
		(start 121.94794 5.206492)
		(mid 121.702665 5.03135)
		(end 121.602754 4.747006)
		(width 0.127)
		(layer "In2.Cu")
		(net "P3E_CPU0_PE2_SS_RXN<12>")
	)
	(arc
		(start 109.66958 -12.84732)
		(mid 109.336854 -13.345279)
		(end 109.22 -13.932662)
		(width 0.127)
		(layer "In2.Cu")
		(net "P3E_CPU0_PE2_SS_RXN<12>")
	)
	(arc
		(start 100.00488 -31.4325)
		(mid 100.151159 -31.863665)
		(end 100.15474 -32.31896)
		(width 0.127)
		(layer "In2.Cu")
		(net "P3E_CPU0_PE2_SS_RXN<12>")
	)
	(arc
		(start 100.15474 -32.31896)
		(mid 100.203315 -32.615005)
		(end 100.416868 -32.82569)
		(width 0.127)
		(layer "In2.Cu")
		(net "P3E_CPU0_PE2_SS_RXN<12>")
	)
	(arc
		(start 110.20044 -11.87958)
		(mid 110.120163 -12.283161)
		(end 109.891576 -12.625324)
		(width 0.127)
		(layer "In2.Cu")
		(net "P3E_CPU0_PE2_SS_RXN<12>")
	)
	(arc
		(start 99.888294 -31.105602)
		(mid 99.934794 -31.273257)
		(end 100.00488 -31.4325)
		(width 0.127)
		(layer "In2.Cu")
		(net "P3E_CPU0_PE2_SS_RXN<12>")
	)
	(arc
		(start 109.693964 -8.076184)
		(mid 110.068816 -8.637189)
		(end 110.20044 -9.29894)
		(width 0.127)
		(layer "In2.Cu")
		(net "P3E_CPU0_PE2_SS_RXN<12>")
	)
	(arc
		(start 100.2792 -29.44622)
		(mid 100.181486 -29.922871)
		(end 99.9744 -30.36316)
		(width 0.127)
		(layer "In2.Cu")
		(net "P3E_CPU0_PE2_SS_RXN<12>")
	)
	(arc
		(start 100.530914 -32.882586)
		(mid 100.62797 -32.889527)
		(end 100.701348 -32.82569)
		(width 0.127)
		(layer "In2.Cu")
		(net "P3E_CPU0_PE2_SS_RXN<12>")
	)
	(arc
		(start 101.02469 -28.157932)
		(mid 100.761197 -28.655255)
		(end 100.42398 -29.10586)
		(width 0.127)
		(layer "In2.Cu")
		(net "P3E_CPU0_PE2_SS_RXN<12>")
	)
	(arc
		(start 99.871276 -30.739842)
		(mid 99.865871 -30.923369)
		(end 99.888294 -31.105602)
		(width 0.127)
		(layer "In2.Cu")
		(net "P3E_CPU0_PE2_SS_RXN<12>")
	)
	(arc
		(start 99.9744 -30.36316)
		(mid 99.907527 -30.547309)
		(end 99.871276 -30.739842)
		(width 0.127)
		(layer "In2.Cu")
		(net "P3E_CPU0_PE2_SS_RXN<12>")
	)
	(arc
		(start 100.42398 -29.10586)
		(mid 100.32424 -29.264407)
		(end 100.2792 -29.44622)
		(width 0.127)
		(layer "In2.Cu")
		(net "P3E_CPU0_PE2_SS_RXN<12>")
	)
	(arc
		(start 109.2327 -7.115556)
		(mid 109.324462 -7.576875)
		(end 109.58576 -7.96798)
		(width 0.127)
		(layer "In2.Cu")
		(net "P3E_CPU0_PE2_SS_RXN<12>")
	)
	(via
		(at 119.35714 5.206492)
		(size 0.508)
		(drill 0.254)
		(layers "F.Cu" "B.Cu")
		(net "P3E_CPU0_PE2_SS_RXN<11>")
	)
	(segment
		(start 118.575074 12.615672)
		(end 118.575074 11.206226)
		(width 0.127)
		(layer "B.Cu")
		(net "P3E_CPU0_PE2_SS_RXN<11>")
	)
	(segment
		(start 118.327424 10.608818)
		(end 118.327424 9.652)
		(width 0.127)
		(layer "B.Cu")
		(net "P3E_CPU0_PE2_SS_RXN<11>")
	)
	(segment
		(start 119.00154 6.978142)
		(end 119.00154 5.816092)
		(width 0.127)
		(layer "B.Cu")
		(net "P3E_CPU0_PE2_SS_RXN<11>")
	)
	(segment
		(start 118.972838 7.68985)
		(end 119.00154 6.978142)
		(width 0.127)
		(layer "B.Cu")
		(net "P3E_CPU0_PE2_SS_RXN<11>")
	)
	(segment
		(start 118.966234 7.817104)
		(end 118.972838 7.690104)
		(width 0.127)
		(layer "B.Cu")
		(net "P3E_CPU0_PE2_SS_RXN<11>")
	)
	(segment
		(start 118.45163 10.907776)
		(end 118.451376 10.907522)
		(width 0.127)
		(layer "B.Cu")
		(net "P3E_CPU0_PE2_SS_RXN<11>")
	)
	(segment
		(start 118.972838 7.690104)
		(end 118.973092 7.68985)
		(width 0.127)
		(layer "B.Cu")
		(net "P3E_CPU0_PE2_SS_RXN<11>")
	)
	(segment
		(start 118.973092 7.68985)
		(end 118.972838 7.68985)
		(width 0.127)
		(layer "B.Cu")
		(net "P3E_CPU0_PE2_SS_RXN<11>")
	)
	(arc
		(start 118.451376 10.907522)
		(mid 118.359721 10.77049)
		(end 118.327424 10.608818)
		(width 0.127)
		(layer "B.Cu")
		(net "P3E_CPU0_PE2_SS_RXN<11>")
	)
	(arc
		(start 119.00154 5.816092)
		(mid 119.096941 5.463229)
		(end 119.35714 5.206492)
		(width 0.127)
		(layer "B.Cu")
		(net "P3E_CPU0_PE2_SS_RXN<11>")
	)
	(arc
		(start 118.327424 9.652)
		(mid 118.398016 9.152725)
		(end 118.6434 8.7122)
		(width 0.127)
		(layer "B.Cu")
		(net "P3E_CPU0_PE2_SS_RXN<11>")
	)
	(arc
		(start 118.6434 8.7122)
		(mid 118.883053 8.29287)
		(end 118.966234 7.817104)
		(width 0.127)
		(layer "B.Cu")
		(net "P3E_CPU0_PE2_SS_RXN<11>")
	)
	(arc
		(start 118.575074 11.206226)
		(mid 118.542989 11.044746)
		(end 118.45163 10.907776)
		(width 0.127)
		(layer "B.Cu")
		(net "P3E_CPU0_PE2_SS_RXN<11>")
	)
	(segment
		(start 105.98404 -4.201668)
		(end 105.586022 -4.77012)
		(width 0.127)
		(layer "In2.Cu")
		(net "P3E_CPU0_PE2_SS_RXN<11>")
	)
	(segment
		(start 98.672142 -24.30018)
		(end 98.746056 -24.517858)
		(width 0.127)
		(layer "In2.Cu")
		(net "P3E_CPU0_PE2_SS_RXN<11>")
	)
	(segment
		(start 104.77246 -15.512288)
		(end 99.7585 -22.098)
		(width 0.127)
		(layer "In2.Cu")
		(net "P3E_CPU0_PE2_SS_RXN<11>")
	)
	(segment
		(start 106.19994 -9.29894)
		(end 106.19994 -11.87958)
		(width 0.127)
		(layer "In2.Cu")
		(net "P3E_CPU0_PE2_SS_RXN<11>")
	)
	(segment
		(start 104.980232 -15.146274)
		(end 104.97947 -15.147544)
		(width 0.127)
		(layer "In2.Cu")
		(net "P3E_CPU0_PE2_SS_RXN<11>")
	)
	(segment
		(start 97.710244 -26.250138)
		(end 97.783904 -26.467816)
		(width 0.127)
		(layer "In2.Cu")
		(net "P3E_CPU0_PE2_SS_RXN<11>")
	)
	(segment
		(start 96.417638 -32.82569)
		(end 96.53143 -32.882586)
		(width 0.127)
		(layer "In2.Cu")
		(net "P3E_CPU0_PE2_SS_RXN<11>")
	)
	(segment
		(start 105.144316 -14.754606)
		(end 105.142792 -14.757908)
		(width 0.127)
		(layer "In2.Cu")
		(net "P3E_CPU0_PE2_SS_RXN<11>")
	)
	(segment
		(start 99.7585 -22.098)
		(end 98.672142 -24.30018)
		(width 0.127)
		(layer "In2.Cu")
		(net "P3E_CPU0_PE2_SS_RXN<11>")
	)
	(segment
		(start 104.97947 -15.147544)
		(end 104.77246 -15.512288)
		(width 0.127)
		(layer "In2.Cu")
		(net "P3E_CPU0_PE2_SS_RXN<11>")
	)
	(segment
		(start 119.010684 4.704588)
		(end 118.998492 4.412234)
		(width 0.127)
		(layer "In2.Cu")
		(net "P3E_CPU0_PE2_SS_RXN<11>")
	)
	(segment
		(start 98.096324 -25.834594)
		(end 97.878646 -25.908254)
		(width 0.127)
		(layer "In2.Cu")
		(net "P3E_CPU0_PE2_SS_RXN<11>")
	)
	(segment
		(start 97.783904 -26.467816)
		(end 97.615502 -26.809446)
		(width 0.127)
		(layer "In2.Cu")
		(net "P3E_CPU0_PE2_SS_RXN<11>")
	)
	(segment
		(start 97.229168 -27.22499)
		(end 97.2312 -27.2288)
		(width 0.127)
		(layer "In2.Cu")
		(net "P3E_CPU0_PE2_SS_RXN<11>")
	)
	(segment
		(start 105.142792 -14.757908)
		(end 104.98201 -15.145512)
		(width 0.127)
		(layer "In2.Cu")
		(net "P3E_CPU0_PE2_SS_RXN<11>")
	)
	(segment
		(start 105.586022 -4.77012)
		(end 105.23347 -6.7691)
		(width 0.127)
		(layer "In2.Cu")
		(net "P3E_CPU0_PE2_SS_RXN<11>")
	)
	(segment
		(start 118.755922 3.035554)
		(end 117.326156 0.994664)
		(width 0.127)
		(layer "In2.Cu")
		(net "P3E_CPU0_PE2_SS_RXN<11>")
	)
	(segment
		(start 98.26498 -25.49271)
		(end 98.096324 -25.834594)
		(width 0.127)
		(layer "In2.Cu")
		(net "P3E_CPU0_PE2_SS_RXN<11>")
	)
	(segment
		(start 107.15371 -3.382772)
		(end 105.98404 -4.201668)
		(width 0.127)
		(layer "In2.Cu")
		(net "P3E_CPU0_PE2_SS_RXN<11>")
	)
	(segment
		(start 98.746056 -24.517858)
		(end 98.5774 -24.859488)
		(width 0.127)
		(layer "In2.Cu")
		(net "P3E_CPU0_PE2_SS_RXN<11>")
	)
	(segment
		(start 98.191066 -25.275032)
		(end 98.26498 -25.49271)
		(width 0.127)
		(layer "In2.Cu")
		(net "P3E_CPU0_PE2_SS_RXN<11>")
	)
	(segment
		(start 98.5774 -24.859488)
		(end 98.359722 -24.933402)
		(width 0.127)
		(layer "In2.Cu")
		(net "P3E_CPU0_PE2_SS_RXN<11>")
	)
	(segment
		(start 105.58653 -7.96798)
		(end 105.693464 -8.076184)
		(width 0.127)
		(layer "In2.Cu")
		(net "P3E_CPU0_PE2_SS_RXN<11>")
	)
	(segment
		(start 105.2195 -14.351508)
		(end 105.148888 -14.752574)
		(width 0.127)
		(layer "In2.Cu")
		(net "P3E_CPU0_PE2_SS_RXN<11>")
	)
	(segment
		(start 105.23347 -6.7691)
		(end 105.23347 -7.115556)
		(width 0.127)
		(layer "In2.Cu")
		(net "P3E_CPU0_PE2_SS_RXN<11>")
	)
	(segment
		(start 104.98201 -15.145512)
		(end 104.980232 -15.146274)
		(width 0.127)
		(layer "In2.Cu")
		(net "P3E_CPU0_PE2_SS_RXN<11>")
	)
	(segment
		(start 97.878646 -25.908254)
		(end 97.710244 -26.250138)
		(width 0.127)
		(layer "In2.Cu")
		(net "P3E_CPU0_PE2_SS_RXN<11>")
	)
	(segment
		(start 96.53143 -32.882586)
		(end 96.531684 -32.882586)
		(width 0.127)
		(layer "In2.Cu")
		(net "P3E_CPU0_PE2_SS_RXN<11>")
	)
	(segment
		(start 98.359722 -24.933402)
		(end 98.191066 -25.275032)
		(width 0.127)
		(layer "In2.Cu")
		(net "P3E_CPU0_PE2_SS_RXN<11>")
	)
	(segment
		(start 105.2195 -13.932662)
		(end 105.2195 -14.351508)
		(width 0.127)
		(layer "In2.Cu")
		(net "P3E_CPU0_PE2_SS_RXN<11>")
	)
	(segment
		(start 112.393984 -2.458974)
		(end 107.15371 -3.382772)
		(width 0.127)
		(layer "In2.Cu")
		(net "P3E_CPU0_PE2_SS_RXN<11>")
	)
	(segment
		(start 105.148888 -14.752574)
		(end 105.144316 -14.754606)
		(width 0.127)
		(layer "In2.Cu")
		(net "P3E_CPU0_PE2_SS_RXN<11>")
	)
	(segment
		(start 118.998492 4.412234)
		(end 118.755922 3.035554)
		(width 0.127)
		(layer "In2.Cu")
		(net "P3E_CPU0_PE2_SS_RXN<11>")
	)
	(segment
		(start 97.397824 -26.88336)
		(end 97.229168 -27.22499)
		(width 0.127)
		(layer "In2.Cu")
		(net "P3E_CPU0_PE2_SS_RXN<11>")
	)
	(segment
		(start 105.891076 -12.625324)
		(end 105.66908 -12.84732)
		(width 0.127)
		(layer "In2.Cu")
		(net "P3E_CPU0_PE2_SS_RXN<11>")
	)
	(segment
		(start 97.615502 -26.809446)
		(end 97.397824 -26.88336)
		(width 0.127)
		(layer "In2.Cu")
		(net "P3E_CPU0_PE2_SS_RXN<11>")
	)
	(segment
		(start 96.702118 -32.82569)
		(end 97.079562 -32.069786)
		(width 0.127)
		(layer "In2.Cu")
		(net "P3E_CPU0_PE2_SS_RXN<11>")
	)
	(segment
		(start 117.326156 0.994664)
		(end 112.393984 -2.458974)
		(width 0.127)
		(layer "In2.Cu")
		(net "P3E_CPU0_PE2_SS_RXN<11>")
	)
	(arc
		(start 119.0117 4.746498)
		(mid 119.011376 4.725539)
		(end 119.010684 4.704588)
		(width 0.127)
		(layer "In2.Cu")
		(net "P3E_CPU0_PE2_SS_RXN<11>")
	)
	(arc
		(start 97.02546 -28.157932)
		(mid 96.761967 -28.655255)
		(end 96.42475 -29.10586)
		(width 0.127)
		(layer "In2.Cu")
		(net "P3E_CPU0_PE2_SS_RXN<11>")
	)
	(arc
		(start 105.66908 -12.84732)
		(mid 105.336354 -13.345279)
		(end 105.2195 -13.932662)
		(width 0.127)
		(layer "In2.Cu")
		(net "P3E_CPU0_PE2_SS_RXN<11>")
	)
	(arc
		(start 95.889064 -31.105602)
		(mid 95.935564 -31.273257)
		(end 96.00565 -31.4325)
		(width 0.127)
		(layer "In2.Cu")
		(net "P3E_CPU0_PE2_SS_RXN<11>")
	)
	(arc
		(start 95.97517 -30.36316)
		(mid 95.908297 -30.547309)
		(end 95.872046 -30.739842)
		(width 0.127)
		(layer "In2.Cu")
		(net "P3E_CPU0_PE2_SS_RXN<11>")
	)
	(arc
		(start 96.531684 -32.882586)
		(mid 96.62874 -32.889527)
		(end 96.702118 -32.82569)
		(width 0.127)
		(layer "In2.Cu")
		(net "P3E_CPU0_PE2_SS_RXN<11>")
	)
	(arc
		(start 106.19994 -11.87958)
		(mid 106.119663 -12.283161)
		(end 105.891076 -12.625324)
		(width 0.127)
		(layer "In2.Cu")
		(net "P3E_CPU0_PE2_SS_RXN<11>")
	)
	(arc
		(start 97.2312 -27.2288)
		(mid 97.172995 -27.703257)
		(end 97.02546 -28.157932)
		(width 0.127)
		(layer "In2.Cu")
		(net "P3E_CPU0_PE2_SS_RXN<11>")
	)
	(arc
		(start 119.35714 5.206492)
		(mid 119.111616 5.031168)
		(end 119.0117 4.746498)
		(width 0.127)
		(layer "In2.Cu")
		(net "P3E_CPU0_PE2_SS_RXN<11>")
	)
	(arc
		(start 105.23347 -7.115556)
		(mid 105.325232 -7.576875)
		(end 105.58653 -7.96798)
		(width 0.127)
		(layer "In2.Cu")
		(net "P3E_CPU0_PE2_SS_RXN<11>")
	)
	(arc
		(start 105.693464 -8.076184)
		(mid 106.068316 -8.637189)
		(end 106.19994 -9.29894)
		(width 0.127)
		(layer "In2.Cu")
		(net "P3E_CPU0_PE2_SS_RXN<11>")
	)
	(arc
		(start 96.15551 -32.31896)
		(mid 96.204085 -32.615005)
		(end 96.417638 -32.82569)
		(width 0.127)
		(layer "In2.Cu")
		(net "P3E_CPU0_PE2_SS_RXN<11>")
	)
	(arc
		(start 95.872046 -30.739842)
		(mid 95.866641 -30.923369)
		(end 95.889064 -31.105602)
		(width 0.127)
		(layer "In2.Cu")
		(net "P3E_CPU0_PE2_SS_RXN<11>")
	)
	(arc
		(start 96.00565 -31.4325)
		(mid 96.151929 -31.863665)
		(end 96.15551 -32.31896)
		(width 0.127)
		(layer "In2.Cu")
		(net "P3E_CPU0_PE2_SS_RXN<11>")
	)
	(arc
		(start 96.42475 -29.10586)
		(mid 96.32501 -29.264407)
		(end 96.27997 -29.44622)
		(width 0.127)
		(layer "In2.Cu")
		(net "P3E_CPU0_PE2_SS_RXN<11>")
	)
	(arc
		(start 96.27997 -29.44622)
		(mid 96.182256 -29.922871)
		(end 95.97517 -30.36316)
		(width 0.127)
		(layer "In2.Cu")
		(net "P3E_CPU0_PE2_SS_RXN<11>")
	)
	(via
		(at 116.76634 5.206492)
		(size 0.508)
		(drill 0.254)
		(layers "F.Cu" "B.Cu")
		(net "P3E_CPU0_PE2_SS_RXN<10>")
	)
	(segment
		(start 115.927632 10.672826)
		(end 115.927632 9.779)
		(width 0.127)
		(layer "B.Cu")
		(net "P3E_CPU0_PE2_SS_RXN<10>")
	)
	(segment
		(start 116.41074 6.978904)
		(end 116.41074 5.816092)
		(width 0.127)
		(layer "B.Cu")
		(net "P3E_CPU0_PE2_SS_RXN<10>")
	)
	(segment
		(start 116.362734 8.009636)
		(end 116.41074 6.978904)
		(width 0.127)
		(layer "B.Cu")
		(net "P3E_CPU0_PE2_SS_RXN<10>")
	)
	(segment
		(start 116.377974 8.380222)
		(end 116.361972 8.01116)
		(width 0.127)
		(layer "B.Cu")
		(net "P3E_CPU0_PE2_SS_RXN<10>")
	)
	(segment
		(start 116.175028 12.615672)
		(end 116.175028 11.270234)
		(width 0.127)
		(layer "B.Cu")
		(net "P3E_CPU0_PE2_SS_RXN<10>")
	)
	(segment
		(start 116.361972 8.01116)
		(end 116.361972 8.010398)
		(width 0.127)
		(layer "B.Cu")
		(net "P3E_CPU0_PE2_SS_RXN<10>")
	)
	(segment
		(start 116.361972 8.010398)
		(end 116.362734 8.009636)
		(width 0.127)
		(layer "B.Cu")
		(net "P3E_CPU0_PE2_SS_RXN<10>")
	)
	(arc
		(start 116.41074 5.816092)
		(mid 116.506141 5.463229)
		(end 116.76634 5.206492)
		(width 0.127)
		(layer "B.Cu")
		(net "P3E_CPU0_PE2_SS_RXN<10>")
	)
	(arc
		(start 116.05133 10.97153)
		(mid 115.959758 10.834483)
		(end 115.927632 10.672826)
		(width 0.127)
		(layer "B.Cu")
		(net "P3E_CPU0_PE2_SS_RXN<10>")
	)
	(arc
		(start 116.1542 9.0424)
		(mid 116.327814 8.732163)
		(end 116.377974 8.380222)
		(width 0.127)
		(layer "B.Cu")
		(net "P3E_CPU0_PE2_SS_RXN<10>")
	)
	(arc
		(start 116.175028 11.270234)
		(mid 116.142875 11.108588)
		(end 116.05133 10.97153)
		(width 0.127)
		(layer "B.Cu")
		(net "P3E_CPU0_PE2_SS_RXN<10>")
	)
	(arc
		(start 115.927632 9.779)
		(mid 115.985555 9.393672)
		(end 116.1542 9.0424)
		(width 0.127)
		(layer "B.Cu")
		(net "P3E_CPU0_PE2_SS_RXN<10>")
	)
	(segment
		(start 93.854778 -26.233374)
		(end 93.68409 -26.574242)
		(width 0.127)
		(layer "In2.Cu")
		(net "P3E_CPU0_PE2_SS_RXN<10>")
	)
	(segment
		(start 102.19944 -9.29894)
		(end 102.19944 -11.87958)
		(width 0.127)
		(layer "In2.Cu")
		(net "P3E_CPU0_PE2_SS_RXN<10>")
	)
	(segment
		(start 111.805974 -0.559816)
		(end 104.898444 -1.775968)
		(width 0.127)
		(layer "In2.Cu")
		(net "P3E_CPU0_PE2_SS_RXN<10>")
	)
	(segment
		(start 116.4209 4.746498)
		(end 116.411756 4.454144)
		(width 0.127)
		(layer "In2.Cu")
		(net "P3E_CPU0_PE2_SS_RXN<10>")
	)
	(segment
		(start 101.58603 -7.96798)
		(end 101.692964 -8.076184)
		(width 0.127)
		(layer "In2.Cu")
		(net "P3E_CPU0_PE2_SS_RXN<10>")
	)
	(segment
		(start 94.439232 -24.702516)
		(end 94.268544 -25.04313)
		(width 0.127)
		(layer "In2.Cu")
		(net "P3E_CPU0_PE2_SS_RXN<10>")
	)
	(segment
		(start 104.75341 -1.873504)
		(end 103.777542 -2.849372)
		(width 0.127)
		(layer "In2.Cu")
		(net "P3E_CPU0_PE2_SS_RXN<10>")
	)
	(segment
		(start 101.219 -13.932662)
		(end 101.219 -14.221714)
		(width 0.127)
		(layer "In2.Cu")
		(net "P3E_CPU0_PE2_SS_RXN<10>")
	)
	(segment
		(start 94.657164 -24.629872)
		(end 94.439232 -24.702516)
		(width 0.127)
		(layer "In2.Cu")
		(net "P3E_CPU0_PE2_SS_RXN<10>")
	)
	(segment
		(start 94.341188 -25.261316)
		(end 94.170754 -25.60193)
		(width 0.127)
		(layer "In2.Cu")
		(net "P3E_CPU0_PE2_SS_RXN<10>")
	)
	(segment
		(start 93.141292 -27.889962)
		(end 93.02496 -28.157932)
		(width 0.127)
		(layer "In2.Cu")
		(net "P3E_CPU0_PE2_SS_RXN<10>")
	)
	(segment
		(start 94.827852 -24.289258)
		(end 94.657164 -24.629872)
		(width 0.127)
		(layer "In2.Cu")
		(net "P3E_CPU0_PE2_SS_RXN<10>")
	)
	(segment
		(start 104.898444 -1.775968)
		(end 104.75341 -1.873504)
		(width 0.127)
		(layer "In2.Cu")
		(net "P3E_CPU0_PE2_SS_RXN<10>")
	)
	(segment
		(start 93.465904 -26.646886)
		(end 93.29547 -26.9875)
		(width 0.127)
		(layer "In2.Cu")
		(net "P3E_CPU0_PE2_SS_RXN<10>")
	)
	(segment
		(start 92.701618 -32.82569)
		(end 93.080332 -32.069786)
		(width 0.127)
		(layer "In2.Cu")
		(net "P3E_CPU0_PE2_SS_RXN<10>")
	)
	(segment
		(start 92.417138 -32.82569)
		(end 92.53093 -32.882586)
		(width 0.127)
		(layer "In2.Cu")
		(net "P3E_CPU0_PE2_SS_RXN<10>")
	)
	(segment
		(start 101.8286 -5.7912)
		(end 101.23297 -6.8834)
		(width 0.127)
		(layer "In2.Cu")
		(net "P3E_CPU0_PE2_SS_RXN<10>")
	)
	(segment
		(start 103.7717 -2.8575)
		(end 101.8286 -5.7912)
		(width 0.127)
		(layer "In2.Cu")
		(net "P3E_CPU0_PE2_SS_RXN<10>")
	)
	(segment
		(start 95.404686 -22.773386)
		(end 94.755208 -24.071072)
		(width 0.127)
		(layer "In2.Cu")
		(net "P3E_CPU0_PE2_SS_RXN<10>")
	)
	(segment
		(start 92.53093 -32.882586)
		(end 92.531184 -32.882586)
		(width 0.127)
		(layer "In2.Cu")
		(net "P3E_CPU0_PE2_SS_RXN<10>")
	)
	(segment
		(start 116.411756 4.454144)
		(end 116.221764 3.376676)
		(width 0.127)
		(layer "In2.Cu")
		(net "P3E_CPU0_PE2_SS_RXN<10>")
	)
	(segment
		(start 103.777542 -2.849372)
		(end 103.7717 -2.8575)
		(width 0.127)
		(layer "In2.Cu")
		(net "P3E_CPU0_PE2_SS_RXN<10>")
	)
	(segment
		(start 94.755208 -24.071072)
		(end 94.827852 -24.289258)
		(width 0.127)
		(layer "In2.Cu")
		(net "P3E_CPU0_PE2_SS_RXN<10>")
	)
	(segment
		(start 116.221764 3.376676)
		(end 115.062 1.720088)
		(width 0.127)
		(layer "In2.Cu")
		(net "P3E_CPU0_PE2_SS_RXN<10>")
	)
	(segment
		(start 93.231208 -27.362658)
		(end 93.141292 -27.889962)
		(width 0.127)
		(layer "In2.Cu")
		(net "P3E_CPU0_PE2_SS_RXN<10>")
	)
	(segment
		(start 101.152452 -14.565122)
		(end 95.404686 -22.773386)
		(width 0.127)
		(layer "In2.Cu")
		(net "P3E_CPU0_PE2_SS_RXN<10>")
	)
	(segment
		(start 93.952568 -25.674574)
		(end 93.782134 -26.015442)
		(width 0.127)
		(layer "In2.Cu")
		(net "P3E_CPU0_PE2_SS_RXN<10>")
	)
	(segment
		(start 93.68409 -26.574242)
		(end 93.465904 -26.646886)
		(width 0.127)
		(layer "In2.Cu")
		(net "P3E_CPU0_PE2_SS_RXN<10>")
	)
	(segment
		(start 93.29547 -26.9875)
		(end 93.231208 -27.362658)
		(width 0.127)
		(layer "In2.Cu")
		(net "P3E_CPU0_PE2_SS_RXN<10>")
	)
	(segment
		(start 94.268544 -25.04313)
		(end 94.341188 -25.261316)
		(width 0.127)
		(layer "In2.Cu")
		(net "P3E_CPU0_PE2_SS_RXN<10>")
	)
	(segment
		(start 101.219 -14.221714)
		(end 101.152452 -14.565122)
		(width 0.127)
		(layer "In2.Cu")
		(net "P3E_CPU0_PE2_SS_RXN<10>")
	)
	(segment
		(start 115.062 1.720088)
		(end 111.805974 -0.559816)
		(width 0.127)
		(layer "In2.Cu")
		(net "P3E_CPU0_PE2_SS_RXN<10>")
	)
	(segment
		(start 94.170754 -25.60193)
		(end 93.952568 -25.674574)
		(width 0.127)
		(layer "In2.Cu")
		(net "P3E_CPU0_PE2_SS_RXN<10>")
	)
	(segment
		(start 101.890576 -12.625324)
		(end 101.66858 -12.84732)
		(width 0.127)
		(layer "In2.Cu")
		(net "P3E_CPU0_PE2_SS_RXN<10>")
	)
	(segment
		(start 101.23297 -6.8834)
		(end 101.23297 -7.115556)
		(width 0.127)
		(layer "In2.Cu")
		(net "P3E_CPU0_PE2_SS_RXN<10>")
	)
	(segment
		(start 93.782134 -26.015442)
		(end 93.854778 -26.233374)
		(width 0.127)
		(layer "In2.Cu")
		(net "P3E_CPU0_PE2_SS_RXN<10>")
	)
	(arc
		(start 93.02496 -28.157932)
		(mid 92.761467 -28.655255)
		(end 92.42425 -29.10586)
		(width 0.127)
		(layer "In2.Cu")
		(net "P3E_CPU0_PE2_SS_RXN<10>")
	)
	(arc
		(start 101.66858 -12.84732)
		(mid 101.335854 -13.345279)
		(end 101.219 -13.932662)
		(width 0.127)
		(layer "In2.Cu")
		(net "P3E_CPU0_PE2_SS_RXN<10>")
	)
	(arc
		(start 92.00515 -31.4325)
		(mid 92.151429 -31.863665)
		(end 92.15501 -32.31896)
		(width 0.127)
		(layer "In2.Cu")
		(net "P3E_CPU0_PE2_SS_RXN<10>")
	)
	(arc
		(start 92.15501 -32.31896)
		(mid 92.203585 -32.615005)
		(end 92.417138 -32.82569)
		(width 0.127)
		(layer "In2.Cu")
		(net "P3E_CPU0_PE2_SS_RXN<10>")
	)
	(arc
		(start 92.531184 -32.882586)
		(mid 92.62824 -32.889527)
		(end 92.701618 -32.82569)
		(width 0.127)
		(layer "In2.Cu")
		(net "P3E_CPU0_PE2_SS_RXN<10>")
	)
	(arc
		(start 91.97467 -30.36316)
		(mid 91.907797 -30.547309)
		(end 91.871546 -30.739842)
		(width 0.127)
		(layer "In2.Cu")
		(net "P3E_CPU0_PE2_SS_RXN<10>")
	)
	(arc
		(start 91.888564 -31.105602)
		(mid 91.935064 -31.273257)
		(end 92.00515 -31.4325)
		(width 0.127)
		(layer "In2.Cu")
		(net "P3E_CPU0_PE2_SS_RXN<10>")
	)
	(arc
		(start 116.76634 5.206492)
		(mid 116.520816 5.031168)
		(end 116.4209 4.746498)
		(width 0.127)
		(layer "In2.Cu")
		(net "P3E_CPU0_PE2_SS_RXN<10>")
	)
	(arc
		(start 102.19944 -11.87958)
		(mid 102.119163 -12.283161)
		(end 101.890576 -12.625324)
		(width 0.127)
		(layer "In2.Cu")
		(net "P3E_CPU0_PE2_SS_RXN<10>")
	)
	(arc
		(start 92.42425 -29.10586)
		(mid 92.32451 -29.264407)
		(end 92.27947 -29.44622)
		(width 0.127)
		(layer "In2.Cu")
		(net "P3E_CPU0_PE2_SS_RXN<10>")
	)
	(arc
		(start 101.692964 -8.076184)
		(mid 102.067816 -8.637189)
		(end 102.19944 -9.29894)
		(width 0.127)
		(layer "In2.Cu")
		(net "P3E_CPU0_PE2_SS_RXN<10>")
	)
	(arc
		(start 101.23297 -7.115556)
		(mid 101.324732 -7.576875)
		(end 101.58603 -7.96798)
		(width 0.127)
		(layer "In2.Cu")
		(net "P3E_CPU0_PE2_SS_RXN<10>")
	)
	(arc
		(start 91.871546 -30.739842)
		(mid 91.866141 -30.923369)
		(end 91.888564 -31.105602)
		(width 0.127)
		(layer "In2.Cu")
		(net "P3E_CPU0_PE2_SS_RXN<10>")
	)
	(arc
		(start 92.27947 -29.44622)
		(mid 92.181756 -29.922871)
		(end 91.97467 -30.36316)
		(width 0.127)
		(layer "In2.Cu")
		(net "P3E_CPU0_PE2_SS_RXN<10>")
	)
	(via
		(at 82.238088 5.165852)
		(size 0.508)
		(drill 0.254)
		(layers "F.Cu" "B.Cu")
		(net "P3E_CPU0_PE2_SS_RXN<1>")
	)
	(segment
		(start 81.854294 7.656322)
		(end 81.906618 8.161274)
		(width 0.127)
		(layer "B.Cu")
		(net "P3E_CPU0_PE2_SS_RXN<1>")
	)
	(segment
		(start 81.797652 7.095998)
		(end 81.854294 7.656322)
		(width 0.127)
		(layer "B.Cu")
		(net "P3E_CPU0_PE2_SS_RXN<1>")
	)
	(segment
		(start 81.882488 5.775452)
		(end 81.882488 6.61035)
		(width 0.127)
		(layer "B.Cu")
		(net "P3E_CPU0_PE2_SS_RXN<1>")
	)
	(segment
		(start 81.882488 6.61035)
		(end 81.797652 7.095998)
		(width 0.127)
		(layer "B.Cu")
		(net "P3E_CPU0_PE2_SS_RXN<1>")
	)
	(segment
		(start 82.532474 10.10539)
		(end 82.532474 10.348468)
		(width 0.127)
		(layer "B.Cu")
		(net "P3E_CPU0_PE2_SS_RXN<1>")
	)
	(segment
		(start 82.77987 10.945876)
		(end 82.77987 12.514072)
		(width 0.127)
		(layer "B.Cu")
		(net "P3E_CPU0_PE2_SS_RXN<1>")
	)
	(arc
		(start 82.1944 9.0678)
		(mid 82.44583 9.55975)
		(end 82.532474 10.10539)
		(width 0.127)
		(layer "B.Cu")
		(net "P3E_CPU0_PE2_SS_RXN<1>")
	)
	(arc
		(start 82.238088 5.165852)
		(mid 81.977873 5.422579)
		(end 81.882488 5.775452)
		(width 0.127)
		(layer "B.Cu")
		(net "P3E_CPU0_PE2_SS_RXN<1>")
	)
	(arc
		(start 81.906618 8.161274)
		(mid 82.00409 8.629272)
		(end 82.1944 9.0678)
		(width 0.127)
		(layer "B.Cu")
		(net "P3E_CPU0_PE2_SS_RXN<1>")
	)
	(arc
		(start 82.656172 10.647172)
		(mid 82.747744 10.784219)
		(end 82.77987 10.945876)
		(width 0.127)
		(layer "B.Cu")
		(net "P3E_CPU0_PE2_SS_RXN<1>")
	)
	(arc
		(start 82.532474 10.348468)
		(mid 82.564627 10.510114)
		(end 82.656172 10.647172)
		(width 0.127)
		(layer "B.Cu")
		(net "P3E_CPU0_PE2_SS_RXN<1>")
	)
	(segment
		(start 54.896258 -24.83993)
		(end 53.380894 -27.00401)
		(width 0.127)
		(layer "In2.Cu")
		(net "P3E_CPU0_PE2_SS_RXN<1>")
	)
	(segment
		(start 81.47939 3.32613)
		(end 80.084676 2.3495)
		(width 0.127)
		(layer "In2.Cu")
		(net "P3E_CPU0_PE2_SS_RXN<1>")
	)
	(segment
		(start 67.62877 -2.66446)
		(end 63.8302 -5.6896)
		(width 0.127)
		(layer "In2.Cu")
		(net "P3E_CPU0_PE2_SS_RXN<1>")
	)
	(segment
		(start 63.8302 -5.6896)
		(end 63.3984 -6.1722)
		(width 0.127)
		(layer "In2.Cu")
		(net "P3E_CPU0_PE2_SS_RXN<1>")
	)
	(segment
		(start 53.380894 -27.00401)
		(end 53.25872 -27.69616)
		(width 0.127)
		(layer "In2.Cu")
		(net "P3E_CPU0_PE2_SS_RXN<1>")
	)
	(segment
		(start 73.007728 1.101852)
		(end 67.62877 -2.66446)
		(width 0.127)
		(layer "In2.Cu")
		(net "P3E_CPU0_PE2_SS_RXN<1>")
	)
	(segment
		(start 81.787746 3.766566)
		(end 81.47939 3.32613)
		(width 0.127)
		(layer "In2.Cu")
		(net "P3E_CPU0_PE2_SS_RXN<1>")
	)
	(segment
		(start 62.908688 -8.043164)
		(end 62.774576 -8.177276)
		(width 0.127)
		(layer "In2.Cu")
		(net "P3E_CPU0_PE2_SS_RXN<1>")
	)
	(segment
		(start 74.75474 1.409954)
		(end 73.007728 1.101852)
		(width 0.127)
		(layer "In2.Cu")
		(net "P3E_CPU0_PE2_SS_RXN<1>")
	)
	(segment
		(start 80.084676 2.3495)
		(end 74.75474 1.409954)
		(width 0.127)
		(layer "In2.Cu")
		(net "P3E_CPU0_PE2_SS_RXN<1>")
	)
	(segment
		(start 62.9158 -15.2654)
		(end 61.3156 -19.4056)
		(width 0.127)
		(layer "In2.Cu")
		(net "P3E_CPU0_PE2_SS_RXN<1>")
	)
	(segment
		(start 61.3156 -19.4056)
		(end 61.308742 -19.423888)
		(width 0.127)
		(layer "In2.Cu")
		(net "P3E_CPU0_PE2_SS_RXN<1>")
	)
	(segment
		(start 81.87944 4.286758)
		(end 81.787746 3.766566)
		(width 0.127)
		(layer "In2.Cu")
		(net "P3E_CPU0_PE2_SS_RXN<1>")
	)
	(segment
		(start 53.872638 -33.087056)
		(end 53.760624 -33.142936)
		(width 0.127)
		(layer "In2.Cu")
		(net "P3E_CPU0_PE2_SS_RXN<1>")
	)
	(segment
		(start 53.760624 -33.142936)
		(end 53.759354 -33.143444)
		(width 0.127)
		(layer "In2.Cu")
		(net "P3E_CPU0_PE2_SS_RXN<1>")
	)
	(segment
		(start 62.648338 -12.622022)
		(end 62.73165 -12.70508)
		(width 0.127)
		(layer "In2.Cu")
		(net "P3E_CPU0_PE2_SS_RXN<1>")
	)
	(segment
		(start 53.702204 -33.313878)
		(end 54.079902 -34.070036)
		(width 0.127)
		(layer "In2.Cu")
		(net "P3E_CPU0_PE2_SS_RXN<1>")
	)
	(segment
		(start 63.29807 -6.370574)
		(end 63.225934 -6.77926)
		(width 0.127)
		(layer "In2.Cu")
		(net "P3E_CPU0_PE2_SS_RXN<1>")
	)
	(segment
		(start 63.225934 -6.77926)
		(end 63.225934 -7.2771)
		(width 0.127)
		(layer "In2.Cu")
		(net "P3E_CPU0_PE2_SS_RXN<1>")
	)
	(segment
		(start 63.3984 -6.1722)
		(end 63.29807 -6.370574)
		(width 0.127)
		(layer "In2.Cu")
		(net "P3E_CPU0_PE2_SS_RXN<1>")
	)
	(segment
		(start 61.308742 -19.423888)
		(end 60.487052 -20.925282)
		(width 0.127)
		(layer "In2.Cu")
		(net "P3E_CPU0_PE2_SS_RXN<1>")
	)
	(segment
		(start 53.759354 -33.143444)
		(end 53.7591 -33.143444)
		(width 0.127)
		(layer "In2.Cu")
		(net "P3E_CPU0_PE2_SS_RXN<1>")
	)
	(segment
		(start 81.892648 4.705858)
		(end 81.87944 4.286758)
		(width 0.127)
		(layer "In2.Cu")
		(net "P3E_CPU0_PE2_SS_RXN<1>")
	)
	(segment
		(start 63.22441 -14.313662)
		(end 62.9158 -15.2654)
		(width 0.127)
		(layer "In2.Cu")
		(net "P3E_CPU0_PE2_SS_RXN<1>")
	)
	(segment
		(start 63.22441 -13.894816)
		(end 63.22441 -14.313662)
		(width 0.127)
		(layer "In2.Cu")
		(net "P3E_CPU0_PE2_SS_RXN<1>")
	)
	(segment
		(start 62.237874 -9.47293)
		(end 62.237874 -11.63066)
		(width 0.127)
		(layer "In2.Cu")
		(net "P3E_CPU0_PE2_SS_RXN<1>")
	)
	(segment
		(start 60.487052 -20.925282)
		(end 54.896258 -24.83993)
		(width 0.127)
		(layer "In2.Cu")
		(net "P3E_CPU0_PE2_SS_RXN<1>")
	)
	(arc
		(start 63.225934 -7.2771)
		(mid 63.143487 -7.691679)
		(end 62.908688 -8.043164)
		(width 0.127)
		(layer "In2.Cu")
		(net "P3E_CPU0_PE2_SS_RXN<1>")
	)
	(arc
		(start 62.73165 -12.70508)
		(mid 63.096379 -13.250936)
		(end 63.22441 -13.894816)
		(width 0.127)
		(layer "In2.Cu")
		(net "P3E_CPU0_PE2_SS_RXN<1>")
	)
	(arc
		(start 62.237874 -11.63066)
		(mid 62.344499 -12.167169)
		(end 62.648338 -12.622022)
		(width 0.127)
		(layer "In2.Cu")
		(net "P3E_CPU0_PE2_SS_RXN<1>")
	)
	(arc
		(start 53.25872 -27.69616)
		(mid 53.4778 -28.20932)
		(end 53.84038 -28.63342)
		(width 0.127)
		(layer "In2.Cu")
		(net "P3E_CPU0_PE2_SS_RXN<1>")
	)
	(arc
		(start 54.25186 -32.23514)
		(mid 54.21487 -32.729053)
		(end 53.872638 -33.087056)
		(width 0.127)
		(layer "In2.Cu")
		(net "P3E_CPU0_PE2_SS_RXN<1>")
	)
	(arc
		(start 53.7591 -33.143444)
		(mid 53.695337 -33.216897)
		(end 53.702204 -33.313878)
		(width 0.127)
		(layer "In2.Cu")
		(net "P3E_CPU0_PE2_SS_RXN<1>")
	)
	(arc
		(start 62.774576 -8.177276)
		(mid 62.377376 -8.771727)
		(end 62.237874 -9.47293)
		(width 0.127)
		(layer "In2.Cu")
		(net "P3E_CPU0_PE2_SS_RXN<1>")
	)
	(arc
		(start 53.84038 -28.63342)
		(mid 54.174458 -29.135704)
		(end 54.20106 -29.73832)
		(width 0.127)
		(layer "In2.Cu")
		(net "P3E_CPU0_PE2_SS_RXN<1>")
	)
	(arc
		(start 54.20106 -29.73832)
		(mid 54.07084 -30.989895)
		(end 54.25186 -32.23514)
		(width 0.127)
		(layer "In2.Cu")
		(net "P3E_CPU0_PE2_SS_RXN<1>")
	)
	(arc
		(start 82.238088 5.165852)
		(mid 81.992564 4.990528)
		(end 81.892648 4.705858)
		(width 0.127)
		(layer "In2.Cu")
		(net "P3E_CPU0_PE2_SS_RXN<1>")
	)
	(via
		(at 79.647288 5.165852)
		(size 0.508)
		(drill 0.254)
		(layers "F.Cu" "B.Cu")
		(net "P3E_CPU0_PE2_SS_RXN<0>")
	)
	(segment
		(start 79.257652 7.728712)
		(end 79.281782 7.424674)
		(width 0.127)
		(layer "B.Cu")
		(net "P3E_CPU0_PE2_SS_RXN<0>")
	)
	(segment
		(start 79.291688 6.50748)
		(end 79.291688 5.6896)
		(width 0.127)
		(layer "B.Cu")
		(net "P3E_CPU0_PE2_SS_RXN<0>")
	)
	(segment
		(start 80.379824 12.514072)
		(end 80.379824 10.854182)
		(width 0.127)
		(layer "B.Cu")
		(net "P3E_CPU0_PE2_SS_RXN<0>")
	)
	(segment
		(start 79.281782 7.424674)
		(end 79.291688 6.50748)
		(width 0.127)
		(layer "B.Cu")
		(net "P3E_CPU0_PE2_SS_RXN<0>")
	)
	(segment
		(start 80.132428 10.243312)
		(end 80.132428 9.705848)
		(width 0.127)
		(layer "B.Cu")
		(net "P3E_CPU0_PE2_SS_RXN<0>")
	)
	(arc
		(start 79.291688 5.6896)
		(mid 79.388978 5.373049)
		(end 79.647288 5.165852)
		(width 0.127)
		(layer "B.Cu")
		(net "P3E_CPU0_PE2_SS_RXN<0>")
	)
	(arc
		(start 80.379824 10.854182)
		(mid 80.338893 10.648406)
		(end 80.222344 10.473944)
		(width 0.127)
		(layer "B.Cu")
		(net "P3E_CPU0_PE2_SS_RXN<0>")
	)
	(arc
		(start 80.132428 9.705848)
		(mid 80.061006 9.346785)
		(end 79.8576 9.0424)
		(width 0.127)
		(layer "B.Cu")
		(net "P3E_CPU0_PE2_SS_RXN<0>")
	)
	(arc
		(start 80.222344 10.473944)
		(mid 80.155792 10.374436)
		(end 80.132428 10.257028)
		(width 0.127)
		(layer "B.Cu")
		(net "P3E_CPU0_PE2_SS_RXN<0>")
	)
	(arc
		(start 79.8576 9.0424)
		(mid 79.528795 8.535086)
		(end 79.288894 7.980172)
		(width 0.127)
		(layer "B.Cu")
		(net "P3E_CPU0_PE2_SS_RXN<0>")
	)
	(arc
		(start 80.132428 10.257028)
		(mid 80.13246 10.25017)
		(end 80.132428 10.243312)
		(width 0.127)
		(layer "B.Cu")
		(net "P3E_CPU0_PE2_SS_RXN<0>")
	)
	(arc
		(start 79.288894 7.980172)
		(mid 79.260598 7.856017)
		(end 79.257652 7.728712)
		(width 0.127)
		(layer "B.Cu")
		(net "P3E_CPU0_PE2_SS_RXN<0>")
	)
	(segment
		(start 50.418492 -25.72766)
		(end 50.646584 -25.699212)
		(width 0.127)
		(layer "In2.Cu")
		(net "P3E_CPU0_PE2_SS_RXN<0>")
	)
	(segment
		(start 51.444652 -24.4094)
		(end 57.043066 -20.557998)
		(width 0.127)
		(layer "In2.Cu")
		(net "P3E_CPU0_PE2_SS_RXN<0>")
	)
	(segment
		(start 70.484492 2.625598)
		(end 78.516734 4.041902)
		(width 0.127)
		(layer "In2.Cu")
		(net "P3E_CPU0_PE2_SS_RXN<0>")
	)
	(segment
		(start 59.226704 -6.77926)
		(end 59.309 -6.5024)
		(width 0.127)
		(layer "In2.Cu")
		(net "P3E_CPU0_PE2_SS_RXN<0>")
	)
	(segment
		(start 49.079912 -32.069786)
		(end 48.702468 -32.825436)
		(width 0.127)
		(layer "In2.Cu")
		(net "P3E_CPU0_PE2_SS_RXN<0>")
	)
	(segment
		(start 48.162972 -32.377634)
		(end 48.162972 -32.37738)
		(width 0.127)
		(layer "In2.Cu")
		(net "P3E_CPU0_PE2_SS_RXN<0>")
	)
	(segment
		(start 48.532288 -32.882332)
		(end 48.532034 -32.882332)
		(width 0.127)
		(layer "In2.Cu")
		(net "P3E_CPU0_PE2_SS_RXN<0>")
	)
	(segment
		(start 58.21299 -18.709894)
		(end 59.06516 -15.221204)
		(width 0.127)
		(layer "In2.Cu")
		(net "P3E_CPU0_PE2_SS_RXN<0>")
	)
	(segment
		(start 57.87898 -19.613372)
		(end 57.896506 -19.586194)
		(width 0.127)
		(layer "In2.Cu")
		(net "P3E_CPU0_PE2_SS_RXN<0>")
	)
	(segment
		(start 57.896506 -19.586194)
		(end 58.21299 -18.709894)
		(width 0.127)
		(layer "In2.Cu")
		(net "P3E_CPU0_PE2_SS_RXN<0>")
	)
	(segment
		(start 49.221644 -27.939492)
		(end 49.276 -27.3558)
		(width 0.127)
		(layer "In2.Cu")
		(net "P3E_CPU0_PE2_SS_RXN<0>")
	)
	(segment
		(start 49.978818 -26.55697)
		(end 50.213006 -26.256488)
		(width 0.127)
		(layer "In2.Cu")
		(net "P3E_CPU0_PE2_SS_RXN<0>")
	)
	(segment
		(start 79.283306 4.8006)
		(end 79.283306 4.802378)
		(width 0.127)
		(layer "In2.Cu")
		(net "P3E_CPU0_PE2_SS_RXN<0>")
	)
	(segment
		(start 59.22518 -14.313662)
		(end 59.22518 -13.894816)
		(width 0.127)
		(layer "In2.Cu")
		(net "P3E_CPU0_PE2_SS_RXN<0>")
	)
	(segment
		(start 58.775346 -8.177276)
		(end 58.909458 -8.043164)
		(width 0.127)
		(layer "In2.Cu")
		(net "P3E_CPU0_PE2_SS_RXN<0>")
	)
	(segment
		(start 48.162972 -32.37738)
		(end 48.208184 -31.72714)
		(width 0.127)
		(layer "In2.Cu")
		(net "P3E_CPU0_PE2_SS_RXN<0>")
	)
	(segment
		(start 79.283306 4.802378)
		(end 79.285338 4.802124)
		(width 0.127)
		(layer "In2.Cu")
		(net "P3E_CPU0_PE2_SS_RXN<0>")
	)
	(segment
		(start 78.516734 4.041902)
		(end 79.079598 4.435856)
		(width 0.127)
		(layer "In2.Cu")
		(net "P3E_CPU0_PE2_SS_RXN<0>")
	)
	(segment
		(start 79.285338 4.802124)
		(end 79.285338 4.803902)
		(width 0.127)
		(layer "In2.Cu")
		(net "P3E_CPU0_PE2_SS_RXN<0>")
	)
	(segment
		(start 64.530732 -1.543304)
		(end 70.484492 2.625598)
		(width 0.127)
		(layer "In2.Cu")
		(net "P3E_CPU0_PE2_SS_RXN<0>")
	)
	(segment
		(start 48.966628 -28.30449)
		(end 49.221644 -27.939492)
		(width 0.127)
		(layer "In2.Cu")
		(net "P3E_CPU0_PE2_SS_RXN<0>")
	)
	(segment
		(start 49.292764 -27.173936)
		(end 49.750726 -26.585418)
		(width 0.127)
		(layer "In2.Cu")
		(net "P3E_CPU0_PE2_SS_RXN<0>")
	)
	(segment
		(start 59.64936 -6.07187)
		(end 60.295282 -5.472176)
		(width 0.127)
		(layer "In2.Cu")
		(net "P3E_CPU0_PE2_SS_RXN<0>")
	)
	(segment
		(start 59.226704 -7.2771)
		(end 59.226704 -6.77926)
		(width 0.127)
		(layer "In2.Cu")
		(net "P3E_CPU0_PE2_SS_RXN<0>")
	)
	(segment
		(start 79.152242 4.508754)
		(end 79.226156 4.614164)
		(width 0.127)
		(layer "In2.Cu")
		(net "P3E_CPU0_PE2_SS_RXN<0>")
	)
	(segment
		(start 59.309 -6.5024)
		(end 59.64936 -6.07187)
		(width 0.127)
		(layer "In2.Cu")
		(net "P3E_CPU0_PE2_SS_RXN<0>")
	)
	(segment
		(start 50.184558 -26.028396)
		(end 50.418492 -25.72766)
		(width 0.127)
		(layer "In2.Cu")
		(net "P3E_CPU0_PE2_SS_RXN<0>")
	)
	(segment
		(start 59.06516 -15.221204)
		(end 59.22518 -14.313662)
		(width 0.127)
		(layer "In2.Cu")
		(net "P3E_CPU0_PE2_SS_RXN<0>")
	)
	(segment
		(start 57.7342 -19.9136)
		(end 57.87898 -19.613372)
		(width 0.127)
		(layer "In2.Cu")
		(net "P3E_CPU0_PE2_SS_RXN<0>")
	)
	(segment
		(start 57.043066 -20.557998)
		(end 57.411112 -20.303998)
		(width 0.127)
		(layer "In2.Cu")
		(net "P3E_CPU0_PE2_SS_RXN<0>")
	)
	(segment
		(start 50.880772 -25.398476)
		(end 50.852324 -25.170384)
		(width 0.127)
		(layer "In2.Cu")
		(net "P3E_CPU0_PE2_SS_RXN<0>")
	)
	(segment
		(start 79.276956 4.74726)
		(end 79.283306 4.8006)
		(width 0.127)
		(layer "In2.Cu")
		(net "P3E_CPU0_PE2_SS_RXN<0>")
	)
	(segment
		(start 50.213006 -26.256488)
		(end 50.184558 -26.028396)
		(width 0.127)
		(layer "In2.Cu")
		(net "P3E_CPU0_PE2_SS_RXN<0>")
	)
	(segment
		(start 60.295282 -5.472176)
		(end 64.530732 -1.543304)
		(width 0.127)
		(layer "In2.Cu")
		(net "P3E_CPU0_PE2_SS_RXN<0>")
	)
	(segment
		(start 57.411112 -20.303998)
		(end 57.7342 -19.9136)
		(width 0.127)
		(layer "In2.Cu")
		(net "P3E_CPU0_PE2_SS_RXN<0>")
	)
	(segment
		(start 49.750726 -26.585418)
		(end 49.978818 -26.55697)
		(width 0.127)
		(layer "In2.Cu")
		(net "P3E_CPU0_PE2_SS_RXN<0>")
	)
	(segment
		(start 58.73242 -12.70508)
		(end 58.649108 -12.622022)
		(width 0.127)
		(layer "In2.Cu")
		(net "P3E_CPU0_PE2_SS_RXN<0>")
	)
	(segment
		(start 48.532034 -32.882332)
		(end 48.418242 -32.82569)
		(width 0.127)
		(layer "In2.Cu")
		(net "P3E_CPU0_PE2_SS_RXN<0>")
	)
	(segment
		(start 49.276 -27.3558)
		(end 49.292764 -27.173936)
		(width 0.127)
		(layer "In2.Cu")
		(net "P3E_CPU0_PE2_SS_RXN<0>")
	)
	(segment
		(start 48.759872 -28.511246)
		(end 48.966628 -28.30449)
		(width 0.127)
		(layer "In2.Cu")
		(net "P3E_CPU0_PE2_SS_RXN<0>")
	)
	(segment
		(start 79.079598 4.435856)
		(end 79.080614 4.436618)
		(width 0.127)
		(layer "In2.Cu")
		(net "P3E_CPU0_PE2_SS_RXN<0>")
	)
	(segment
		(start 51.444398 -24.409654)
		(end 51.444652 -24.4094)
		(width 0.127)
		(layer "In2.Cu")
		(net "P3E_CPU0_PE2_SS_RXN<0>")
	)
	(segment
		(start 58.238644 -11.63066)
		(end 58.238644 -9.47293)
		(width 0.127)
		(layer "In2.Cu")
		(net "P3E_CPU0_PE2_SS_RXN<0>")
	)
	(segment
		(start 50.852324 -25.170384)
		(end 51.444398 -24.409654)
		(width 0.127)
		(layer "In2.Cu")
		(net "P3E_CPU0_PE2_SS_RXN<0>")
	)
	(segment
		(start 50.646584 -25.699212)
		(end 50.880772 -25.398476)
		(width 0.127)
		(layer "In2.Cu")
		(net "P3E_CPU0_PE2_SS_RXN<0>")
	)
	(arc
		(start 58.909458 -8.043164)
		(mid 59.144251 -7.691677)
		(end 59.226704 -7.2771)
		(width 0.127)
		(layer "In2.Cu")
		(net "P3E_CPU0_PE2_SS_RXN<0>")
	)
	(arc
		(start 59.22518 -13.894816)
		(mid 59.097108 -13.250953)
		(end 58.73242 -12.70508)
		(width 0.127)
		(layer "In2.Cu")
		(net "P3E_CPU0_PE2_SS_RXN<0>")
	)
	(arc
		(start 79.080614 4.436618)
		(mid 79.119581 4.469554)
		(end 79.152242 4.508754)
		(width 0.127)
		(layer "In2.Cu")
		(net "P3E_CPU0_PE2_SS_RXN<0>")
	)
	(arc
		(start 58.649108 -12.622022)
		(mid 58.345276 -12.167166)
		(end 58.238644 -11.63066)
		(width 0.127)
		(layer "In2.Cu")
		(net "P3E_CPU0_PE2_SS_RXN<0>")
	)
	(arc
		(start 48.265334 -29.642308)
		(mid 48.379848 -29.060595)
		(end 48.705008 -28.56484)
		(width 0.127)
		(layer "In2.Cu")
		(net "P3E_CPU0_PE2_SS_RXN<0>")
	)
	(arc
		(start 48.705008 -28.56484)
		(mid 48.73211 -28.537705)
		(end 48.759872 -28.511246)
		(width 0.127)
		(layer "In2.Cu")
		(net "P3E_CPU0_PE2_SS_RXN<0>")
	)
	(arc
		(start 79.226156 4.614164)
		(mid 79.25981 4.677564)
		(end 79.276956 4.74726)
		(width 0.127)
		(layer "In2.Cu")
		(net "P3E_CPU0_PE2_SS_RXN<0>")
	)
	(arc
		(start 79.285338 4.803902)
		(mid 79.391351 5.059839)
		(end 79.647288 5.165852)
		(width 0.127)
		(layer "In2.Cu")
		(net "P3E_CPU0_PE2_SS_RXN<0>")
	)
	(arc
		(start 48.418242 -32.82569)
		(mid 48.222699 -32.640329)
		(end 48.162972 -32.377634)
		(width 0.127)
		(layer "In2.Cu")
		(net "P3E_CPU0_PE2_SS_RXN<0>")
	)
	(arc
		(start 58.238644 -9.47293)
		(mid 58.378124 -8.771718)
		(end 58.775346 -8.177276)
		(width 0.127)
		(layer "In2.Cu")
		(net "P3E_CPU0_PE2_SS_RXN<0>")
	)
	(arc
		(start 48.208184 -31.72714)
		(mid 48.258307 -30.685315)
		(end 48.265334 -29.642308)
		(width 0.127)
		(layer "In2.Cu")
		(net "P3E_CPU0_PE2_SS_RXN<0>")
	)
	(arc
		(start 48.702468 -32.825436)
		(mid 48.629162 -32.889129)
		(end 48.532288 -32.882332)
		(width 0.127)
		(layer "In2.Cu")
		(net "P3E_CPU0_PE2_SS_RXN<0>")
	)
	(segment
		(start 112.175036 12.234672)
		(end 112.175036 11.082274)
		(width 0.127)
		(layer "F.Cu")
		(net "P3E_CPU0_PE2_SS_C_TXP<9>")
	)
	(segment
		(start 112.346486 9.037066)
		(end 112.346486 9.036812)
		(width 0.127)
		(layer "F.Cu")
		(net "P3E_CPU0_PE2_SS_C_TXP<9>")
	)
	(segment
		(start 112.29848 10.783824)
		(end 112.298734 10.78357)
		(width 0.127)
		(layer "F.Cu")
		(net "P3E_CPU0_PE2_SS_C_TXP<9>")
	)
	(segment
		(start 112.346486 9.036812)
		(end 112.201452 8.214868)
		(width 0.127)
		(layer "F.Cu")
		(net "P3E_CPU0_PE2_SS_C_TXP<9>")
	)
	(segment
		(start 112.422686 10.484866)
		(end 112.422686 9.468358)
		(width 0.127)
		(layer "F.Cu")
		(net "P3E_CPU0_PE2_SS_C_TXP<9>")
	)
	(segment
		(start 112.422686 9.468358)
		(end 112.346486 9.037066)
		(width 0.127)
		(layer "F.Cu")
		(net "P3E_CPU0_PE2_SS_C_TXP<9>")
	)
	(segment
		(start 112.201452 8.214868)
		(end 112.201452 8.04164)
		(width 0.127)
		(layer "F.Cu")
		(net "P3E_CPU0_PE2_SS_C_TXP<9>")
	)
	(segment
		(start 111.902494 7.742682)
		(end 111.833406 7.742682)
		(width 0.127)
		(layer "F.Cu")
		(net "P3E_CPU0_PE2_SS_C_TXP<9>")
	)
	(via
		(at 111.833406 7.742682)
		(size 0.508)
		(drill 0.254)
		(layers "F.Cu" "B.Cu")
		(net "P3E_CPU0_PE2_SS_C_TXP<9>")
	)
	(arc
		(start 112.298734 10.78357)
		(mid 112.390389 10.646538)
		(end 112.422686 10.484866)
		(width 0.127)
		(layer "F.Cu")
		(net "P3E_CPU0_PE2_SS_C_TXP<9>")
	)
	(arc
		(start 112.175036 11.082274)
		(mid 112.207121 10.920794)
		(end 112.29848 10.783824)
		(width 0.127)
		(layer "F.Cu")
		(net "P3E_CPU0_PE2_SS_C_TXP<9>")
	)
	(arc
		(start 112.201452 8.04164)
		(mid 112.113889 7.830245)
		(end 111.902494 7.742682)
		(width 0.127)
		(layer "F.Cu")
		(net "P3E_CPU0_PE2_SS_C_TXP<9>")
	)
	(segment
		(start 111.621062 3.777742)
		(end 112.151922 4.535678)
		(width 0.127)
		(layer "In2.Cu")
		(net "P3E_CPU0_PE2_SS_C_TXP<9>")
	)
	(segment
		(start 86.628986 -28.382468)
		(end 86.742016 -28.325826)
		(width 0.127)
		(layer "In2.Cu")
		(net "P3E_CPU0_PE2_SS_C_TXP<9>")
	)
	(segment
		(start 88.00465 -25.086564)
		(end 87.964772 -24.86025)
		(width 0.127)
		(layer "In2.Cu")
		(net "P3E_CPU0_PE2_SS_C_TXP<9>")
	)
	(segment
		(start 88.183212 -24.548084)
		(end 88.40978 -24.508206)
		(width 0.127)
		(layer "In2.Cu")
		(net "P3E_CPU0_PE2_SS_C_TXP<9>")
	)
	(segment
		(start 95.90786 -11.87958)
		(end 95.90786 -9.298686)
		(width 0.127)
		(layer "In2.Cu")
		(net "P3E_CPU0_PE2_SS_C_TXP<9>")
	)
	(segment
		(start 110.710726 3.140456)
		(end 111.621062 3.777742)
		(width 0.127)
		(layer "In2.Cu")
		(net "P3E_CPU0_PE2_SS_C_TXP<9>")
	)
	(segment
		(start 112.2299 4.9784)
		(end 112.2299 5.538978)
		(width 0.127)
		(layer "In2.Cu")
		(net "P3E_CPU0_PE2_SS_C_TXP<9>")
	)
	(segment
		(start 94.92742 -14.325854)
		(end 94.92742 -13.932408)
		(width 0.127)
		(layer "In2.Cu")
		(net "P3E_CPU0_PE2_SS_C_TXP<9>")
	)
	(segment
		(start 86.628732 -28.382468)
		(end 86.628986 -28.382468)
		(width 0.127)
		(layer "In2.Cu")
		(net "P3E_CPU0_PE2_SS_C_TXP<9>")
	)
	(segment
		(start 95.462344 -12.640564)
		(end 95.68434 -12.418568)
		(width 0.127)
		(layer "In2.Cu")
		(net "P3E_CPU0_PE2_SS_C_TXP<9>")
	)
	(segment
		(start 98.027998 -0.93853)
		(end 101.544374 1.523746)
		(width 0.127)
		(layer "In2.Cu")
		(net "P3E_CPU0_PE2_SS_C_TXP<9>")
	)
	(segment
		(start 95.486728 -8.28294)
		(end 95.378524 -8.174736)
		(width 0.127)
		(layer "In2.Cu")
		(net "P3E_CPU0_PE2_SS_C_TXP<9>")
	)
	(segment
		(start 97.73158 -1.361694)
		(end 98.027998 -0.93853)
		(width 0.127)
		(layer "In2.Cu")
		(net "P3E_CPU0_PE2_SS_C_TXP<9>")
	)
	(segment
		(start 87.015828 -27.029664)
		(end 87.16264 -26.289254)
		(width 0.127)
		(layer "In2.Cu")
		(net "P3E_CPU0_PE2_SS_C_TXP<9>")
	)
	(segment
		(start 112.211866 6.601714)
		(end 112.211866 7.269988)
		(width 0.127)
		(layer "In2.Cu")
		(net "P3E_CPU0_PE2_SS_C_TXP<9>")
	)
	(segment
		(start 87.341202 -25.750774)
		(end 87.559896 -25.438608)
		(width 0.127)
		(layer "In2.Cu")
		(net "P3E_CPU0_PE2_SS_C_TXP<9>")
	)
	(segment
		(start 95.350584 -4.761738)
		(end 97.62236 -1.517904)
		(width 0.127)
		(layer "In2.Cu")
		(net "P3E_CPU0_PE2_SS_C_TXP<9>")
	)
	(segment
		(start 94.720918 -15.495016)
		(end 94.92742 -14.325854)
		(width 0.127)
		(layer "In2.Cu")
		(net "P3E_CPU0_PE2_SS_C_TXP<9>")
	)
	(segment
		(start 87.38108 -25.977088)
		(end 87.341202 -25.750774)
		(width 0.127)
		(layer "In2.Cu")
		(net "P3E_CPU0_PE2_SS_C_TXP<9>")
	)
	(segment
		(start 112.2299 5.538978)
		(end 112.140238 6.081522)
		(width 0.127)
		(layer "In2.Cu")
		(net "P3E_CPU0_PE2_SS_C_TXP<9>")
	)
	(segment
		(start 86.080092 -27.570176)
		(end 86.458298 -28.325826)
		(width 0.127)
		(layer "In2.Cu")
		(net "P3E_CPU0_PE2_SS_C_TXP<9>")
	)
	(segment
		(start 88.40978 -24.508206)
		(end 94.720918 -15.495016)
		(width 0.127)
		(layer "In2.Cu")
		(net "P3E_CPU0_PE2_SS_C_TXP<9>")
	)
	(segment
		(start 87.78621 -25.39873)
		(end 88.00465 -25.086564)
		(width 0.127)
		(layer "In2.Cu")
		(net "P3E_CPU0_PE2_SS_C_TXP<9>")
	)
	(segment
		(start 112.140238 6.081522)
		(end 112.211866 6.601714)
		(width 0.127)
		(layer "In2.Cu")
		(net "P3E_CPU0_PE2_SS_C_TXP<9>")
	)
	(segment
		(start 94.94012 -7.088632)
		(end 95.350584 -4.761738)
		(width 0.127)
		(layer "In2.Cu")
		(net "P3E_CPU0_PE2_SS_C_TXP<9>")
	)
	(segment
		(start 87.964772 -24.86025)
		(end 88.183212 -24.548084)
		(width 0.127)
		(layer "In2.Cu")
		(net "P3E_CPU0_PE2_SS_C_TXP<9>")
	)
	(segment
		(start 87.16264 -26.289254)
		(end 87.38108 -25.977088)
		(width 0.127)
		(layer "In2.Cu")
		(net "P3E_CPU0_PE2_SS_C_TXP<9>")
	)
	(segment
		(start 101.544374 1.523746)
		(end 110.710726 3.140456)
		(width 0.127)
		(layer "In2.Cu")
		(net "P3E_CPU0_PE2_SS_C_TXP<9>")
	)
	(segment
		(start 112.151922 4.535678)
		(end 112.2299 4.9784)
		(width 0.127)
		(layer "In2.Cu")
		(net "P3E_CPU0_PE2_SS_C_TXP<9>")
	)
	(segment
		(start 87.559896 -25.438608)
		(end 87.78621 -25.39873)
		(width 0.127)
		(layer "In2.Cu")
		(net "P3E_CPU0_PE2_SS_C_TXP<9>")
	)
	(segment
		(start 97.62236 -1.517904)
		(end 97.73158 -1.361694)
		(width 0.127)
		(layer "In2.Cu")
		(net "P3E_CPU0_PE2_SS_C_TXP<9>")
	)
	(arc
		(start 95.68434 -12.418568)
		(mid 95.849657 -12.171293)
		(end 95.90786 -11.87958)
		(width 0.127)
		(layer "In2.Cu")
		(net "P3E_CPU0_PE2_SS_C_TXP<9>")
	)
	(arc
		(start 112.211866 7.269988)
		(mid 112.10559 7.572743)
		(end 111.833406 7.742682)
		(width 0.127)
		(layer "In2.Cu")
		(net "P3E_CPU0_PE2_SS_C_TXP<9>")
	)
	(arc
		(start 95.378524 -8.174736)
		(mid 95.048808 -7.676304)
		(end 94.94012 -7.088632)
		(width 0.127)
		(layer "In2.Cu")
		(net "P3E_CPU0_PE2_SS_C_TXP<9>")
	)
	(arc
		(start 86.458298 -28.325826)
		(mid 86.531784 -28.389445)
		(end 86.628732 -28.382468)
		(width 0.127)
		(layer "In2.Cu")
		(net "P3E_CPU0_PE2_SS_C_TXP<9>")
	)
	(arc
		(start 86.995508 -27.840178)
		(mid 86.97101 -27.434054)
		(end 87.015828 -27.029664)
		(width 0.127)
		(layer "In2.Cu")
		(net "P3E_CPU0_PE2_SS_C_TXP<9>")
	)
	(arc
		(start 86.742016 -28.325826)
		(mid 86.947466 -28.12406)
		(end 86.995508 -27.840178)
		(width 0.127)
		(layer "In2.Cu")
		(net "P3E_CPU0_PE2_SS_C_TXP<9>")
	)
	(arc
		(start 94.92742 -13.932408)
		(mid 95.066444 -13.233306)
		(end 95.462344 -12.640564)
		(width 0.127)
		(layer "In2.Cu")
		(net "P3E_CPU0_PE2_SS_C_TXP<9>")
	)
	(arc
		(start 95.90786 -9.298686)
		(mid 95.798318 -8.748924)
		(end 95.486728 -8.28294)
		(width 0.127)
		(layer "In2.Cu")
		(net "P3E_CPU0_PE2_SS_C_TXP<9>")
	)
	(segment
		(start 109.601 8.220964)
		(end 109.601 8.101076)
		(width 0.127)
		(layer "F.Cu")
		(net "P3E_CPU0_PE2_SS_C_TXP<8>")
	)
	(segment
		(start 110.02264 10.484866)
		(end 110.02264 9.767824)
		(width 0.127)
		(layer "F.Cu")
		(net "P3E_CPU0_PE2_SS_C_TXP<8>")
	)
	(segment
		(start 109.72038 8.89762)
		(end 109.72038 8.897366)
		(width 0.127)
		(layer "F.Cu")
		(net "P3E_CPU0_PE2_SS_C_TXP<8>")
	)
	(segment
		(start 109.77499 12.234672)
		(end 109.77499 11.082274)
		(width 0.127)
		(layer "F.Cu")
		(net "P3E_CPU0_PE2_SS_C_TXP<8>")
	)
	(segment
		(start 110.02264 9.767824)
		(end 109.919008 9.181084)
		(width 0.127)
		(layer "F.Cu")
		(net "P3E_CPU0_PE2_SS_C_TXP<8>")
	)
	(segment
		(start 109.898434 10.783824)
		(end 109.898688 10.78357)
		(width 0.127)
		(layer "F.Cu")
		(net "P3E_CPU0_PE2_SS_C_TXP<8>")
	)
	(segment
		(start 109.673898 8.633968)
		(end 109.601 8.220964)
		(width 0.127)
		(layer "F.Cu")
		(net "P3E_CPU0_PE2_SS_C_TXP<8>")
	)
	(segment
		(start 109.72038 8.897366)
		(end 109.673898 8.633968)
		(width 0.127)
		(layer "F.Cu")
		(net "P3E_CPU0_PE2_SS_C_TXP<8>")
	)
	(segment
		(start 109.919008 9.181084)
		(end 109.72038 8.89762)
		(width 0.127)
		(layer "F.Cu")
		(net "P3E_CPU0_PE2_SS_C_TXP<8>")
	)
	(via
		(at 109.242606 7.742682)
		(size 0.508)
		(drill 0.254)
		(layers "F.Cu" "B.Cu")
		(net "P3E_CPU0_PE2_SS_C_TXP<8>")
	)
	(arc
		(start 109.898688 10.78357)
		(mid 109.990343 10.646538)
		(end 110.02264 10.484866)
		(width 0.127)
		(layer "F.Cu")
		(net "P3E_CPU0_PE2_SS_C_TXP<8>")
	)
	(arc
		(start 109.77499 11.082274)
		(mid 109.807075 10.920794)
		(end 109.898434 10.783824)
		(width 0.127)
		(layer "F.Cu")
		(net "P3E_CPU0_PE2_SS_C_TXP<8>")
	)
	(arc
		(start 109.601 8.101076)
		(mid 109.496029 7.847653)
		(end 109.242606 7.742682)
		(width 0.127)
		(layer "F.Cu")
		(net "P3E_CPU0_PE2_SS_C_TXP<8>")
	)
	(segment
		(start 83.657694 -24.968708)
		(end 83.43138 -25.008586)
		(width 0.127)
		(layer "In2.Cu")
		(net "P3E_CPU0_PE2_SS_C_TXP<8>")
	)
	(segment
		(start 109.621066 6.601714)
		(end 109.550962 6.204966)
		(width 0.127)
		(layer "In2.Cu")
		(net "P3E_CPU0_PE2_SS_C_TXP<8>")
	)
	(segment
		(start 91.378024 -8.174736)
		(end 91.486228 -8.28294)
		(width 0.127)
		(layer "In2.Cu")
		(net "P3E_CPU0_PE2_SS_C_TXP<8>")
	)
	(segment
		(start 83.252818 -25.547066)
		(end 83.028282 -25.867614)
		(width 0.127)
		(layer "In2.Cu")
		(net "P3E_CPU0_PE2_SS_C_TXP<8>")
	)
	(segment
		(start 109.55147 6.196838)
		(end 109.452664 5.959348)
		(width 0.127)
		(layer "In2.Cu")
		(net "P3E_CPU0_PE2_SS_C_TXP<8>")
	)
	(segment
		(start 90.93962 -6.743446)
		(end 90.93962 -7.115302)
		(width 0.127)
		(layer "In2.Cu")
		(net "P3E_CPU0_PE2_SS_C_TXP<8>")
	)
	(segment
		(start 84.281264 -24.078184)
		(end 84.05495 -24.118062)
		(width 0.127)
		(layer "In2.Cu")
		(net "P3E_CPU0_PE2_SS_C_TXP<8>")
	)
	(segment
		(start 91.68384 -12.418568)
		(end 91.461844 -12.640564)
		(width 0.127)
		(layer "In2.Cu")
		(net "P3E_CPU0_PE2_SS_C_TXP<8>")
	)
	(segment
		(start 109.552994 6.20014)
		(end 109.55147 6.196838)
		(width 0.127)
		(layer "In2.Cu")
		(net "P3E_CPU0_PE2_SS_C_TXP<8>")
	)
	(segment
		(start 82.741516 -28.325826)
		(end 82.628486 -28.382468)
		(width 0.127)
		(layer "In2.Cu")
		(net "P3E_CPU0_PE2_SS_C_TXP<8>")
	)
	(segment
		(start 97.475802 2.460498)
		(end 97.31883 2.236216)
		(width 0.127)
		(layer "In2.Cu")
		(net "P3E_CPU0_PE2_SS_C_TXP<8>")
	)
	(segment
		(start 100.3808 3.9878)
		(end 99.411536 3.816858)
		(width 0.127)
		(layer "In2.Cu")
		(net "P3E_CPU0_PE2_SS_C_TXP<8>")
	)
	(segment
		(start 99.411536 3.816858)
		(end 97.475802 2.460498)
		(width 0.127)
		(layer "In2.Cu")
		(net "P3E_CPU0_PE2_SS_C_TXP<8>")
	)
	(segment
		(start 82.984848 -26.114248)
		(end 82.949288 -26.616406)
		(width 0.127)
		(layer "In2.Cu")
		(net "P3E_CPU0_PE2_SS_C_TXP<8>")
	)
	(segment
		(start 90.865198 -14.675104)
		(end 84.281264 -24.078184)
		(width 0.127)
		(layer "In2.Cu")
		(net "P3E_CPU0_PE2_SS_C_TXP<8>")
	)
	(segment
		(start 83.21294 -25.320752)
		(end 83.252818 -25.547066)
		(width 0.127)
		(layer "In2.Cu")
		(net "P3E_CPU0_PE2_SS_C_TXP<8>")
	)
	(segment
		(start 101.811328 3.735578)
		(end 100.3808 3.9878)
		(width 0.127)
		(layer "In2.Cu")
		(net "P3E_CPU0_PE2_SS_C_TXP<8>")
	)
	(segment
		(start 91.90736 -9.298686)
		(end 91.90736 -11.87958)
		(width 0.127)
		(layer "In2.Cu")
		(net "P3E_CPU0_PE2_SS_C_TXP<8>")
	)
	(segment
		(start 83.836256 -24.430228)
		(end 83.876388 -24.656542)
		(width 0.127)
		(layer "In2.Cu")
		(net "P3E_CPU0_PE2_SS_C_TXP<8>")
	)
	(segment
		(start 91.080336 -5.944362)
		(end 90.93962 -6.743446)
		(width 0.127)
		(layer "In2.Cu")
		(net "P3E_CPU0_PE2_SS_C_TXP<8>")
	)
	(segment
		(start 91.91879 -5.105908)
		(end 91.080336 -5.944362)
		(width 0.127)
		(layer "In2.Cu")
		(net "P3E_CPU0_PE2_SS_C_TXP<8>")
	)
	(segment
		(start 109.621066 7.291578)
		(end 109.621066 6.601714)
		(width 0.127)
		(layer "In2.Cu")
		(net "P3E_CPU0_PE2_SS_C_TXP<8>")
	)
	(segment
		(start 92.452444 -4.716526)
		(end 92.403676 -4.765548)
		(width 0.127)
		(layer "In2.Cu")
		(net "P3E_CPU0_PE2_SS_C_TXP<8>")
	)
	(segment
		(start 82.457798 -28.325826)
		(end 82.079592 -27.570176)
		(width 0.127)
		(layer "In2.Cu")
		(net "P3E_CPU0_PE2_SS_C_TXP<8>")
	)
	(segment
		(start 83.876388 -24.656542)
		(end 83.657694 -24.968708)
		(width 0.127)
		(layer "In2.Cu")
		(net "P3E_CPU0_PE2_SS_C_TXP<8>")
	)
	(segment
		(start 83.028282 -25.867614)
		(end 82.984848 -26.114248)
		(width 0.127)
		(layer "In2.Cu")
		(net "P3E_CPU0_PE2_SS_C_TXP<8>")
	)
	(segment
		(start 84.05495 -24.118062)
		(end 83.836256 -24.430228)
		(width 0.127)
		(layer "In2.Cu")
		(net "P3E_CPU0_PE2_SS_C_TXP<8>")
	)
	(segment
		(start 92.403676 -4.765548)
		(end 91.91879 -5.105908)
		(width 0.127)
		(layer "In2.Cu")
		(net "P3E_CPU0_PE2_SS_C_TXP<8>")
	)
	(segment
		(start 90.92692 -13.932408)
		(end 90.92692 -14.325854)
		(width 0.127)
		(layer "In2.Cu")
		(net "P3E_CPU0_PE2_SS_C_TXP<8>")
	)
	(segment
		(start 90.92692 -14.325854)
		(end 90.865198 -14.675104)
		(width 0.127)
		(layer "In2.Cu")
		(net "P3E_CPU0_PE2_SS_C_TXP<8>")
	)
	(segment
		(start 83.43138 -25.008586)
		(end 83.21294 -25.320752)
		(width 0.127)
		(layer "In2.Cu")
		(net "P3E_CPU0_PE2_SS_C_TXP<8>")
	)
	(segment
		(start 97.31883 2.236216)
		(end 92.452444 -4.716526)
		(width 0.127)
		(layer "In2.Cu")
		(net "P3E_CPU0_PE2_SS_C_TXP<8>")
	)
	(segment
		(start 107.780836 4.788154)
		(end 101.811328 3.735578)
		(width 0.127)
		(layer "In2.Cu")
		(net "P3E_CPU0_PE2_SS_C_TXP<8>")
	)
	(segment
		(start 82.628486 -28.382468)
		(end 82.628232 -28.382468)
		(width 0.127)
		(layer "In2.Cu")
		(net "P3E_CPU0_PE2_SS_C_TXP<8>")
	)
	(segment
		(start 109.452664 5.959348)
		(end 107.780836 4.788154)
		(width 0.127)
		(layer "In2.Cu")
		(net "P3E_CPU0_PE2_SS_C_TXP<8>")
	)
	(segment
		(start 109.550962 6.204966)
		(end 109.552994 6.20014)
		(width 0.127)
		(layer "In2.Cu")
		(net "P3E_CPU0_PE2_SS_C_TXP<8>")
	)
	(arc
		(start 91.461844 -12.640564)
		(mid 91.06592 -13.233296)
		(end 90.92692 -13.932408)
		(width 0.127)
		(layer "In2.Cu")
		(net "P3E_CPU0_PE2_SS_C_TXP<8>")
	)
	(arc
		(start 109.242606 7.742682)
		(mid 109.517772 7.589277)
		(end 109.621066 7.291578)
		(width 0.127)
		(layer "In2.Cu")
		(net "P3E_CPU0_PE2_SS_C_TXP<8>")
	)
	(arc
		(start 91.486228 -8.28294)
		(mid 91.797784 -8.748938)
		(end 91.90736 -9.298686)
		(width 0.127)
		(layer "In2.Cu")
		(net "P3E_CPU0_PE2_SS_C_TXP<8>")
	)
	(arc
		(start 82.995008 -27.840178)
		(mid 82.946853 -28.124001)
		(end 82.741516 -28.325826)
		(width 0.127)
		(layer "In2.Cu")
		(net "P3E_CPU0_PE2_SS_C_TXP<8>")
	)
	(arc
		(start 82.628232 -28.382468)
		(mid 82.531284 -28.389445)
		(end 82.457798 -28.325826)
		(width 0.127)
		(layer "In2.Cu")
		(net "P3E_CPU0_PE2_SS_C_TXP<8>")
	)
	(arc
		(start 91.90736 -11.87958)
		(mid 91.849235 -12.171325)
		(end 91.68384 -12.418568)
		(width 0.127)
		(layer "In2.Cu")
		(net "P3E_CPU0_PE2_SS_C_TXP<8>")
	)
	(arc
		(start 90.93962 -7.115302)
		(mid 91.053387 -7.688661)
		(end 91.378024 -8.174736)
		(width 0.127)
		(layer "In2.Cu")
		(net "P3E_CPU0_PE2_SS_C_TXP<8>")
	)
	(arc
		(start 82.949288 -26.616406)
		(mid 82.938914 -27.229534)
		(end 82.995008 -27.840178)
		(width 0.127)
		(layer "In2.Cu")
		(net "P3E_CPU0_PE2_SS_C_TXP<8>")
	)
	(segment
		(start 95.827342 10.373868)
		(end 95.827342 8.2296)
		(width 0.127)
		(layer "F.Cu")
		(net "P3E_CPU0_PE2_SS_C_TXP<7>")
	)
	(segment
		(start 95.827596 10.373868)
		(end 95.827342 10.373868)
		(width 0.127)
		(layer "F.Cu")
		(net "P3E_CPU0_PE2_SS_C_TXP<7>")
	)
	(segment
		(start 95.827596 10.383266)
		(end 95.827596 10.373868)
		(width 0.127)
		(layer "F.Cu")
		(net "P3E_CPU0_PE2_SS_C_TXP<7>")
	)
	(segment
		(start 95.579946 12.133072)
		(end 95.579946 10.980674)
		(width 0.127)
		(layer "F.Cu")
		(net "P3E_CPU0_PE2_SS_C_TXP<7>")
	)
	(segment
		(start 95.70339 10.682224)
		(end 95.703644 10.68197)
		(width 0.127)
		(layer "F.Cu")
		(net "P3E_CPU0_PE2_SS_C_TXP<7>")
	)
	(via
		(at 95.440754 7.702042)
		(size 0.508)
		(drill 0.254)
		(layers "F.Cu" "B.Cu")
		(net "P3E_CPU0_PE2_SS_C_TXP<7>")
	)
	(arc
		(start 95.579946 10.980674)
		(mid 95.612031 10.819194)
		(end 95.70339 10.682224)
		(width 0.127)
		(layer "F.Cu")
		(net "P3E_CPU0_PE2_SS_C_TXP<7>")
	)
	(arc
		(start 95.827342 8.2296)
		(mid 95.720345 7.90259)
		(end 95.440754 7.702042)
		(width 0.127)
		(layer "F.Cu")
		(net "P3E_CPU0_PE2_SS_C_TXP<7>")
	)
	(arc
		(start 95.703644 10.68197)
		(mid 95.795299 10.544938)
		(end 95.827596 10.383266)
		(width 0.127)
		(layer "F.Cu")
		(net "P3E_CPU0_PE2_SS_C_TXP<7>")
	)
	(segment
		(start 87.001096 -6.325616)
		(end 87.58682 -5.48894)
		(width 0.127)
		(layer "In2.Cu")
		(net "P3E_CPU0_PE2_SS_C_TXP<7>")
	)
	(segment
		(start 77.079602 -29.570426)
		(end 77.457808 -28.814522)
		(width 0.127)
		(layer "In2.Cu")
		(net "P3E_CPU0_PE2_SS_C_TXP<7>")
	)
	(segment
		(start 77.16647 -26.6319)
		(end 77.37729 -26.181812)
		(width 0.127)
		(layer "In2.Cu")
		(net "P3E_CPU0_PE2_SS_C_TXP<7>")
	)
	(segment
		(start 77.401166 -28.644088)
		(end 77.400912 -28.644088)
		(width 0.127)
		(layer "In2.Cu")
		(net "P3E_CPU0_PE2_SS_C_TXP<7>")
	)
	(segment
		(start 87.486998 -8.28294)
		(end 87.378794 -8.174736)
		(width 0.127)
		(layer "In2.Cu")
		(net "P3E_CPU0_PE2_SS_C_TXP<7>")
	)
	(segment
		(start 87.90813 -11.87958)
		(end 87.90813 -9.298686)
		(width 0.127)
		(layer "In2.Cu")
		(net "P3E_CPU0_PE2_SS_C_TXP<7>")
	)
	(segment
		(start 91.438222 -2.792222)
		(end 95.422466 2.897124)
		(width 0.127)
		(layer "In2.Cu")
		(net "P3E_CPU0_PE2_SS_C_TXP<7>")
	)
	(segment
		(start 95.820484 6.22935)
		(end 95.820484 6.651752)
		(width 0.127)
		(layer "In2.Cu")
		(net "P3E_CPU0_PE2_SS_C_TXP<7>")
	)
	(segment
		(start 77.79512 -25.889712)
		(end 80.185514 -24.215852)
		(width 0.127)
		(layer "In2.Cu")
		(net "P3E_CPU0_PE2_SS_C_TXP<7>")
	)
	(segment
		(start 86.94039 -6.670548)
		(end 87.001096 -6.325616)
		(width 0.127)
		(layer "In2.Cu")
		(net "P3E_CPU0_PE2_SS_C_TXP<7>")
	)
	(segment
		(start 87.58682 -5.48894)
		(end 91.438222 -2.792222)
		(width 0.127)
		(layer "In2.Cu")
		(net "P3E_CPU0_PE2_SS_C_TXP<7>")
	)
	(segment
		(start 86.865968 -14.67485)
		(end 86.92769 -14.325854)
		(width 0.127)
		(layer "In2.Cu")
		(net "P3E_CPU0_PE2_SS_C_TXP<7>")
	)
	(segment
		(start 87.462614 -12.640564)
		(end 87.68461 -12.418568)
		(width 0.127)
		(layer "In2.Cu")
		(net "P3E_CPU0_PE2_SS_C_TXP<7>")
	)
	(segment
		(start 86.92769 -14.325854)
		(end 86.92769 -13.932408)
		(width 0.127)
		(layer "In2.Cu")
		(net "P3E_CPU0_PE2_SS_C_TXP<7>")
	)
	(segment
		(start 80.185514 -24.215852)
		(end 86.865968 -14.67485)
		(width 0.127)
		(layer "In2.Cu")
		(net "P3E_CPU0_PE2_SS_C_TXP<7>")
	)
	(segment
		(start 77.400912 -28.644088)
		(end 77.287374 -28.587192)
		(width 0.127)
		(layer "In2.Cu")
		(net "P3E_CPU0_PE2_SS_C_TXP<7>")
	)
	(segment
		(start 77.37729 -26.181812)
		(end 77.79512 -25.889712)
		(width 0.127)
		(layer "In2.Cu")
		(net "P3E_CPU0_PE2_SS_C_TXP<7>")
	)
	(segment
		(start 95.422466 2.897124)
		(end 95.803466 4.864354)
		(width 0.127)
		(layer "In2.Cu")
		(net "P3E_CPU0_PE2_SS_C_TXP<7>")
	)
	(segment
		(start 86.94039 -7.115302)
		(end 86.94039 -6.670548)
		(width 0.127)
		(layer "In2.Cu")
		(net "P3E_CPU0_PE2_SS_C_TXP<7>")
	)
	(arc
		(start 77.287374 -28.587192)
		(mid 76.985135 -28.306403)
		(end 76.88199 -27.90698)
		(width 0.127)
		(layer "In2.Cu")
		(net "P3E_CPU0_PE2_SS_C_TXP<7>")
	)
	(arc
		(start 87.378794 -8.174736)
		(mid 87.05426 -7.688618)
		(end 86.94039 -7.115302)
		(width 0.127)
		(layer "In2.Cu")
		(net "P3E_CPU0_PE2_SS_C_TXP<7>")
	)
	(arc
		(start 95.82277 5.524246)
		(mid 95.799168 5.876725)
		(end 95.820484 6.22935)
		(width 0.127)
		(layer "In2.Cu")
		(net "P3E_CPU0_PE2_SS_C_TXP<7>")
	)
	(arc
		(start 95.820484 6.651752)
		(mid 95.820166 6.951346)
		(end 95.819214 7.250938)
		(width 0.127)
		(layer "In2.Cu")
		(net "P3E_CPU0_PE2_SS_C_TXP<7>")
	)
	(arc
		(start 86.92769 -13.932408)
		(mid 87.066714 -13.233306)
		(end 87.462614 -12.640564)
		(width 0.127)
		(layer "In2.Cu")
		(net "P3E_CPU0_PE2_SS_C_TXP<7>")
	)
	(arc
		(start 77.457808 -28.814522)
		(mid 77.464785 -28.717574)
		(end 77.401166 -28.644088)
		(width 0.127)
		(layer "In2.Cu")
		(net "P3E_CPU0_PE2_SS_C_TXP<7>")
	)
	(arc
		(start 87.90813 -9.298686)
		(mid 87.798588 -8.748924)
		(end 87.486998 -8.28294)
		(width 0.127)
		(layer "In2.Cu")
		(net "P3E_CPU0_PE2_SS_C_TXP<7>")
	)
	(arc
		(start 87.68461 -12.418568)
		(mid 87.849927 -12.171293)
		(end 87.90813 -11.87958)
		(width 0.127)
		(layer "In2.Cu")
		(net "P3E_CPU0_PE2_SS_C_TXP<7>")
	)
	(arc
		(start 95.803466 4.864354)
		(mid 95.839838 5.193518)
		(end 95.82277 5.524246)
		(width 0.127)
		(layer "In2.Cu")
		(net "P3E_CPU0_PE2_SS_C_TXP<7>")
	)
	(arc
		(start 95.819214 7.250938)
		(mid 95.716072 7.548765)
		(end 95.440754 7.702042)
		(width 0.127)
		(layer "In2.Cu")
		(net "P3E_CPU0_PE2_SS_C_TXP<7>")
	)
	(arc
		(start 76.88199 -27.90698)
		(mid 76.953975 -27.253766)
		(end 77.16647 -26.6319)
		(width 0.127)
		(layer "In2.Cu")
		(net "P3E_CPU0_PE2_SS_C_TXP<7>")
	)
	(segment
		(start 93.218 8.426958)
		(end 93.218 8.001)
		(width 0.127)
		(layer "F.Cu")
		(net "P3E_CPU0_PE2_SS_C_TXP<6>")
	)
	(segment
		(start 93.42755 10.383266)
		(end 93.42755 10.373868)
		(width 0.127)
		(layer "F.Cu")
		(net "P3E_CPU0_PE2_SS_C_TXP<6>")
	)
	(segment
		(start 92.919042 7.702042)
		(end 92.849954 7.702042)
		(width 0.127)
		(layer "F.Cu")
		(net "P3E_CPU0_PE2_SS_C_TXP<6>")
	)
	(segment
		(start 93.1799 12.133072)
		(end 93.1799 10.980674)
		(width 0.127)
		(layer "F.Cu")
		(net "P3E_CPU0_PE2_SS_C_TXP<6>")
	)
	(segment
		(start 93.303344 10.682224)
		(end 93.303598 10.68197)
		(width 0.127)
		(layer "F.Cu")
		(net "P3E_CPU0_PE2_SS_C_TXP<6>")
	)
	(via
		(at 92.849954 7.702042)
		(size 0.508)
		(drill 0.254)
		(layers "F.Cu" "B.Cu")
		(net "P3E_CPU0_PE2_SS_C_TXP<6>")
	)
	(arc
		(start 93.1799 10.980674)
		(mid 93.211985 10.819194)
		(end 93.303344 10.682224)
		(width 0.127)
		(layer "F.Cu")
		(net "P3E_CPU0_PE2_SS_C_TXP<6>")
	)
	(arc
		(start 93.224858 8.491474)
		(mid 93.219674 8.459402)
		(end 93.218 8.426958)
		(width 0.127)
		(layer "F.Cu")
		(net "P3E_CPU0_PE2_SS_C_TXP<6>")
	)
	(arc
		(start 93.218 8.001)
		(mid 93.130437 7.789605)
		(end 92.919042 7.702042)
		(width 0.127)
		(layer "F.Cu")
		(net "P3E_CPU0_PE2_SS_C_TXP<6>")
	)
	(arc
		(start 93.303598 10.68197)
		(mid 93.395253 10.544938)
		(end 93.42755 10.383266)
		(width 0.127)
		(layer "F.Cu")
		(net "P3E_CPU0_PE2_SS_C_TXP<6>")
	)
	(arc
		(start 93.42755 10.373868)
		(mid 93.376702 9.427234)
		(end 93.224858 8.491474)
		(width 0.127)
		(layer "F.Cu")
		(net "P3E_CPU0_PE2_SS_C_TXP<6>")
	)
	(segment
		(start 78.296008 -21.409152)
		(end 73.349866 -26.265632)
		(width 0.127)
		(layer "In2.Cu")
		(net "P3E_CPU0_PE2_SS_C_TXP<6>")
	)
	(segment
		(start 83.90763 -9.298686)
		(end 83.90763 -11.87958)
		(width 0.127)
		(layer "In2.Cu")
		(net "P3E_CPU0_PE2_SS_C_TXP<6>")
	)
	(segment
		(start 83.010248 -6.689598)
		(end 82.93989 -7.088632)
		(width 0.127)
		(layer "In2.Cu")
		(net "P3E_CPU0_PE2_SS_C_TXP<6>")
	)
	(segment
		(start 93.156786 4.577588)
		(end 93.156532 4.577334)
		(width 0.127)
		(layer "In2.Cu")
		(net "P3E_CPU0_PE2_SS_C_TXP<6>")
	)
	(segment
		(start 73.288144 -28.587192)
		(end 73.401682 -28.644088)
		(width 0.127)
		(layer "In2.Cu")
		(net "P3E_CPU0_PE2_SS_C_TXP<6>")
	)
	(segment
		(start 93.229684 6.651752)
		(end 93.229684 6.22935)
		(width 0.127)
		(layer "In2.Cu")
		(net "P3E_CPU0_PE2_SS_C_TXP<6>")
	)
	(segment
		(start 93.15704 4.577334)
		(end 93.156786 4.57708)
		(width 0.127)
		(layer "In2.Cu")
		(net "P3E_CPU0_PE2_SS_C_TXP<6>")
	)
	(segment
		(start 82.816446 -14.952726)
		(end 78.296008 -21.409152)
		(width 0.127)
		(layer "In2.Cu")
		(net "P3E_CPU0_PE2_SS_C_TXP<6>")
	)
	(segment
		(start 73.458578 -28.814522)
		(end 73.080372 -29.570426)
		(width 0.127)
		(layer "In2.Cu")
		(net "P3E_CPU0_PE2_SS_C_TXP<6>")
	)
	(segment
		(start 82.871818 -14.639036)
		(end 82.816446 -14.952726)
		(width 0.127)
		(layer "In2.Cu")
		(net "P3E_CPU0_PE2_SS_C_TXP<6>")
	)
	(segment
		(start 83.68411 -12.418568)
		(end 83.462114 -12.640564)
		(width 0.127)
		(layer "In2.Cu")
		(net "P3E_CPU0_PE2_SS_C_TXP<6>")
	)
	(segment
		(start 83.378294 -8.174736)
		(end 83.486498 -8.28294)
		(width 0.127)
		(layer "In2.Cu")
		(net "P3E_CPU0_PE2_SS_C_TXP<6>")
	)
	(segment
		(start 93.156786 4.57708)
		(end 92.995496 3.170174)
		(width 0.127)
		(layer "In2.Cu")
		(net "P3E_CPU0_PE2_SS_C_TXP<6>")
	)
	(segment
		(start 82.92719 -14.325854)
		(end 82.871818 -14.639036)
		(width 0.127)
		(layer "In2.Cu")
		(net "P3E_CPU0_PE2_SS_C_TXP<6>")
	)
	(segment
		(start 89.701878 -1.534922)
		(end 83.654392 -5.769864)
		(width 0.127)
		(layer "In2.Cu")
		(net "P3E_CPU0_PE2_SS_C_TXP<6>")
	)
	(segment
		(start 73.328784 -26.287476)
		(end 73.16724 -26.6319)
		(width 0.127)
		(layer "In2.Cu")
		(net "P3E_CPU0_PE2_SS_C_TXP<6>")
	)
	(segment
		(start 83.654392 -5.769864)
		(end 83.010248 -6.689598)
		(width 0.127)
		(layer "In2.Cu")
		(net "P3E_CPU0_PE2_SS_C_TXP<6>")
	)
	(segment
		(start 92.995496 3.170174)
		(end 89.701878 -1.534922)
		(width 0.127)
		(layer "In2.Cu")
		(net "P3E_CPU0_PE2_SS_C_TXP<6>")
	)
	(segment
		(start 93.156532 4.577334)
		(end 93.15704 4.577334)
		(width 0.127)
		(layer "In2.Cu")
		(net "P3E_CPU0_PE2_SS_C_TXP<6>")
	)
	(segment
		(start 93.212412 4.864354)
		(end 93.156786 4.577588)
		(width 0.127)
		(layer "In2.Cu")
		(net "P3E_CPU0_PE2_SS_C_TXP<6>")
	)
	(segment
		(start 82.92719 -13.932408)
		(end 82.92719 -14.325854)
		(width 0.127)
		(layer "In2.Cu")
		(net "P3E_CPU0_PE2_SS_C_TXP<6>")
	)
	(segment
		(start 73.349866 -26.265632)
		(end 73.328784 -26.287476)
		(width 0.127)
		(layer "In2.Cu")
		(net "P3E_CPU0_PE2_SS_C_TXP<6>")
	)
	(segment
		(start 73.401682 -28.644088)
		(end 73.401936 -28.644088)
		(width 0.127)
		(layer "In2.Cu")
		(net "P3E_CPU0_PE2_SS_C_TXP<6>")
	)
	(arc
		(start 83.90763 -11.87958)
		(mid 83.849505 -12.171325)
		(end 83.68411 -12.418568)
		(width 0.127)
		(layer "In2.Cu")
		(net "P3E_CPU0_PE2_SS_C_TXP<6>")
	)
	(arc
		(start 93.229684 6.22935)
		(mid 93.208358 5.876725)
		(end 93.23197 5.524246)
		(width 0.127)
		(layer "In2.Cu")
		(net "P3E_CPU0_PE2_SS_C_TXP<6>")
	)
	(arc
		(start 72.88276 -27.90698)
		(mid 72.985952 -28.306375)
		(end 73.288144 -28.587192)
		(width 0.127)
		(layer "In2.Cu")
		(net "P3E_CPU0_PE2_SS_C_TXP<6>")
	)
	(arc
		(start 83.462114 -12.640564)
		(mid 83.06619 -13.233296)
		(end 82.92719 -13.932408)
		(width 0.127)
		(layer "In2.Cu")
		(net "P3E_CPU0_PE2_SS_C_TXP<6>")
	)
	(arc
		(start 73.401936 -28.644088)
		(mid 73.465555 -28.717574)
		(end 73.458578 -28.814522)
		(width 0.127)
		(layer "In2.Cu")
		(net "P3E_CPU0_PE2_SS_C_TXP<6>")
	)
	(arc
		(start 92.849954 7.702042)
		(mid 93.12512 7.548637)
		(end 93.228414 7.250938)
		(width 0.127)
		(layer "In2.Cu")
		(net "P3E_CPU0_PE2_SS_C_TXP<6>")
	)
	(arc
		(start 73.16724 -26.6319)
		(mid 72.95474 -27.253765)
		(end 72.88276 -27.90698)
		(width 0.127)
		(layer "In2.Cu")
		(net "P3E_CPU0_PE2_SS_C_TXP<6>")
	)
	(arc
		(start 93.23197 5.524246)
		(mid 93.248917 5.193507)
		(end 93.212412 4.864354)
		(width 0.127)
		(layer "In2.Cu")
		(net "P3E_CPU0_PE2_SS_C_TXP<6>")
	)
	(arc
		(start 82.93989 -7.088632)
		(mid 83.048482 -7.676343)
		(end 83.378294 -8.174736)
		(width 0.127)
		(layer "In2.Cu")
		(net "P3E_CPU0_PE2_SS_C_TXP<6>")
	)
	(arc
		(start 93.228414 7.250938)
		(mid 93.228732 6.951344)
		(end 93.229684 6.651752)
		(width 0.127)
		(layer "In2.Cu")
		(net "P3E_CPU0_PE2_SS_C_TXP<6>")
	)
	(arc
		(start 83.486498 -8.28294)
		(mid 83.798054 -8.748938)
		(end 83.90763 -9.298686)
		(width 0.127)
		(layer "In2.Cu")
		(net "P3E_CPU0_PE2_SS_C_TXP<6>")
	)
	(segment
		(start 91.027504 10.383266)
		(end 91.027504 9.525)
		(width 0.127)
		(layer "F.Cu")
		(net "P3E_CPU0_PE2_SS_C_TXP<5>")
	)
	(segment
		(start 90.328242 7.702042)
		(end 90.259154 7.702042)
		(width 0.127)
		(layer "F.Cu")
		(net "P3E_CPU0_PE2_SS_C_TXP<5>")
	)
	(segment
		(start 90.903298 10.682224)
		(end 90.903552 10.68197)
		(width 0.127)
		(layer "F.Cu")
		(net "P3E_CPU0_PE2_SS_C_TXP<5>")
	)
	(segment
		(start 90.779854 12.133072)
		(end 90.779854 10.980674)
		(width 0.127)
		(layer "F.Cu")
		(net "P3E_CPU0_PE2_SS_C_TXP<5>")
	)
	(segment
		(start 90.6272 8.2296)
		(end 90.6272 8.001)
		(width 0.127)
		(layer "F.Cu")
		(net "P3E_CPU0_PE2_SS_C_TXP<5>")
	)
	(via
		(at 90.259154 7.702042)
		(size 0.508)
		(drill 0.254)
		(layers "F.Cu" "B.Cu")
		(net "P3E_CPU0_PE2_SS_C_TXP<5>")
	)
	(arc
		(start 90.6272 8.001)
		(mid 90.539637 7.789605)
		(end 90.328242 7.702042)
		(width 0.127)
		(layer "F.Cu")
		(net "P3E_CPU0_PE2_SS_C_TXP<5>")
	)
	(arc
		(start 90.779854 10.980674)
		(mid 90.811939 10.819194)
		(end 90.903298 10.682224)
		(width 0.127)
		(layer "F.Cu")
		(net "P3E_CPU0_PE2_SS_C_TXP<5>")
	)
	(arc
		(start 91.027504 9.525)
		(mid 90.982849 9.279465)
		(end 90.854784 9.06526)
		(width 0.127)
		(layer "F.Cu")
		(net "P3E_CPU0_PE2_SS_C_TXP<5>")
	)
	(arc
		(start 90.854784 9.06526)
		(mid 90.666965 8.731133)
		(end 90.628724 8.349742)
		(width 0.127)
		(layer "F.Cu")
		(net "P3E_CPU0_PE2_SS_C_TXP<5>")
	)
	(arc
		(start 90.628724 8.349742)
		(mid 90.631527 8.289626)
		(end 90.6272 8.2296)
		(width 0.127)
		(layer "F.Cu")
		(net "P3E_CPU0_PE2_SS_C_TXP<5>")
	)
	(arc
		(start 90.903552 10.68197)
		(mid 90.995207 10.544938)
		(end 91.027504 10.383266)
		(width 0.127)
		(layer "F.Cu")
		(net "P3E_CPU0_PE2_SS_C_TXP<5>")
	)
	(segment
		(start 79.0067 -6.839458)
		(end 78.93431 -7.251446)
		(width 0.127)
		(layer "In2.Cu")
		(net "P3E_CPU0_PE2_SS_C_TXP<5>")
	)
	(segment
		(start 90.616532 4.770882)
		(end 90.624152 4.379976)
		(width 0.127)
		(layer "In2.Cu")
		(net "P3E_CPU0_PE2_SS_C_TXP<5>")
	)
	(segment
		(start 68.905882 -27.333956)
		(end 68.882514 -27.900122)
		(width 0.127)
		(layer "In2.Cu")
		(net "P3E_CPU0_PE2_SS_C_TXP<5>")
	)
	(segment
		(start 78.871318 -14.63675)
		(end 74.375264 -21.056854)
		(width 0.127)
		(layer "In2.Cu")
		(net "P3E_CPU0_PE2_SS_C_TXP<5>")
	)
	(segment
		(start 78.932786 -13.894816)
		(end 78.93304 -13.894562)
		(width 0.127)
		(layer "In2.Cu")
		(net "P3E_CPU0_PE2_SS_C_TXP<5>")
	)
	(segment
		(start 78.442566 -12.828778)
		(end 78.525878 -12.911836)
		(width 0.127)
		(layer "In2.Cu")
		(net "P3E_CPU0_PE2_SS_C_TXP<5>")
	)
	(segment
		(start 90.621358 4.864354)
		(end 90.621104 4.8641)
		(width 0.127)
		(layer "In2.Cu")
		(net "P3E_CPU0_PE2_SS_C_TXP<5>")
	)
	(segment
		(start 69.401182 -28.644088)
		(end 69.401436 -28.644088)
		(width 0.127)
		(layer "In2.Cu")
		(net "P3E_CPU0_PE2_SS_C_TXP<5>")
	)
	(segment
		(start 69.287644 -28.587192)
		(end 69.401182 -28.644088)
		(width 0.127)
		(layer "In2.Cu")
		(net "P3E_CPU0_PE2_SS_C_TXP<5>")
	)
	(segment
		(start 78.93304 -14.288008)
		(end 78.871318 -14.63675)
		(width 0.127)
		(layer "In2.Cu")
		(net "P3E_CPU0_PE2_SS_C_TXP<5>")
	)
	(segment
		(start 78.93304 -13.894562)
		(end 78.93304 -14.288008)
		(width 0.127)
		(layer "In2.Cu")
		(net "P3E_CPU0_PE2_SS_C_TXP<5>")
	)
	(segment
		(start 88.03767 -0.28956)
		(end 79.318612 -6.394196)
		(width 0.127)
		(layer "In2.Cu")
		(net "P3E_CPU0_PE2_SS_C_TXP<5>")
	)
	(segment
		(start 90.637614 7.250938)
		(end 90.637614 6.549644)
		(width 0.127)
		(layer "In2.Cu")
		(net "P3E_CPU0_PE2_SS_C_TXP<5>")
	)
	(segment
		(start 69.20484 -26.07691)
		(end 68.905882 -27.333956)
		(width 0.127)
		(layer "In2.Cu")
		(net "P3E_CPU0_PE2_SS_C_TXP<5>")
	)
	(segment
		(start 90.394028 3.075178)
		(end 88.03767 -0.28956)
		(width 0.127)
		(layer "In2.Cu")
		(net "P3E_CPU0_PE2_SS_C_TXP<5>")
	)
	(segment
		(start 78.93431 -7.251446)
		(end 78.93431 -7.2771)
		(width 0.127)
		(layer "In2.Cu")
		(net "P3E_CPU0_PE2_SS_C_TXP<5>")
	)
	(segment
		(start 90.621104 4.8641)
		(end 90.618818 4.835652)
		(width 0.127)
		(layer "In2.Cu")
		(net "P3E_CPU0_PE2_SS_C_TXP<5>")
	)
	(segment
		(start 79.318612 -6.394196)
		(end 79.0067 -6.839458)
		(width 0.127)
		(layer "In2.Cu")
		(net "P3E_CPU0_PE2_SS_C_TXP<5>")
	)
	(segment
		(start 77.946504 -9.472676)
		(end 77.946504 -11.63066)
		(width 0.127)
		(layer "In2.Cu")
		(net "P3E_CPU0_PE2_SS_C_TXP<5>")
	)
	(segment
		(start 74.371454 -21.062188)
		(end 69.20484 -26.07691)
		(width 0.127)
		(layer "In2.Cu")
		(net "P3E_CPU0_PE2_SS_C_TXP<5>")
	)
	(segment
		(start 90.624152 4.379976)
		(end 90.394028 3.075178)
		(width 0.127)
		(layer "In2.Cu")
		(net "P3E_CPU0_PE2_SS_C_TXP<5>")
	)
	(segment
		(start 74.375264 -21.056854)
		(end 74.371454 -21.062188)
		(width 0.127)
		(layer "In2.Cu")
		(net "P3E_CPU0_PE2_SS_C_TXP<5>")
	)
	(segment
		(start 69.458078 -28.814522)
		(end 69.079872 -29.570426)
		(width 0.127)
		(layer "In2.Cu")
		(net "P3E_CPU0_PE2_SS_C_TXP<5>")
	)
	(segment
		(start 78.702662 -7.836408)
		(end 78.56855 -7.97052)
		(width 0.127)
		(layer "In2.Cu")
		(net "P3E_CPU0_PE2_SS_C_TXP<5>")
	)
	(arc
		(start 90.64117 6.2484)
		(mid 90.617488 5.886324)
		(end 90.64117 5.524246)
		(width 0.127)
		(layer "In2.Cu")
		(net "P3E_CPU0_PE2_SS_C_TXP<5>")
	)
	(arc
		(start 90.64117 5.524246)
		(mid 90.657994 5.193497)
		(end 90.621358 4.864354)
		(width 0.127)
		(layer "In2.Cu")
		(net "P3E_CPU0_PE2_SS_C_TXP<5>")
	)
	(arc
		(start 78.93431 -7.2771)
		(mid 78.874102 -7.579786)
		(end 78.702662 -7.836408)
		(width 0.127)
		(layer "In2.Cu")
		(net "P3E_CPU0_PE2_SS_C_TXP<5>")
	)
	(arc
		(start 90.637614 6.549644)
		(mid 90.641447 6.399046)
		(end 90.64117 6.2484)
		(width 0.127)
		(layer "In2.Cu")
		(net "P3E_CPU0_PE2_SS_C_TXP<5>")
	)
	(arc
		(start 90.259154 7.702042)
		(mid 90.53432 7.548637)
		(end 90.637614 7.250938)
		(width 0.127)
		(layer "In2.Cu")
		(net "P3E_CPU0_PE2_SS_C_TXP<5>")
	)
	(arc
		(start 69.401436 -28.644088)
		(mid 69.465055 -28.717574)
		(end 69.458078 -28.814522)
		(width 0.127)
		(layer "In2.Cu")
		(net "P3E_CPU0_PE2_SS_C_TXP<5>")
	)
	(arc
		(start 78.56855 -7.97052)
		(mid 78.108152 -8.659743)
		(end 77.946504 -9.472676)
		(width 0.127)
		(layer "In2.Cu")
		(net "P3E_CPU0_PE2_SS_C_TXP<5>")
	)
	(arc
		(start 90.618818 4.835652)
		(mid 90.616843 4.803296)
		(end 90.616532 4.770882)
		(width 0.127)
		(layer "In2.Cu")
		(net "P3E_CPU0_PE2_SS_C_TXP<5>")
	)
	(arc
		(start 78.525878 -12.911836)
		(mid 78.827087 -13.36286)
		(end 78.932786 -13.894816)
		(width 0.127)
		(layer "In2.Cu")
		(net "P3E_CPU0_PE2_SS_C_TXP<5>")
	)
	(arc
		(start 68.882514 -27.900122)
		(mid 68.983706 -28.303422)
		(end 69.287644 -28.587192)
		(width 0.127)
		(layer "In2.Cu")
		(net "P3E_CPU0_PE2_SS_C_TXP<5>")
	)
	(arc
		(start 77.946504 -11.63066)
		(mid 78.075398 -12.279034)
		(end 78.442566 -12.828778)
		(width 0.127)
		(layer "In2.Cu")
		(net "P3E_CPU0_PE2_SS_C_TXP<5>")
	)
	(segment
		(start 88.0364 8.147304)
		(end 88.0364 8.001)
		(width 0.127)
		(layer "F.Cu")
		(net "P3E_CPU0_PE2_SS_C_TXP<4>")
	)
	(segment
		(start 88.503252 10.682224)
		(end 88.503506 10.68197)
		(width 0.127)
		(layer "F.Cu")
		(net "P3E_CPU0_PE2_SS_C_TXP<4>")
	)
	(segment
		(start 88.627458 10.383266)
		(end 88.627458 9.445244)
		(width 0.127)
		(layer "F.Cu")
		(net "P3E_CPU0_PE2_SS_C_TXP<4>")
	)
	(segment
		(start 87.737442 7.702042)
		(end 87.668354 7.702042)
		(width 0.127)
		(layer "F.Cu")
		(net "P3E_CPU0_PE2_SS_C_TXP<4>")
	)
	(segment
		(start 88.627458 9.445244)
		(end 88.627204 9.445498)
		(width 0.127)
		(layer "F.Cu")
		(net "P3E_CPU0_PE2_SS_C_TXP<4>")
	)
	(segment
		(start 88.328754 8.724646)
		(end 88.237568 8.63346)
		(width 0.127)
		(layer "F.Cu")
		(net "P3E_CPU0_PE2_SS_C_TXP<4>")
	)
	(segment
		(start 88.379808 12.133072)
		(end 88.379808 10.980674)
		(width 0.127)
		(layer "F.Cu")
		(net "P3E_CPU0_PE2_SS_C_TXP<4>")
	)
	(via
		(at 87.668354 7.702042)
		(size 0.508)
		(drill 0.254)
		(layers "F.Cu" "B.Cu")
		(net "P3E_CPU0_PE2_SS_C_TXP<4>")
	)
	(arc
		(start 88.503506 10.68197)
		(mid 88.595161 10.544938)
		(end 88.627458 10.383266)
		(width 0.127)
		(layer "F.Cu")
		(net "P3E_CPU0_PE2_SS_C_TXP<4>")
	)
	(arc
		(start 88.0364 8.001)
		(mid 87.948837 7.789605)
		(end 87.737442 7.702042)
		(width 0.127)
		(layer "F.Cu")
		(net "P3E_CPU0_PE2_SS_C_TXP<4>")
	)
	(arc
		(start 88.379808 10.980674)
		(mid 88.411893 10.819194)
		(end 88.503252 10.682224)
		(width 0.127)
		(layer "F.Cu")
		(net "P3E_CPU0_PE2_SS_C_TXP<4>")
	)
	(arc
		(start 88.237568 8.63346)
		(mid 88.088667 8.41038)
		(end 88.0364 8.147304)
		(width 0.127)
		(layer "F.Cu")
		(net "P3E_CPU0_PE2_SS_C_TXP<4>")
	)
	(arc
		(start 88.627204 9.445498)
		(mid 88.549697 9.055374)
		(end 88.328754 8.724646)
		(width 0.127)
		(layer "F.Cu")
		(net "P3E_CPU0_PE2_SS_C_TXP<4>")
	)
	(segment
		(start 86.094824 0.710692)
		(end 87.462868 3.264916)
		(width 0.127)
		(layer "In2.Cu")
		(net "P3E_CPU0_PE2_SS_C_TXP<4>")
	)
	(segment
		(start 67.601846 -22.99843)
		(end 67.603624 -22.99589)
		(width 0.127)
		(layer "In2.Cu")
		(net "P3E_CPU0_PE2_SS_C_TXP<4>")
	)
	(segment
		(start 65.400936 -28.644088)
		(end 65.400682 -28.644088)
		(width 0.127)
		(layer "In2.Cu")
		(net "P3E_CPU0_PE2_SS_C_TXP<4>")
	)
	(segment
		(start 80.805528 -2.230628)
		(end 82.259932 -1.974596)
		(width 0.127)
		(layer "In2.Cu")
		(net "P3E_CPU0_PE2_SS_C_TXP<4>")
	)
	(segment
		(start 65.175892 -26.611326)
		(end 67.601846 -22.99843)
		(width 0.127)
		(layer "In2.Cu")
		(net "P3E_CPU0_PE2_SS_C_TXP<4>")
	)
	(segment
		(start 82.259932 -1.974596)
		(end 86.094824 0.710692)
		(width 0.127)
		(layer "In2.Cu")
		(net "P3E_CPU0_PE2_SS_C_TXP<4>")
	)
	(segment
		(start 74.56805 -7.97052)
		(end 74.702162 -7.836408)
		(width 0.127)
		(layer "In2.Cu")
		(net "P3E_CPU0_PE2_SS_C_TXP<4>")
	)
	(segment
		(start 75.078336 -6.430772)
		(end 75.340464 -6.057138)
		(width 0.127)
		(layer "In2.Cu")
		(net "P3E_CPU0_PE2_SS_C_TXP<4>")
	)
	(segment
		(start 65.400682 -28.644088)
		(end 65.287144 -28.587192)
		(width 0.127)
		(layer "In2.Cu")
		(net "P3E_CPU0_PE2_SS_C_TXP<4>")
	)
	(segment
		(start 67.634866 -22.951694)
		(end 71.770494 -20.05584)
		(width 0.127)
		(layer "In2.Cu")
		(net "P3E_CPU0_PE2_SS_C_TXP<4>")
	)
	(segment
		(start 73.946004 -11.63066)
		(end 73.946004 -9.472676)
		(width 0.127)
		(layer "In2.Cu")
		(net "P3E_CPU0_PE2_SS_C_TXP<4>")
	)
	(segment
		(start 71.770494 -20.05584)
		(end 74.636884 -15.962376)
		(width 0.127)
		(layer "In2.Cu")
		(net "P3E_CPU0_PE2_SS_C_TXP<4>")
	)
	(segment
		(start 74.636884 -15.962376)
		(end 74.93254 -14.288008)
		(width 0.127)
		(layer "In2.Cu")
		(net "P3E_CPU0_PE2_SS_C_TXP<4>")
	)
	(segment
		(start 74.525378 -12.911836)
		(end 74.442066 -12.828778)
		(width 0.127)
		(layer "In2.Cu")
		(net "P3E_CPU0_PE2_SS_C_TXP<4>")
	)
	(segment
		(start 74.93381 -7.251446)
		(end 75.078336 -6.430772)
		(width 0.127)
		(layer "In2.Cu")
		(net "P3E_CPU0_PE2_SS_C_TXP<4>")
	)
	(segment
		(start 65.079372 -29.570426)
		(end 65.457578 -28.814522)
		(width 0.127)
		(layer "In2.Cu")
		(net "P3E_CPU0_PE2_SS_C_TXP<4>")
	)
	(segment
		(start 74.93381 -7.2771)
		(end 74.93381 -7.251446)
		(width 0.127)
		(layer "In2.Cu")
		(net "P3E_CPU0_PE2_SS_C_TXP<4>")
	)
	(segment
		(start 75.340464 -6.057138)
		(end 80.805528 -2.230628)
		(width 0.127)
		(layer "In2.Cu")
		(net "P3E_CPU0_PE2_SS_C_TXP<4>")
	)
	(segment
		(start 74.93254 -13.894562)
		(end 74.932286 -13.894816)
		(width 0.127)
		(layer "In2.Cu")
		(net "P3E_CPU0_PE2_SS_C_TXP<4>")
	)
	(segment
		(start 67.603624 -22.99589)
		(end 67.634866 -22.951694)
		(width 0.127)
		(layer "In2.Cu")
		(net "P3E_CPU0_PE2_SS_C_TXP<4>")
	)
	(segment
		(start 74.93254 -14.288008)
		(end 74.93254 -13.894562)
		(width 0.127)
		(layer "In2.Cu")
		(net "P3E_CPU0_PE2_SS_C_TXP<4>")
	)
	(arc
		(start 74.442066 -12.828778)
		(mid 74.074797 -12.279076)
		(end 73.946004 -11.63066)
		(width 0.127)
		(layer "In2.Cu")
		(net "P3E_CPU0_PE2_SS_C_TXP<4>")
	)
	(arc
		(start 88.07069 7.030466)
		(mid 88.060385 7.140879)
		(end 88.046814 7.250938)
		(width 0.127)
		(layer "In2.Cu")
		(net "P3E_CPU0_PE2_SS_C_TXP<4>")
	)
	(arc
		(start 88.030558 4.864354)
		(mid 88.067178 5.193497)
		(end 88.05037 5.524246)
		(width 0.127)
		(layer "In2.Cu")
		(net "P3E_CPU0_PE2_SS_C_TXP<4>")
	)
	(arc
		(start 88.05037 5.524246)
		(mid 88.026655 5.886324)
		(end 88.05037 6.2484)
		(width 0.127)
		(layer "In2.Cu")
		(net "P3E_CPU0_PE2_SS_C_TXP<4>")
	)
	(arc
		(start 65.16624 -26.6319)
		(mid 65.171046 -26.621604)
		(end 65.175892 -26.611326)
		(width 0.127)
		(layer "In2.Cu")
		(net "P3E_CPU0_PE2_SS_C_TXP<4>")
	)
	(arc
		(start 65.287144 -28.587192)
		(mid 64.984905 -28.306403)
		(end 64.88176 -27.90698)
		(width 0.127)
		(layer "In2.Cu")
		(net "P3E_CPU0_PE2_SS_C_TXP<4>")
	)
	(arc
		(start 73.946004 -9.472676)
		(mid 74.107669 -8.659751)
		(end 74.56805 -7.97052)
		(width 0.127)
		(layer "In2.Cu")
		(net "P3E_CPU0_PE2_SS_C_TXP<4>")
	)
	(arc
		(start 65.457578 -28.814522)
		(mid 65.464555 -28.717574)
		(end 65.400936 -28.644088)
		(width 0.127)
		(layer "In2.Cu")
		(net "P3E_CPU0_PE2_SS_C_TXP<4>")
	)
	(arc
		(start 74.702162 -7.836408)
		(mid 74.873625 -7.579795)
		(end 74.93381 -7.2771)
		(width 0.127)
		(layer "In2.Cu")
		(net "P3E_CPU0_PE2_SS_C_TXP<4>")
	)
	(arc
		(start 88.05037 6.2484)
		(mid 88.080991 6.638901)
		(end 88.07069 7.030466)
		(width 0.127)
		(layer "In2.Cu")
		(net "P3E_CPU0_PE2_SS_C_TXP<4>")
	)
	(arc
		(start 88.046814 7.250938)
		(mid 87.943672 7.548765)
		(end 87.668354 7.702042)
		(width 0.127)
		(layer "In2.Cu")
		(net "P3E_CPU0_PE2_SS_C_TXP<4>")
	)
	(arc
		(start 64.88176 -27.90698)
		(mid 64.953745 -27.253766)
		(end 65.16624 -26.6319)
		(width 0.127)
		(layer "In2.Cu")
		(net "P3E_CPU0_PE2_SS_C_TXP<4>")
	)
	(arc
		(start 87.462868 3.264916)
		(mid 87.806987 4.043241)
		(end 88.030558 4.864354)
		(width 0.127)
		(layer "In2.Cu")
		(net "P3E_CPU0_PE2_SS_C_TXP<4>")
	)
	(arc
		(start 74.932286 -13.894816)
		(mid 74.826585 -13.362861)
		(end 74.525378 -12.911836)
		(width 0.127)
		(layer "In2.Cu")
		(net "P3E_CPU0_PE2_SS_C_TXP<4>")
	)
	(segment
		(start 85.146642 7.702042)
		(end 85.077554 7.702042)
		(width 0.127)
		(layer "F.Cu")
		(net "P3E_CPU0_PE2_SS_C_TXP<3>")
	)
	(segment
		(start 85.980016 12.133072)
		(end 85.980016 10.980674)
		(width 0.127)
		(layer "F.Cu")
		(net "P3E_CPU0_PE2_SS_C_TXP<3>")
	)
	(segment
		(start 86.042754 9.029446)
		(end 85.646768 8.63346)
		(width 0.127)
		(layer "F.Cu")
		(net "P3E_CPU0_PE2_SS_C_TXP<3>")
	)
	(segment
		(start 86.10346 10.682224)
		(end 86.103714 10.68197)
		(width 0.127)
		(layer "F.Cu")
		(net "P3E_CPU0_PE2_SS_C_TXP<3>")
	)
	(segment
		(start 86.227666 10.383266)
		(end 86.227666 9.475978)
		(width 0.127)
		(layer "F.Cu")
		(net "P3E_CPU0_PE2_SS_C_TXP<3>")
	)
	(segment
		(start 85.4456 8.147304)
		(end 85.4456 8.001)
		(width 0.127)
		(layer "F.Cu")
		(net "P3E_CPU0_PE2_SS_C_TXP<3>")
	)
	(via
		(at 85.077554 7.702042)
		(size 0.508)
		(drill 0.254)
		(layers "F.Cu" "B.Cu")
		(net "P3E_CPU0_PE2_SS_C_TXP<3>")
	)
	(arc
		(start 85.980016 10.980674)
		(mid 86.012101 10.819194)
		(end 86.10346 10.682224)
		(width 0.127)
		(layer "F.Cu")
		(net "P3E_CPU0_PE2_SS_C_TXP<3>")
	)
	(arc
		(start 86.103714 10.68197)
		(mid 86.195369 10.544938)
		(end 86.227666 10.383266)
		(width 0.127)
		(layer "F.Cu")
		(net "P3E_CPU0_PE2_SS_C_TXP<3>")
	)
	(arc
		(start 85.4456 8.001)
		(mid 85.358037 7.789605)
		(end 85.146642 7.702042)
		(width 0.127)
		(layer "F.Cu")
		(net "P3E_CPU0_PE2_SS_C_TXP<3>")
	)
	(arc
		(start 86.227666 9.475978)
		(mid 86.1796 9.234335)
		(end 86.042754 9.029446)
		(width 0.127)
		(layer "F.Cu")
		(net "P3E_CPU0_PE2_SS_C_TXP<3>")
	)
	(arc
		(start 85.646768 8.63346)
		(mid 85.497867 8.41038)
		(end 85.4456 8.147304)
		(width 0.127)
		(layer "F.Cu")
		(net "P3E_CPU0_PE2_SS_C_TXP<3>")
	)
	(segment
		(start 85.410294 6.02234)
		(end 85.474048 5.504688)
		(width 0.127)
		(layer "In2.Cu")
		(net "P3E_CPU0_PE2_SS_C_TXP<3>")
	)
	(segment
		(start 70.701662 -7.836408)
		(end 70.56755 -7.97052)
		(width 0.127)
		(layer "In2.Cu")
		(net "P3E_CPU0_PE2_SS_C_TXP<3>")
	)
	(segment
		(start 85.357462 3.926078)
		(end 83.464146 1.222248)
		(width 0.127)
		(layer "In2.Cu")
		(net "P3E_CPU0_PE2_SS_C_TXP<3>")
	)
	(segment
		(start 70.931786 -13.894816)
		(end 70.93204 -13.894562)
		(width 0.127)
		(layer "In2.Cu")
		(net "P3E_CPU0_PE2_SS_C_TXP<3>")
	)
	(segment
		(start 59.40044 -28.643834)
		(end 59.400694 -28.643834)
		(width 0.127)
		(layer "In2.Cu")
		(net "P3E_CPU0_PE2_SS_C_TXP<3>")
	)
	(segment
		(start 72.918574 -3.589274)
		(end 71.01078 -6.313678)
		(width 0.127)
		(layer "In2.Cu")
		(net "P3E_CPU0_PE2_SS_C_TXP<3>")
	)
	(segment
		(start 70.93204 -14.288008)
		(end 70.500748 -16.734536)
		(width 0.127)
		(layer "In2.Cu")
		(net "P3E_CPU0_PE2_SS_C_TXP<3>")
	)
	(segment
		(start 70.933564 -6.88721)
		(end 70.93331 -6.96468)
		(width 0.127)
		(layer "In2.Cu")
		(net "P3E_CPU0_PE2_SS_C_TXP<3>")
	)
	(segment
		(start 85.474048 4.58724)
		(end 85.357462 3.926078)
		(width 0.127)
		(layer "In2.Cu")
		(net "P3E_CPU0_PE2_SS_C_TXP<3>")
	)
	(segment
		(start 70.50278 -16.739362)
		(end 70.501256 -16.742664)
		(width 0.127)
		(layer "In2.Cu")
		(net "P3E_CPU0_PE2_SS_C_TXP<3>")
	)
	(segment
		(start 70.501256 -16.742664)
		(end 70.452488 -16.860012)
		(width 0.127)
		(layer "In2.Cu")
		(net "P3E_CPU0_PE2_SS_C_TXP<3>")
	)
	(segment
		(start 69.945504 -9.472676)
		(end 69.945504 -11.63066)
		(width 0.127)
		(layer "In2.Cu")
		(net "P3E_CPU0_PE2_SS_C_TXP<3>")
	)
	(segment
		(start 59.361832 -26.041858)
		(end 59.299094 -26.08961)
		(width 0.127)
		(layer "In2.Cu")
		(net "P3E_CPU0_PE2_SS_C_TXP<3>")
	)
	(segment
		(start 70.933564 -6.753606)
		(end 70.933564 -6.88721)
		(width 0.127)
		(layer "In2.Cu")
		(net "P3E_CPU0_PE2_SS_C_TXP<3>")
	)
	(segment
		(start 70.441566 -12.828778)
		(end 70.524878 -12.911836)
		(width 0.127)
		(layer "In2.Cu")
		(net "P3E_CPU0_PE2_SS_C_TXP<3>")
	)
	(segment
		(start 71.01078 -6.313678)
		(end 70.933564 -6.753606)
		(width 0.127)
		(layer "In2.Cu")
		(net "P3E_CPU0_PE2_SS_C_TXP<3>")
	)
	(segment
		(start 85.456014 6.561074)
		(end 85.410294 6.02234)
		(width 0.127)
		(layer "In2.Cu")
		(net "P3E_CPU0_PE2_SS_C_TXP<3>")
	)
	(segment
		(start 83.464146 1.222248)
		(end 81.608168 -0.077216)
		(width 0.127)
		(layer "In2.Cu")
		(net "P3E_CPU0_PE2_SS_C_TXP<3>")
	)
	(segment
		(start 59.45759 -28.814268)
		(end 59.079892 -29.570426)
		(width 0.127)
		(layer "In2.Cu")
		(net "P3E_CPU0_PE2_SS_C_TXP<3>")
	)
	(segment
		(start 59.287156 -28.587446)
		(end 59.39917 -28.643326)
		(width 0.127)
		(layer "In2.Cu")
		(net "P3E_CPU0_PE2_SS_C_TXP<3>")
	)
	(segment
		(start 81.608168 -0.077216)
		(end 76.696824 -0.943864)
		(width 0.127)
		(layer "In2.Cu")
		(net "P3E_CPU0_PE2_SS_C_TXP<3>")
	)
	(segment
		(start 70.93204 -13.894562)
		(end 70.93204 -14.288008)
		(width 0.127)
		(layer "In2.Cu")
		(net "P3E_CPU0_PE2_SS_C_TXP<3>")
	)
	(segment
		(start 85.474048 5.504688)
		(end 85.474048 4.58724)
		(width 0.127)
		(layer "In2.Cu")
		(net "P3E_CPU0_PE2_SS_C_TXP<3>")
	)
	(segment
		(start 59.299094 -26.08961)
		(end 58.86831 -27.64536)
		(width 0.127)
		(layer "In2.Cu")
		(net "P3E_CPU0_PE2_SS_C_TXP<3>")
	)
	(segment
		(start 59.39917 -28.643326)
		(end 59.40044 -28.643834)
		(width 0.127)
		(layer "In2.Cu")
		(net "P3E_CPU0_PE2_SS_C_TXP<3>")
	)
	(segment
		(start 76.696824 -0.943864)
		(end 72.918574 -3.589274)
		(width 0.127)
		(layer "In2.Cu")
		(net "P3E_CPU0_PE2_SS_C_TXP<3>")
	)
	(segment
		(start 85.456014 7.250938)
		(end 85.456014 6.561074)
		(width 0.127)
		(layer "In2.Cu")
		(net "P3E_CPU0_PE2_SS_C_TXP<3>")
	)
	(segment
		(start 67.601846 -19.926808)
		(end 59.361832 -26.041858)
		(width 0.127)
		(layer "In2.Cu")
		(net "P3E_CPU0_PE2_SS_C_TXP<3>")
	)
	(segment
		(start 70.500748 -16.734536)
		(end 70.50278 -16.739362)
		(width 0.127)
		(layer "In2.Cu")
		(net "P3E_CPU0_PE2_SS_C_TXP<3>")
	)
	(segment
		(start 70.452488 -16.860012)
		(end 67.601846 -19.926808)
		(width 0.127)
		(layer "In2.Cu")
		(net "P3E_CPU0_PE2_SS_C_TXP<3>")
	)
	(segment
		(start 70.93331 -6.96468)
		(end 70.93331 -7.2771)
		(width 0.127)
		(layer "In2.Cu")
		(net "P3E_CPU0_PE2_SS_C_TXP<3>")
	)
	(arc
		(start 58.86831 -27.64536)
		(mid 58.908912 -28.191451)
		(end 59.287156 -28.587446)
		(width 0.127)
		(layer "In2.Cu")
		(net "P3E_CPU0_PE2_SS_C_TXP<3>")
	)
	(arc
		(start 70.93331 -7.2771)
		(mid 70.873102 -7.579786)
		(end 70.701662 -7.836408)
		(width 0.127)
		(layer "In2.Cu")
		(net "P3E_CPU0_PE2_SS_C_TXP<3>")
	)
	(arc
		(start 69.945504 -11.63066)
		(mid 70.074398 -12.279034)
		(end 70.441566 -12.828778)
		(width 0.127)
		(layer "In2.Cu")
		(net "P3E_CPU0_PE2_SS_C_TXP<3>")
	)
	(arc
		(start 85.077554 7.702042)
		(mid 85.35272 7.548637)
		(end 85.456014 7.250938)
		(width 0.127)
		(layer "In2.Cu")
		(net "P3E_CPU0_PE2_SS_C_TXP<3>")
	)
	(arc
		(start 70.56755 -7.97052)
		(mid 70.107152 -8.659743)
		(end 69.945504 -9.472676)
		(width 0.127)
		(layer "In2.Cu")
		(net "P3E_CPU0_PE2_SS_C_TXP<3>")
	)
	(arc
		(start 70.524878 -12.911836)
		(mid 70.826087 -13.36286)
		(end 70.931786 -13.894816)
		(width 0.127)
		(layer "In2.Cu")
		(net "P3E_CPU0_PE2_SS_C_TXP<3>")
	)
	(arc
		(start 59.400694 -28.643834)
		(mid 59.464457 -28.717287)
		(end 59.45759 -28.814268)
		(width 0.127)
		(layer "In2.Cu")
		(net "P3E_CPU0_PE2_SS_C_TXP<3>")
	)
	(segment
		(start 83.82762 10.383266)
		(end 83.82762 10.373868)
		(width 0.127)
		(layer "F.Cu")
		(net "P3E_CPU0_PE2_SS_C_TXP<2>")
	)
	(segment
		(start 83.827366 9.65835)
		(end 83.827112 9.658604)
		(width 0.127)
		(layer "F.Cu")
		(net "P3E_CPU0_PE2_SS_C_TXP<2>")
	)
	(segment
		(start 82.8548 8.147558)
		(end 82.8548 8.001)
		(width 0.127)
		(layer "F.Cu")
		(net "P3E_CPU0_PE2_SS_C_TXP<2>")
	)
	(segment
		(start 82.555842 7.702042)
		(end 82.486754 7.702042)
		(width 0.127)
		(layer "F.Cu")
		(net "P3E_CPU0_PE2_SS_C_TXP<2>")
	)
	(segment
		(start 83.629754 9.181846)
		(end 83.038188 8.590026)
		(width 0.127)
		(layer "F.Cu")
		(net "P3E_CPU0_PE2_SS_C_TXP<2>")
	)
	(segment
		(start 83.827366 10.373868)
		(end 83.827366 9.65835)
		(width 0.127)
		(layer "F.Cu")
		(net "P3E_CPU0_PE2_SS_C_TXP<2>")
	)
	(segment
		(start 83.57997 12.133072)
		(end 83.57997 10.980674)
		(width 0.127)
		(layer "F.Cu")
		(net "P3E_CPU0_PE2_SS_C_TXP<2>")
	)
	(segment
		(start 83.82762 10.373868)
		(end 83.827366 10.373868)
		(width 0.127)
		(layer "F.Cu")
		(net "P3E_CPU0_PE2_SS_C_TXP<2>")
	)
	(segment
		(start 83.703414 10.682224)
		(end 83.703668 10.68197)
		(width 0.127)
		(layer "F.Cu")
		(net "P3E_CPU0_PE2_SS_C_TXP<2>")
	)
	(via
		(at 82.486754 7.702042)
		(size 0.508)
		(drill 0.254)
		(layers "F.Cu" "B.Cu")
		(net "P3E_CPU0_PE2_SS_C_TXP<2>")
	)
	(arc
		(start 83.038188 8.590026)
		(mid 82.902514 8.387021)
		(end 82.8548 8.147558)
		(width 0.127)
		(layer "F.Cu")
		(net "P3E_CPU0_PE2_SS_C_TXP<2>")
	)
	(arc
		(start 83.827112 9.658604)
		(mid 83.775798 9.400631)
		(end 83.629754 9.181846)
		(width 0.127)
		(layer "F.Cu")
		(net "P3E_CPU0_PE2_SS_C_TXP<2>")
	)
	(arc
		(start 82.8548 8.001)
		(mid 82.767237 7.789605)
		(end 82.555842 7.702042)
		(width 0.127)
		(layer "F.Cu")
		(net "P3E_CPU0_PE2_SS_C_TXP<2>")
	)
	(arc
		(start 83.57997 10.980674)
		(mid 83.612055 10.819194)
		(end 83.703414 10.682224)
		(width 0.127)
		(layer "F.Cu")
		(net "P3E_CPU0_PE2_SS_C_TXP<2>")
	)
	(arc
		(start 83.703668 10.68197)
		(mid 83.795323 10.544938)
		(end 83.82762 10.383266)
		(width 0.127)
		(layer "F.Cu")
		(net "P3E_CPU0_PE2_SS_C_TXP<2>")
	)
	(segment
		(start 82.882994 5.493766)
		(end 82.81289 5.834634)
		(width 0.127)
		(layer "In2.Cu")
		(net "P3E_CPU0_PE2_SS_C_TXP<2>")
	)
	(segment
		(start 55.714646 -25.462738)
		(end 64.498728 -19.312382)
		(width 0.127)
		(layer "In2.Cu")
		(net "P3E_CPU0_PE2_SS_C_TXP<2>")
	)
	(segment
		(start 66.56832 -7.97052)
		(end 66.702432 -7.836408)
		(width 0.127)
		(layer "In2.Cu")
		(net "P3E_CPU0_PE2_SS_C_TXP<2>")
	)
	(segment
		(start 82.883248 5.493766)
		(end 82.882994 5.493766)
		(width 0.127)
		(layer "In2.Cu")
		(net "P3E_CPU0_PE2_SS_C_TXP<2>")
	)
	(segment
		(start 66.934334 -6.753606)
		(end 67.023742 -6.245606)
		(width 0.127)
		(layer "In2.Cu")
		(net "P3E_CPU0_PE2_SS_C_TXP<2>")
	)
	(segment
		(start 64.498728 -19.312382)
		(end 66.567812 -16.3576)
		(width 0.127)
		(layer "In2.Cu")
		(net "P3E_CPU0_PE2_SS_C_TXP<2>")
	)
	(segment
		(start 66.525648 -12.911836)
		(end 66.442336 -12.828778)
		(width 0.127)
		(layer "In2.Cu")
		(net "P3E_CPU0_PE2_SS_C_TXP<2>")
	)
	(segment
		(start 66.567812 -16.3576)
		(end 66.567812 -16.357346)
		(width 0.127)
		(layer "In2.Cu")
		(net "P3E_CPU0_PE2_SS_C_TXP<2>")
	)
	(segment
		(start 82.883248 4.529582)
		(end 82.883248 5.493766)
		(width 0.127)
		(layer "In2.Cu")
		(net "P3E_CPU0_PE2_SS_C_TXP<2>")
	)
	(segment
		(start 66.567812 -16.357346)
		(end 66.93281 -14.288008)
		(width 0.127)
		(layer "In2.Cu")
		(net "P3E_CPU0_PE2_SS_C_TXP<2>")
	)
	(segment
		(start 82.805778 5.899912)
		(end 82.865214 6.561074)
		(width 0.127)
		(layer "In2.Cu")
		(net "P3E_CPU0_PE2_SS_C_TXP<2>")
	)
	(segment
		(start 82.76844 3.879342)
		(end 82.883248 4.529582)
		(width 0.127)
		(layer "In2.Cu")
		(net "P3E_CPU0_PE2_SS_C_TXP<2>")
	)
	(segment
		(start 74.083672 0.543814)
		(end 80.462374 1.668526)
		(width 0.127)
		(layer "In2.Cu")
		(net "P3E_CPU0_PE2_SS_C_TXP<2>")
	)
	(segment
		(start 67.023742 -6.245606)
		(end 69.560186 -2.62382)
		(width 0.127)
		(layer "In2.Cu")
		(net "P3E_CPU0_PE2_SS_C_TXP<2>")
	)
	(segment
		(start 55.16626 -26.6319)
		(end 55.714646 -25.462738)
		(width 0.127)
		(layer "In2.Cu")
		(net "P3E_CPU0_PE2_SS_C_TXP<2>")
	)
	(segment
		(start 66.934334 -6.88721)
		(end 66.934334 -6.753606)
		(width 0.127)
		(layer "In2.Cu")
		(net "P3E_CPU0_PE2_SS_C_TXP<2>")
	)
	(segment
		(start 80.462374 1.668526)
		(end 81.949544 2.709672)
		(width 0.127)
		(layer "In2.Cu")
		(net "P3E_CPU0_PE2_SS_C_TXP<2>")
	)
	(segment
		(start 65.946274 -11.63066)
		(end 65.946274 -9.472676)
		(width 0.127)
		(layer "In2.Cu")
		(net "P3E_CPU0_PE2_SS_C_TXP<2>")
	)
	(segment
		(start 66.93408 -7.2771)
		(end 66.93408 -6.96468)
		(width 0.127)
		(layer "In2.Cu")
		(net "P3E_CPU0_PE2_SS_C_TXP<2>")
	)
	(segment
		(start 69.560186 -2.62382)
		(end 74.083672 0.543814)
		(width 0.127)
		(layer "In2.Cu")
		(net "P3E_CPU0_PE2_SS_C_TXP<2>")
	)
	(segment
		(start 55.400702 -28.644088)
		(end 55.287164 -28.587192)
		(width 0.127)
		(layer "In2.Cu")
		(net "P3E_CPU0_PE2_SS_C_TXP<2>")
	)
	(segment
		(start 55.079392 -29.570426)
		(end 55.457598 -28.814522)
		(width 0.127)
		(layer "In2.Cu")
		(net "P3E_CPU0_PE2_SS_C_TXP<2>")
	)
	(segment
		(start 81.949544 2.709672)
		(end 82.76844 3.879342)
		(width 0.127)
		(layer "In2.Cu")
		(net "P3E_CPU0_PE2_SS_C_TXP<2>")
	)
	(segment
		(start 66.93408 -6.96468)
		(end 66.934334 -6.88721)
		(width 0.127)
		(layer "In2.Cu")
		(net "P3E_CPU0_PE2_SS_C_TXP<2>")
	)
	(segment
		(start 82.865214 6.561074)
		(end 82.865214 7.250938)
		(width 0.127)
		(layer "In2.Cu")
		(net "P3E_CPU0_PE2_SS_C_TXP<2>")
	)
	(segment
		(start 55.400956 -28.644088)
		(end 55.400702 -28.644088)
		(width 0.127)
		(layer "In2.Cu")
		(net "P3E_CPU0_PE2_SS_C_TXP<2>")
	)
	(segment
		(start 82.81289 5.834634)
		(end 82.805778 5.899912)
		(width 0.127)
		(layer "In2.Cu")
		(net "P3E_CPU0_PE2_SS_C_TXP<2>")
	)
	(segment
		(start 66.93281 -13.894562)
		(end 66.932556 -13.894816)
		(width 0.127)
		(layer "In2.Cu")
		(net "P3E_CPU0_PE2_SS_C_TXP<2>")
	)
	(segment
		(start 66.93281 -14.288008)
		(end 66.93281 -13.894562)
		(width 0.127)
		(layer "In2.Cu")
		(net "P3E_CPU0_PE2_SS_C_TXP<2>")
	)
	(arc
		(start 66.932556 -13.894816)
		(mid 66.826855 -13.362861)
		(end 66.525648 -12.911836)
		(width 0.127)
		(layer "In2.Cu")
		(net "P3E_CPU0_PE2_SS_C_TXP<2>")
	)
	(arc
		(start 82.865214 7.250938)
		(mid 82.758059 7.545325)
		(end 82.486754 7.702042)
		(width 0.127)
		(layer "In2.Cu")
		(net "P3E_CPU0_PE2_SS_C_TXP<2>")
	)
	(arc
		(start 66.442336 -12.828778)
		(mid 66.075067 -12.279076)
		(end 65.946274 -11.63066)
		(width 0.127)
		(layer "In2.Cu")
		(net "P3E_CPU0_PE2_SS_C_TXP<2>")
	)
	(arc
		(start 55.457598 -28.814522)
		(mid 55.464575 -28.717574)
		(end 55.400956 -28.644088)
		(width 0.127)
		(layer "In2.Cu")
		(net "P3E_CPU0_PE2_SS_C_TXP<2>")
	)
	(arc
		(start 65.946274 -9.472676)
		(mid 66.107939 -8.659751)
		(end 66.56832 -7.97052)
		(width 0.127)
		(layer "In2.Cu")
		(net "P3E_CPU0_PE2_SS_C_TXP<2>")
	)
	(arc
		(start 66.702432 -7.836408)
		(mid 66.873895 -7.579795)
		(end 66.93408 -7.2771)
		(width 0.127)
		(layer "In2.Cu")
		(net "P3E_CPU0_PE2_SS_C_TXP<2>")
	)
	(arc
		(start 54.88178 -27.90698)
		(mid 54.953765 -27.253766)
		(end 55.16626 -26.6319)
		(width 0.127)
		(layer "In2.Cu")
		(net "P3E_CPU0_PE2_SS_C_TXP<2>")
	)
	(arc
		(start 55.287164 -28.587192)
		(mid 54.984925 -28.306403)
		(end 54.88178 -27.90698)
		(width 0.127)
		(layer "In2.Cu")
		(net "P3E_CPU0_PE2_SS_C_TXP<2>")
	)
	(segment
		(start 126.698502 10.783824)
		(end 126.698756 10.78357)
		(width 0.127)
		(layer "F.Cu")
		(net "P3E_CPU0_PE2_SS_C_TXP<15>")
	)
	(segment
		(start 126.822708 10.484866)
		(end 126.827026 10.422636)
		(width 0.127)
		(layer "F.Cu")
		(net "P3E_CPU0_PE2_SS_C_TXP<15>")
	)
	(segment
		(start 127.602234 8.739886)
		(end 127.636524 8.545576)
		(width 0.127)
		(layer "F.Cu")
		(net "P3E_CPU0_PE2_SS_C_TXP<15>")
	)
	(segment
		(start 127.490982 7.742682)
		(end 127.378206 7.742682)
		(width 0.127)
		(layer "F.Cu")
		(net "P3E_CPU0_PE2_SS_C_TXP<15>")
	)
	(segment
		(start 127.579628 8.866124)
		(end 127.602234 8.739886)
		(width 0.127)
		(layer "F.Cu")
		(net "P3E_CPU0_PE2_SS_C_TXP<15>")
	)
	(segment
		(start 126.575058 12.234672)
		(end 126.575058 11.082274)
		(width 0.127)
		(layer "F.Cu")
		(net "P3E_CPU0_PE2_SS_C_TXP<15>")
	)
	(segment
		(start 127.636524 8.545576)
		(end 127.738124 7.96925)
		(width 0.127)
		(layer "F.Cu")
		(net "P3E_CPU0_PE2_SS_C_TXP<15>")
	)
	(segment
		(start 126.990602 9.728708)
		(end 127.5588 8.916924)
		(width 0.127)
		(layer "F.Cu")
		(net "P3E_CPU0_PE2_SS_C_TXP<15>")
	)
	(segment
		(start 126.827026 10.422636)
		(end 126.918974 9.901428)
		(width 0.127)
		(layer "F.Cu")
		(net "P3E_CPU0_PE2_SS_C_TXP<15>")
	)
	(via
		(at 127.378206 7.742682)
		(size 0.508)
		(drill 0.254)
		(layers "F.Cu" "B.Cu")
		(net "P3E_CPU0_PE2_SS_C_TXP<15>")
	)
	(arc
		(start 126.575058 11.082274)
		(mid 126.607143 10.920794)
		(end 126.698502 10.783824)
		(width 0.127)
		(layer "F.Cu")
		(net "P3E_CPU0_PE2_SS_C_TXP<15>")
	)
	(arc
		(start 126.918974 9.901428)
		(mid 126.945338 9.811151)
		(end 126.990602 9.728708)
		(width 0.127)
		(layer "F.Cu")
		(net "P3E_CPU0_PE2_SS_C_TXP<15>")
	)
	(arc
		(start 126.698756 10.78357)
		(mid 126.790411 10.646538)
		(end 126.822708 10.484866)
		(width 0.127)
		(layer "F.Cu")
		(net "P3E_CPU0_PE2_SS_C_TXP<15>")
	)
	(arc
		(start 127.5588 8.916924)
		(mid 127.572 8.892666)
		(end 127.579628 8.866124)
		(width 0.127)
		(layer "F.Cu")
		(net "P3E_CPU0_PE2_SS_C_TXP<15>")
	)
	(arc
		(start 127.738124 7.96925)
		(mid 127.658596 7.807945)
		(end 127.490982 7.742682)
		(width 0.127)
		(layer "F.Cu")
		(net "P3E_CPU0_PE2_SS_C_TXP<15>")
	)
	(segment
		(start 111.286036 -25.713182)
		(end 111.39297 -25.916636)
		(width 0.127)
		(layer "In2.Cu")
		(net "P3E_CPU0_PE2_SS_C_TXP<15>")
	)
	(segment
		(start 110.96244 -26.751026)
		(end 111.069374 -26.95448)
		(width 0.127)
		(layer "In2.Cu")
		(net "P3E_CPU0_PE2_SS_C_TXP<15>")
	)
	(segment
		(start 110.628176 -28.382468)
		(end 110.627922 -28.382468)
		(width 0.127)
		(layer "In2.Cu")
		(net "P3E_CPU0_PE2_SS_C_TXP<15>")
	)
	(segment
		(start 111.603028 -25.24252)
		(end 111.399574 -25.349454)
		(width 0.127)
		(layer "In2.Cu")
		(net "P3E_CPU0_PE2_SS_C_TXP<15>")
	)
	(segment
		(start 111.075978 -26.387298)
		(end 110.96244 -26.751026)
		(width 0.127)
		(layer "In2.Cu")
		(net "P3E_CPU0_PE2_SS_C_TXP<15>")
	)
	(segment
		(start 119.686832 -10.966196)
		(end 119.525288 -11.881104)
		(width 0.127)
		(layer "In2.Cu")
		(net "P3E_CPU0_PE2_SS_C_TXP<15>")
	)
	(segment
		(start 110.972854 -27.513534)
		(end 110.97768 -27.533854)
		(width 0.127)
		(layer "In2.Cu")
		(net "P3E_CPU0_PE2_SS_C_TXP<15>")
	)
	(segment
		(start 127.757936 6.692392)
		(end 127.757936 6.26999)
		(width 0.127)
		(layer "In2.Cu")
		(net "P3E_CPU0_PE2_SS_C_TXP<15>")
	)
	(segment
		(start 110.457488 -28.325826)
		(end 110.079282 -27.570176)
		(width 0.127)
		(layer "In2.Cu")
		(net "P3E_CPU0_PE2_SS_C_TXP<15>")
	)
	(segment
		(start 112.753902 -21.5519)
		(end 111.603028 -25.24252)
		(width 0.127)
		(layer "In2.Cu")
		(net "P3E_CPU0_PE2_SS_C_TXP<15>")
	)
	(segment
		(start 111.069374 -26.95448)
		(end 110.955836 -27.318208)
		(width 0.127)
		(layer "In2.Cu")
		(net "P3E_CPU0_PE2_SS_C_TXP<15>")
	)
	(segment
		(start 120.1928 -8.095742)
		(end 119.847868 -10.05205)
		(width 0.127)
		(layer "In2.Cu")
		(net "P3E_CPU0_PE2_SS_C_TXP<15>")
	)
	(segment
		(start 119.847868 -10.05205)
		(end 119.686832 -10.966196)
		(width 0.127)
		(layer "In2.Cu")
		(net "P3E_CPU0_PE2_SS_C_TXP<15>")
	)
	(segment
		(start 110.74146 -28.325826)
		(end 110.628176 -28.382468)
		(width 0.127)
		(layer "In2.Cu")
		(net "P3E_CPU0_PE2_SS_C_TXP<15>")
	)
	(segment
		(start 111.279432 -26.280364)
		(end 111.075978 -26.387298)
		(width 0.127)
		(layer "In2.Cu")
		(net "P3E_CPU0_PE2_SS_C_TXP<15>")
	)
	(segment
		(start 111.39297 -25.916636)
		(end 111.279432 -26.280364)
		(width 0.127)
		(layer "In2.Cu")
		(net "P3E_CPU0_PE2_SS_C_TXP<15>")
	)
	(segment
		(start 127.16383 1.860042)
		(end 120.1928 -8.095742)
		(width 0.127)
		(layer "In2.Cu")
		(net "P3E_CPU0_PE2_SS_C_TXP<15>")
	)
	(segment
		(start 111.399574 -25.349454)
		(end 111.286036 -25.713182)
		(width 0.127)
		(layer "In2.Cu")
		(net "P3E_CPU0_PE2_SS_C_TXP<15>")
	)
	(segment
		(start 127.740918 4.904994)
		(end 127.16383 1.860042)
		(width 0.127)
		(layer "In2.Cu")
		(net "P3E_CPU0_PE2_SS_C_TXP<15>")
	)
	(segment
		(start 110.955836 -27.318208)
		(end 110.972854 -27.513534)
		(width 0.127)
		(layer "In2.Cu")
		(net "P3E_CPU0_PE2_SS_C_TXP<15>")
	)
	(segment
		(start 119.525288 -11.881104)
		(end 112.753902 -21.5519)
		(width 0.127)
		(layer "In2.Cu")
		(net "P3E_CPU0_PE2_SS_C_TXP<15>")
	)
	(arc
		(start 127.378206 7.742682)
		(mid 127.653372 7.589277)
		(end 127.756666 7.291578)
		(width 0.127)
		(layer "In2.Cu")
		(net "P3E_CPU0_PE2_SS_C_TXP<15>")
	)
	(arc
		(start 127.757936 6.26999)
		(mid 127.73661 5.917365)
		(end 127.760222 5.564886)
		(width 0.127)
		(layer "In2.Cu")
		(net "P3E_CPU0_PE2_SS_C_TXP<15>")
	)
	(arc
		(start 127.760222 5.564886)
		(mid 127.777294 5.234158)
		(end 127.740918 4.904994)
		(width 0.127)
		(layer "In2.Cu")
		(net "P3E_CPU0_PE2_SS_C_TXP<15>")
	)
	(arc
		(start 110.993936 -27.980894)
		(mid 110.909469 -28.18394)
		(end 110.74146 -28.325826)
		(width 0.127)
		(layer "In2.Cu")
		(net "P3E_CPU0_PE2_SS_C_TXP<15>")
	)
	(arc
		(start 110.97768 -27.533854)
		(mid 111.007398 -27.756589)
		(end 110.993936 -27.980894)
		(width 0.127)
		(layer "In2.Cu")
		(net "P3E_CPU0_PE2_SS_C_TXP<15>")
	)
	(arc
		(start 110.627922 -28.382468)
		(mid 110.530974 -28.389445)
		(end 110.457488 -28.325826)
		(width 0.127)
		(layer "In2.Cu")
		(net "P3E_CPU0_PE2_SS_C_TXP<15>")
	)
	(arc
		(start 127.756666 7.291578)
		(mid 127.756984 6.991984)
		(end 127.757936 6.692392)
		(width 0.127)
		(layer "In2.Cu")
		(net "P3E_CPU0_PE2_SS_C_TXP<15>")
	)
	(segment
		(start 124.298456 10.783824)
		(end 124.29871 10.78357)
		(width 0.127)
		(layer "F.Cu")
		(net "P3E_CPU0_PE2_SS_C_TXP<14>")
	)
	(segment
		(start 125.164342 8.396478)
		(end 125.155452 8.34644)
		(width 0.127)
		(layer "F.Cu")
		(net "P3E_CPU0_PE2_SS_C_TXP<14>")
	)
	(segment
		(start 124.427234 10.422636)
		(end 124.527056 9.854946)
		(width 0.127)
		(layer "F.Cu")
		(net "P3E_CPU0_PE2_SS_C_TXP<14>")
	)
	(segment
		(start 124.527056 9.854946)
		(end 125.035056 9.129776)
		(width 0.127)
		(layer "F.Cu")
		(net "P3E_CPU0_PE2_SS_C_TXP<14>")
	)
	(segment
		(start 124.422662 10.484866)
		(end 124.427234 10.422636)
		(width 0.127)
		(layer "F.Cu")
		(net "P3E_CPU0_PE2_SS_C_TXP<14>")
	)
	(segment
		(start 124.856494 7.742682)
		(end 124.787406 7.742682)
		(width 0.127)
		(layer "F.Cu")
		(net "P3E_CPU0_PE2_SS_C_TXP<14>")
	)
	(segment
		(start 125.155452 8.34644)
		(end 125.155452 8.04164)
		(width 0.127)
		(layer "F.Cu")
		(net "P3E_CPU0_PE2_SS_C_TXP<14>")
	)
	(segment
		(start 125.035056 9.129776)
		(end 125.164342 8.396478)
		(width 0.127)
		(layer "F.Cu")
		(net "P3E_CPU0_PE2_SS_C_TXP<14>")
	)
	(segment
		(start 124.175012 12.234672)
		(end 124.175012 11.082274)
		(width 0.127)
		(layer "F.Cu")
		(net "P3E_CPU0_PE2_SS_C_TXP<14>")
	)
	(via
		(at 124.787406 7.742682)
		(size 0.508)
		(drill 0.254)
		(layers "F.Cu" "B.Cu")
		(net "P3E_CPU0_PE2_SS_C_TXP<14>")
	)
	(arc
		(start 124.175012 11.082274)
		(mid 124.207097 10.920794)
		(end 124.298456 10.783824)
		(width 0.127)
		(layer "F.Cu")
		(net "P3E_CPU0_PE2_SS_C_TXP<14>")
	)
	(arc
		(start 124.29871 10.78357)
		(mid 124.390365 10.646538)
		(end 124.422662 10.484866)
		(width 0.127)
		(layer "F.Cu")
		(net "P3E_CPU0_PE2_SS_C_TXP<14>")
	)
	(arc
		(start 125.155452 8.04164)
		(mid 125.067889 7.830245)
		(end 124.856494 7.742682)
		(width 0.127)
		(layer "F.Cu")
		(net "P3E_CPU0_PE2_SS_C_TXP<14>")
	)
	(segment
		(start 108.618528 -23.782274)
		(end 108.472478 -23.991316)
		(width 0.127)
		(layer "In2.Cu")
		(net "P3E_CPU0_PE2_SS_C_TXP<14>")
	)
	(segment
		(start 109.254798 -22.873462)
		(end 109.192822 -22.9616)
		(width 0.127)
		(layer "In2.Cu")
		(net "P3E_CPU0_PE2_SS_C_TXP<14>")
	)
	(segment
		(start 124.566172 1.891538)
		(end 124.562108 1.885696)
		(width 0.127)
		(layer "In2.Cu")
		(net "P3E_CPU0_PE2_SS_C_TXP<14>")
	)
	(segment
		(start 125.149864 4.904994)
		(end 124.566172 1.891538)
		(width 0.127)
		(layer "In2.Cu")
		(net "P3E_CPU0_PE2_SS_C_TXP<14>")
	)
	(segment
		(start 121.54662 -2.758694)
		(end 118.250208 -7.46633)
		(width 0.127)
		(layer "In2.Cu")
		(net "P3E_CPU0_PE2_SS_C_TXP<14>")
	)
	(segment
		(start 107.669584 -25.390094)
		(end 107.514136 -25.73782)
		(width 0.127)
		(layer "In2.Cu")
		(net "P3E_CPU0_PE2_SS_C_TXP<14>")
	)
	(segment
		(start 108.690664 -23.67915)
		(end 108.621322 -23.778464)
		(width 0.127)
		(layer "In2.Cu")
		(net "P3E_CPU0_PE2_SS_C_TXP<14>")
	)
	(segment
		(start 107.152948 -26.945082)
		(end 106.9975 -27.293062)
		(width 0.127)
		(layer "In2.Cu")
		(net "P3E_CPU0_PE2_SS_C_TXP<14>")
	)
	(segment
		(start 107.2261 -26.382472)
		(end 107.070652 -26.730452)
		(width 0.127)
		(layer "In2.Cu")
		(net "P3E_CPU0_PE2_SS_C_TXP<14>")
	)
	(segment
		(start 125.167136 6.692392)
		(end 125.167136 6.26999)
		(width 0.127)
		(layer "In2.Cu")
		(net "P3E_CPU0_PE2_SS_C_TXP<14>")
	)
	(segment
		(start 107.596178 -25.952704)
		(end 107.44073 -26.30043)
		(width 0.127)
		(layer "In2.Cu")
		(net "P3E_CPU0_PE2_SS_C_TXP<14>")
	)
	(segment
		(start 107.44073 -26.30043)
		(end 107.2261 -26.382472)
		(width 0.127)
		(layer "In2.Cu")
		(net "P3E_CPU0_PE2_SS_C_TXP<14>")
	)
	(segment
		(start 108.461556 -24.0157)
		(end 108.461048 -24.016462)
		(width 0.127)
		(layer "In2.Cu")
		(net "P3E_CPU0_PE2_SS_C_TXP<14>")
	)
	(segment
		(start 108.621322 -23.778464)
		(end 108.618528 -23.782274)
		(width 0.127)
		(layer "In2.Cu")
		(net "P3E_CPU0_PE2_SS_C_TXP<14>")
	)
	(segment
		(start 121.873264 -2.291842)
		(end 121.54662 -2.758694)
		(width 0.127)
		(layer "In2.Cu")
		(net "P3E_CPU0_PE2_SS_C_TXP<14>")
	)
	(segment
		(start 106.9975 -27.293062)
		(end 106.995976 -27.761184)
		(width 0.127)
		(layer "In2.Cu")
		(net "P3E_CPU0_PE2_SS_C_TXP<14>")
	)
	(segment
		(start 117.64772 -10.887456)
		(end 117.64772 -10.88771)
		(width 0.127)
		(layer "In2.Cu")
		(net "P3E_CPU0_PE2_SS_C_TXP<14>")
	)
	(segment
		(start 107.514136 -25.73782)
		(end 107.596178 -25.952704)
		(width 0.127)
		(layer "In2.Cu")
		(net "P3E_CPU0_PE2_SS_C_TXP<14>")
	)
	(segment
		(start 107.884214 -25.307798)
		(end 107.669584 -25.390094)
		(width 0.127)
		(layer "In2.Cu")
		(net "P3E_CPU0_PE2_SS_C_TXP<14>")
	)
	(segment
		(start 106.628692 -28.382468)
		(end 106.5149 -28.382468)
		(width 0.127)
		(layer "In2.Cu")
		(net "P3E_CPU0_PE2_SS_C_TXP<14>")
	)
	(segment
		(start 108.472478 -23.991316)
		(end 108.461556 -24.0157)
		(width 0.127)
		(layer "In2.Cu")
		(net "P3E_CPU0_PE2_SS_C_TXP<14>")
	)
	(segment
		(start 122.2883 -1.699514)
		(end 121.873264 -2.291842)
		(width 0.127)
		(layer "In2.Cu")
		(net "P3E_CPU0_PE2_SS_C_TXP<14>")
	)
	(segment
		(start 124.562108 1.885696)
		(end 124.482098 1.433576)
		(width 0.127)
		(layer "In2.Cu")
		(net "P3E_CPU0_PE2_SS_C_TXP<14>")
	)
	(segment
		(start 106.458258 -28.325826)
		(end 106.080052 -27.570176)
		(width 0.127)
		(layer "In2.Cu")
		(net "P3E_CPU0_PE2_SS_C_TXP<14>")
	)
	(segment
		(start 106.780584 -28.230576)
		(end 106.628692 -28.382468)
		(width 0.127)
		(layer "In2.Cu")
		(net "P3E_CPU0_PE2_SS_C_TXP<14>")
	)
	(segment
		(start 117.64772 -10.88771)
		(end 109.254798 -22.873462)
		(width 0.127)
		(layer "In2.Cu")
		(net "P3E_CPU0_PE2_SS_C_TXP<14>")
	)
	(segment
		(start 107.070652 -26.730452)
		(end 107.152948 -26.945082)
		(width 0.127)
		(layer "In2.Cu")
		(net "P3E_CPU0_PE2_SS_C_TXP<14>")
	)
	(segment
		(start 124.482098 1.433576)
		(end 122.2883 -1.699514)
		(width 0.127)
		(layer "In2.Cu")
		(net "P3E_CPU0_PE2_SS_C_TXP<14>")
	)
	(segment
		(start 108.46054 -24.017478)
		(end 107.884214 -25.307798)
		(width 0.127)
		(layer "In2.Cu")
		(net "P3E_CPU0_PE2_SS_C_TXP<14>")
	)
	(segment
		(start 109.192822 -22.9616)
		(end 108.690664 -23.67915)
		(width 0.127)
		(layer "In2.Cu")
		(net "P3E_CPU0_PE2_SS_C_TXP<14>")
	)
	(segment
		(start 106.5149 -28.382468)
		(end 106.458258 -28.325826)
		(width 0.127)
		(layer "In2.Cu")
		(net "P3E_CPU0_PE2_SS_C_TXP<14>")
	)
	(segment
		(start 118.250208 -7.46633)
		(end 117.64772 -10.887456)
		(width 0.127)
		(layer "In2.Cu")
		(net "P3E_CPU0_PE2_SS_C_TXP<14>")
	)
	(segment
		(start 106.995976 -27.761184)
		(end 106.780584 -28.230576)
		(width 0.127)
		(layer "In2.Cu")
		(net "P3E_CPU0_PE2_SS_C_TXP<14>")
	)
	(segment
		(start 108.461048 -24.016462)
		(end 108.46054 -24.017478)
		(width 0.127)
		(layer "In2.Cu")
		(net "P3E_CPU0_PE2_SS_C_TXP<14>")
	)
	(arc
		(start 124.787406 7.742682)
		(mid 125.062572 7.589277)
		(end 125.165866 7.291578)
		(width 0.127)
		(layer "In2.Cu")
		(net "P3E_CPU0_PE2_SS_C_TXP<14>")
	)
	(arc
		(start 125.167136 6.26999)
		(mid 125.14581 5.917365)
		(end 125.169422 5.564886)
		(width 0.127)
		(layer "In2.Cu")
		(net "P3E_CPU0_PE2_SS_C_TXP<14>")
	)
	(arc
		(start 125.165866 7.291578)
		(mid 125.166184 6.991984)
		(end 125.167136 6.692392)
		(width 0.127)
		(layer "In2.Cu")
		(net "P3E_CPU0_PE2_SS_C_TXP<14>")
	)
	(arc
		(start 125.169422 5.564886)
		(mid 125.186369 5.234147)
		(end 125.149864 4.904994)
		(width 0.127)
		(layer "In2.Cu")
		(net "P3E_CPU0_PE2_SS_C_TXP<14>")
	)
	(segment
		(start 122.196606 7.742682)
		(end 122.265694 7.742682)
		(width 0.127)
		(layer "F.Cu")
		(net "P3E_CPU0_PE2_SS_C_TXP<13>")
	)
	(segment
		(start 122.564652 8.04164)
		(end 122.564652 8.44677)
		(width 0.127)
		(layer "F.Cu")
		(net "P3E_CPU0_PE2_SS_C_TXP<13>")
	)
	(segment
		(start 122.12574 9.864598)
		(end 122.09526 10.037318)
		(width 0.127)
		(layer "F.Cu")
		(net "P3E_CPU0_PE2_SS_C_TXP<13>")
	)
	(segment
		(start 121.774966 11.082274)
		(end 121.774966 12.234672)
		(width 0.127)
		(layer "F.Cu")
		(net "P3E_CPU0_PE2_SS_C_TXP<13>")
	)
	(segment
		(start 122.564652 8.44677)
		(end 122.378216 9.504172)
		(width 0.127)
		(layer "F.Cu")
		(net "P3E_CPU0_PE2_SS_C_TXP<13>")
	)
	(segment
		(start 122.027188 10.422636)
		(end 122.022616 10.484866)
		(width 0.127)
		(layer "F.Cu")
		(net "P3E_CPU0_PE2_SS_C_TXP<13>")
	)
	(segment
		(start 121.898664 10.78357)
		(end 121.89841 10.783824)
		(width 0.127)
		(layer "F.Cu")
		(net "P3E_CPU0_PE2_SS_C_TXP<13>")
	)
	(segment
		(start 122.378216 9.504172)
		(end 122.12574 9.864598)
		(width 0.127)
		(layer "F.Cu")
		(net "P3E_CPU0_PE2_SS_C_TXP<13>")
	)
	(segment
		(start 122.09526 10.037318)
		(end 122.027188 10.422636)
		(width 0.127)
		(layer "F.Cu")
		(net "P3E_CPU0_PE2_SS_C_TXP<13>")
	)
	(via
		(at 122.196606 7.742682)
		(size 0.508)
		(drill 0.254)
		(layers "F.Cu" "B.Cu")
		(net "P3E_CPU0_PE2_SS_C_TXP<13>")
	)
	(arc
		(start 121.89841 10.783824)
		(mid 121.807024 10.920782)
		(end 121.774966 11.082274)
		(width 0.127)
		(layer "F.Cu")
		(net "P3E_CPU0_PE2_SS_C_TXP<13>")
	)
	(arc
		(start 122.022616 10.484866)
		(mid 121.99036 10.646556)
		(end 121.898664 10.78357)
		(width 0.127)
		(layer "F.Cu")
		(net "P3E_CPU0_PE2_SS_C_TXP<13>")
	)
	(arc
		(start 122.265694 7.742682)
		(mid 122.477089 7.830245)
		(end 122.564652 8.04164)
		(width 0.127)
		(layer "F.Cu")
		(net "P3E_CPU0_PE2_SS_C_TXP<13>")
	)
	(segment
		(start 122.14225 2.67589)
		(end 122.56135 4.918202)
		(width 0.127)
		(layer "In2.Cu")
		(net "P3E_CPU0_PE2_SS_C_TXP<13>")
	)
	(segment
		(start 110.927642 -13.933932)
		(end 110.927642 -13.93317)
		(width 0.127)
		(layer "In2.Cu")
		(net "P3E_CPU0_PE2_SS_C_TXP<13>")
	)
	(segment
		(start 104.429052 -23.9649)
		(end 104.655112 -23.922228)
		(width 0.127)
		(layer "In2.Cu")
		(net "P3E_CPU0_PE2_SS_C_TXP<13>")
	)
	(segment
		(start 114.367056 -5.303266)
		(end 118.661688 -2.294382)
		(width 0.127)
		(layer "In2.Cu")
		(net "P3E_CPU0_PE2_SS_C_TXP<13>")
	)
	(segment
		(start 103.4288 -25.717754)
		(end 103.643684 -25.403048)
		(width 0.127)
		(layer "In2.Cu")
		(net "P3E_CPU0_PE2_SS_C_TXP<13>")
	)
	(segment
		(start 102.99065 -27.802332)
		(end 102.99065 -27.801062)
		(width 0.127)
		(layer "In2.Cu")
		(net "P3E_CPU0_PE2_SS_C_TXP<13>")
	)
	(segment
		(start 103.40848 -25.747218)
		(end 103.4288 -25.717754)
		(width 0.127)
		(layer "In2.Cu")
		(net "P3E_CPU0_PE2_SS_C_TXP<13>")
	)
	(segment
		(start 111.90732 -11.87958)
		(end 111.90732 -9.385046)
		(width 0.127)
		(layer "In2.Cu")
		(net "P3E_CPU0_PE2_SS_C_TXP<13>")
	)
	(segment
		(start 110.927642 -13.93317)
		(end 110.92688 -13.932408)
		(width 0.127)
		(layer "In2.Cu")
		(net "P3E_CPU0_PE2_SS_C_TXP<13>")
	)
	(segment
		(start 110.870238 -14.587474)
		(end 110.870746 -14.58595)
		(width 0.127)
		(layer "In2.Cu")
		(net "P3E_CPU0_PE2_SS_C_TXP<13>")
	)
	(segment
		(start 102.99065 -27.801062)
		(end 102.987856 -27.674316)
		(width 0.127)
		(layer "In2.Cu")
		(net "P3E_CPU0_PE2_SS_C_TXP<13>")
	)
	(segment
		(start 113.301272 -6.050026)
		(end 114.367056 -5.303266)
		(width 0.127)
		(layer "In2.Cu")
		(net "P3E_CPU0_PE2_SS_C_TXP<13>")
	)
	(segment
		(start 102.628446 -28.382468)
		(end 102.741476 -28.325826)
		(width 0.127)
		(layer "In2.Cu")
		(net "P3E_CPU0_PE2_SS_C_TXP<13>")
	)
	(segment
		(start 102.994968 -27.840178)
		(end 102.989634 -27.803602)
		(width 0.127)
		(layer "In2.Cu")
		(net "P3E_CPU0_PE2_SS_C_TXP<13>")
	)
	(segment
		(start 110.869476 -14.585696)
		(end 110.869984 -14.584172)
		(width 0.127)
		(layer "In2.Cu")
		(net "P3E_CPU0_PE2_SS_C_TXP<13>")
	)
	(segment
		(start 102.628192 -28.382468)
		(end 102.628446 -28.382468)
		(width 0.127)
		(layer "In2.Cu")
		(net "P3E_CPU0_PE2_SS_C_TXP<13>")
	)
	(segment
		(start 102.079552 -27.570176)
		(end 102.457758 -28.325826)
		(width 0.127)
		(layer "In2.Cu")
		(net "P3E_CPU0_PE2_SS_C_TXP<13>")
	)
	(segment
		(start 110.788196 -14.94282)
		(end 110.847378 -14.686534)
		(width 0.127)
		(layer "In2.Cu")
		(net "P3E_CPU0_PE2_SS_C_TXP<13>")
	)
	(segment
		(start 110.916212 -14.060932)
		(end 110.927642 -13.933932)
		(width 0.127)
		(layer "In2.Cu")
		(net "P3E_CPU0_PE2_SS_C_TXP<13>")
	)
	(segment
		(start 103.815896 -24.862536)
		(end 104.041956 -24.820118)
		(width 0.127)
		(layer "In2.Cu")
		(net "P3E_CPU0_PE2_SS_C_TXP<13>")
	)
	(segment
		(start 103.090726 -26.603706)
		(end 103.40848 -25.747218)
		(width 0.127)
		(layer "In2.Cu")
		(net "P3E_CPU0_PE2_SS_C_TXP<13>")
	)
	(segment
		(start 104.655112 -23.922228)
		(end 110.788196 -14.94282)
		(width 0.127)
		(layer "In2.Cu")
		(net "P3E_CPU0_PE2_SS_C_TXP<13>")
	)
	(segment
		(start 104.041956 -24.820118)
		(end 104.25684 -24.505412)
		(width 0.127)
		(layer "In2.Cu")
		(net "P3E_CPU0_PE2_SS_C_TXP<13>")
	)
	(segment
		(start 112.366044 -8.276844)
		(end 112.441228 -8.20166)
		(width 0.127)
		(layer "In2.Cu")
		(net "P3E_CPU0_PE2_SS_C_TXP<13>")
	)
	(segment
		(start 111.461804 -12.640564)
		(end 111.6838 -12.418568)
		(width 0.127)
		(layer "In2.Cu")
		(net "P3E_CPU0_PE2_SS_C_TXP<13>")
	)
	(segment
		(start 102.989634 -27.803348)
		(end 102.99065 -27.802332)
		(width 0.127)
		(layer "In2.Cu")
		(net "P3E_CPU0_PE2_SS_C_TXP<13>")
	)
	(segment
		(start 118.661688 -2.294382)
		(end 121.45391 1.69291)
		(width 0.127)
		(layer "In2.Cu")
		(net "P3E_CPU0_PE2_SS_C_TXP<13>")
	)
	(segment
		(start 110.869984 -14.584172)
		(end 110.916212 -14.060932)
		(width 0.127)
		(layer "In2.Cu")
		(net "P3E_CPU0_PE2_SS_C_TXP<13>")
	)
	(segment
		(start 110.870746 -14.58595)
		(end 110.869476 -14.585696)
		(width 0.127)
		(layer "In2.Cu")
		(net "P3E_CPU0_PE2_SS_C_TXP<13>")
	)
	(segment
		(start 121.45391 1.69291)
		(end 122.14225 2.67589)
		(width 0.127)
		(layer "In2.Cu")
		(net "P3E_CPU0_PE2_SS_C_TXP<13>")
	)
	(segment
		(start 103.601012 -25.177242)
		(end 103.815896 -24.862536)
		(width 0.127)
		(layer "In2.Cu")
		(net "P3E_CPU0_PE2_SS_C_TXP<13>")
	)
	(segment
		(start 103.643684 -25.403048)
		(end 103.601012 -25.177242)
		(width 0.127)
		(layer "In2.Cu")
		(net "P3E_CPU0_PE2_SS_C_TXP<13>")
	)
	(segment
		(start 122.575066 6.590284)
		(end 122.575066 7.291578)
		(width 0.127)
		(layer "In2.Cu")
		(net "P3E_CPU0_PE2_SS_C_TXP<13>")
	)
	(segment
		(start 102.987856 -27.653742)
		(end 103.090726 -26.603706)
		(width 0.127)
		(layer "In2.Cu")
		(net "P3E_CPU0_PE2_SS_C_TXP<13>")
	)
	(segment
		(start 110.847378 -14.686534)
		(end 110.870238 -14.587474)
		(width 0.127)
		(layer "In2.Cu")
		(net "P3E_CPU0_PE2_SS_C_TXP<13>")
	)
	(segment
		(start 104.25684 -24.505412)
		(end 104.214168 -24.279606)
		(width 0.127)
		(layer "In2.Cu")
		(net "P3E_CPU0_PE2_SS_C_TXP<13>")
	)
	(segment
		(start 104.214168 -24.279606)
		(end 104.429052 -23.9649)
		(width 0.127)
		(layer "In2.Cu")
		(net "P3E_CPU0_PE2_SS_C_TXP<13>")
	)
	(segment
		(start 102.989634 -27.803602)
		(end 102.989634 -27.803348)
		(width 0.127)
		(layer "In2.Cu")
		(net "P3E_CPU0_PE2_SS_C_TXP<13>")
	)
	(segment
		(start 112.9665 -6.934454)
		(end 112.9665 -6.829806)
		(width 0.127)
		(layer "In2.Cu")
		(net "P3E_CPU0_PE2_SS_C_TXP<13>")
	)
	(segment
		(start 102.987856 -27.674316)
		(end 102.987856 -27.653742)
		(width 0.127)
		(layer "In2.Cu")
		(net "P3E_CPU0_PE2_SS_C_TXP<13>")
	)
	(arc
		(start 102.741476 -28.325826)
		(mid 102.946926 -28.12406)
		(end 102.994968 -27.840178)
		(width 0.127)
		(layer "In2.Cu")
		(net "P3E_CPU0_PE2_SS_C_TXP<13>")
	)
	(arc
		(start 122.578622 5.564886)
		(mid 122.554907 5.926964)
		(end 122.578622 6.28904)
		(width 0.127)
		(layer "In2.Cu")
		(net "P3E_CPU0_PE2_SS_C_TXP<13>")
	)
	(arc
		(start 112.9665 -6.829806)
		(mid 113.048416 -6.41828)
		(end 113.28146 -6.06933)
		(width 0.127)
		(layer "In2.Cu")
		(net "P3E_CPU0_PE2_SS_C_TXP<13>")
	)
	(arc
		(start 112.441228 -8.20166)
		(mid 112.829872 -7.620291)
		(end 112.9665 -6.934454)
		(width 0.127)
		(layer "In2.Cu")
		(net "P3E_CPU0_PE2_SS_C_TXP<13>")
	)
	(arc
		(start 122.575066 7.291578)
		(mid 122.471924 7.589405)
		(end 122.196606 7.742682)
		(width 0.127)
		(layer "In2.Cu")
		(net "P3E_CPU0_PE2_SS_C_TXP<13>")
	)
	(arc
		(start 110.92688 -13.932408)
		(mid 111.065904 -13.233306)
		(end 111.461804 -12.640564)
		(width 0.127)
		(layer "In2.Cu")
		(net "P3E_CPU0_PE2_SS_C_TXP<13>")
	)
	(arc
		(start 111.6838 -12.418568)
		(mid 111.849117 -12.171293)
		(end 111.90732 -11.87958)
		(width 0.127)
		(layer "In2.Cu")
		(net "P3E_CPU0_PE2_SS_C_TXP<13>")
	)
	(arc
		(start 111.90732 -9.385046)
		(mid 112.026497 -8.785341)
		(end 112.366044 -8.276844)
		(width 0.127)
		(layer "In2.Cu")
		(net "P3E_CPU0_PE2_SS_C_TXP<13>")
	)
	(arc
		(start 122.592084 5.164074)
		(mid 122.595167 5.364809)
		(end 122.578622 5.564886)
		(width 0.127)
		(layer "In2.Cu")
		(net "P3E_CPU0_PE2_SS_C_TXP<13>")
	)
	(arc
		(start 122.578622 6.28904)
		(mid 122.578903 6.439686)
		(end 122.575066 6.590284)
		(width 0.127)
		(layer "In2.Cu")
		(net "P3E_CPU0_PE2_SS_C_TXP<13>")
	)
	(arc
		(start 102.457758 -28.325826)
		(mid 102.531244 -28.389445)
		(end 102.628192 -28.382468)
		(width 0.127)
		(layer "In2.Cu")
		(net "P3E_CPU0_PE2_SS_C_TXP<13>")
	)
	(arc
		(start 122.56135 4.918202)
		(mid 122.580436 5.040673)
		(end 122.592084 5.164074)
		(width 0.127)
		(layer "In2.Cu")
		(net "P3E_CPU0_PE2_SS_C_TXP<13>")
	)
	(arc
		(start 113.28146 -6.06933)
		(mid 113.291304 -6.059615)
		(end 113.301272 -6.050026)
		(width 0.127)
		(layer "In2.Cu")
		(net "P3E_CPU0_PE2_SS_C_TXP<13>")
	)
	(segment
		(start 119.973852 8.04164)
		(end 119.973852 8.47344)
		(width 0.127)
		(layer "F.Cu")
		(net "P3E_CPU0_PE2_SS_C_TXP<12>")
	)
	(segment
		(start 119.973852 8.47344)
		(end 119.969026 8.480298)
		(width 0.127)
		(layer "F.Cu")
		(net "P3E_CPU0_PE2_SS_C_TXP<12>")
	)
	(segment
		(start 119.627142 10.422636)
		(end 119.62257 10.484866)
		(width 0.127)
		(layer "F.Cu")
		(net "P3E_CPU0_PE2_SS_C_TXP<12>")
	)
	(segment
		(start 119.37492 11.082274)
		(end 119.375174 12.234672)
		(width 0.127)
		(layer "F.Cu")
		(net "P3E_CPU0_PE2_SS_C_TXP<12>")
	)
	(segment
		(start 119.498618 10.78357)
		(end 119.498364 10.783824)
		(width 0.127)
		(layer "F.Cu")
		(net "P3E_CPU0_PE2_SS_C_TXP<12>")
	)
	(segment
		(start 119.969026 8.480298)
		(end 119.627142 10.422636)
		(width 0.127)
		(layer "F.Cu")
		(net "P3E_CPU0_PE2_SS_C_TXP<12>")
	)
	(segment
		(start 119.605806 7.742682)
		(end 119.674894 7.742682)
		(width 0.127)
		(layer "F.Cu")
		(net "P3E_CPU0_PE2_SS_C_TXP<12>")
	)
	(via
		(at 119.605806 7.742682)
		(size 0.508)
		(drill 0.254)
		(layers "F.Cu" "B.Cu")
		(net "P3E_CPU0_PE2_SS_C_TXP<12>")
	)
	(arc
		(start 119.62257 10.484866)
		(mid 119.590314 10.646556)
		(end 119.498618 10.78357)
		(width 0.127)
		(layer "F.Cu")
		(net "P3E_CPU0_PE2_SS_C_TXP<12>")
	)
	(arc
		(start 119.674894 7.742682)
		(mid 119.886289 7.830245)
		(end 119.973852 8.04164)
		(width 0.127)
		(layer "F.Cu")
		(net "P3E_CPU0_PE2_SS_C_TXP<12>")
	)
	(arc
		(start 119.498364 10.783824)
		(mid 119.406978 10.920782)
		(end 119.37492 11.082274)
		(width 0.127)
		(layer "F.Cu")
		(net "P3E_CPU0_PE2_SS_C_TXP<12>")
	)
	(segment
		(start 99.532948 -25.62987)
		(end 99.400106 -25.986994)
		(width 0.127)
		(layer "In2.Cu")
		(net "P3E_CPU0_PE2_SS_C_TXP<12>")
	)
	(segment
		(start 100.153724 -23.968202)
		(end 100.149914 -23.973536)
		(width 0.127)
		(layer "In2.Cu")
		(net "P3E_CPU0_PE2_SS_C_TXP<12>")
	)
	(segment
		(start 99.400106 -25.986994)
		(end 99.191064 -26.082752)
		(width 0.127)
		(layer "In2.Cu")
		(net "P3E_CPU0_PE2_SS_C_TXP<12>")
	)
	(segment
		(start 99.191064 -26.082752)
		(end 99.057968 -26.439622)
		(width 0.127)
		(layer "In2.Cu")
		(net "P3E_CPU0_PE2_SS_C_TXP<12>")
	)
	(segment
		(start 106.92765 -13.932408)
		(end 106.84256 -14.41577)
		(width 0.127)
		(layer "In2.Cu")
		(net "P3E_CPU0_PE2_SS_C_TXP<12>")
	)
	(segment
		(start 99.057968 -26.439622)
		(end 99.153726 -26.648664)
		(width 0.127)
		(layer "In2.Cu")
		(net "P3E_CPU0_PE2_SS_C_TXP<12>")
	)
	(segment
		(start 98.458528 -28.325826)
		(end 98.080322 -27.570176)
		(width 0.127)
		(layer "In2.Cu")
		(net "P3E_CPU0_PE2_SS_C_TXP<12>")
	)
	(segment
		(start 106.94035 -6.575044)
		(end 106.94035 -7.115302)
		(width 0.127)
		(layer "In2.Cu")
		(net "P3E_CPU0_PE2_SS_C_TXP<12>")
	)
	(segment
		(start 107.994196 -4.235196)
		(end 107.136946 -5.459222)
		(width 0.127)
		(layer "In2.Cu")
		(net "P3E_CPU0_PE2_SS_C_TXP<12>")
	)
	(segment
		(start 108.532676 -3.858006)
		(end 107.994196 -4.235196)
		(width 0.127)
		(layer "In2.Cu")
		(net "P3E_CPU0_PE2_SS_C_TXP<12>")
	)
	(segment
		(start 99.779582 -24.9682)
		(end 99.570286 -25.063958)
		(width 0.127)
		(layer "In2.Cu")
		(net "P3E_CPU0_PE2_SS_C_TXP<12>")
	)
	(segment
		(start 99.437444 -25.420828)
		(end 99.532948 -25.62987)
		(width 0.127)
		(layer "In2.Cu")
		(net "P3E_CPU0_PE2_SS_C_TXP<12>")
	)
	(segment
		(start 98.742246 -28.325826)
		(end 98.629216 -28.382468)
		(width 0.127)
		(layer "In2.Cu")
		(net "P3E_CPU0_PE2_SS_C_TXP<12>")
	)
	(segment
		(start 119.968264 4.904994)
		(end 119.549926 2.743962)
		(width 0.127)
		(layer "In2.Cu")
		(net "P3E_CPU0_PE2_SS_C_TXP<12>")
	)
	(segment
		(start 107.136946 -5.459222)
		(end 106.94035 -6.575044)
		(width 0.127)
		(layer "In2.Cu")
		(net "P3E_CPU0_PE2_SS_C_TXP<12>")
	)
	(segment
		(start 107.378754 -8.174736)
		(end 107.486958 -8.28294)
		(width 0.127)
		(layer "In2.Cu")
		(net "P3E_CPU0_PE2_SS_C_TXP<12>")
	)
	(segment
		(start 116.93398 -0.992124)
		(end 114.29111 -2.84226)
		(width 0.127)
		(layer "In2.Cu")
		(net "P3E_CPU0_PE2_SS_C_TXP<12>")
	)
	(segment
		(start 119.233188 2.291588)
		(end 116.93398 -0.992124)
		(width 0.127)
		(layer "In2.Cu")
		(net "P3E_CPU0_PE2_SS_C_TXP<12>")
	)
	(segment
		(start 106.84256 -14.41577)
		(end 100.153724 -23.968202)
		(width 0.127)
		(layer "In2.Cu")
		(net "P3E_CPU0_PE2_SS_C_TXP<12>")
	)
	(segment
		(start 99.153726 -26.648664)
		(end 99.02063 -27.005788)
		(width 0.127)
		(layer "In2.Cu")
		(net "P3E_CPU0_PE2_SS_C_TXP<12>")
	)
	(segment
		(start 107.68457 -12.418568)
		(end 107.462574 -12.640564)
		(width 0.127)
		(layer "In2.Cu")
		(net "P3E_CPU0_PE2_SS_C_TXP<12>")
	)
	(segment
		(start 114.29111 -2.84226)
		(end 108.532676 -3.858006)
		(width 0.127)
		(layer "In2.Cu")
		(net "P3E_CPU0_PE2_SS_C_TXP<12>")
	)
	(segment
		(start 98.629216 -28.382468)
		(end 98.628962 -28.382468)
		(width 0.127)
		(layer "In2.Cu")
		(net "P3E_CPU0_PE2_SS_C_TXP<12>")
	)
	(segment
		(start 119.549926 2.743962)
		(end 119.233188 2.291588)
		(width 0.127)
		(layer "In2.Cu")
		(net "P3E_CPU0_PE2_SS_C_TXP<12>")
	)
	(segment
		(start 99.570286 -25.063958)
		(end 99.437444 -25.420828)
		(width 0.127)
		(layer "In2.Cu")
		(net "P3E_CPU0_PE2_SS_C_TXP<12>")
	)
	(segment
		(start 100.149914 -23.973536)
		(end 99.779582 -24.9682)
		(width 0.127)
		(layer "In2.Cu")
		(net "P3E_CPU0_PE2_SS_C_TXP<12>")
	)
	(segment
		(start 107.90809 -9.298686)
		(end 107.90809 -11.87958)
		(width 0.127)
		(layer "In2.Cu")
		(net "P3E_CPU0_PE2_SS_C_TXP<12>")
	)
	(arc
		(start 120.008142 7.071106)
		(mid 120.018467 6.67954)
		(end 119.987822 6.28904)
		(width 0.127)
		(layer "In2.Cu")
		(net "P3E_CPU0_PE2_SS_C_TXP<12>")
	)
	(arc
		(start 106.94035 -7.115302)
		(mid 107.054117 -7.688661)
		(end 107.378754 -8.174736)
		(width 0.127)
		(layer "In2.Cu")
		(net "P3E_CPU0_PE2_SS_C_TXP<12>")
	)
	(arc
		(start 107.486958 -8.28294)
		(mid 107.798514 -8.748938)
		(end 107.90809 -9.298686)
		(width 0.127)
		(layer "In2.Cu")
		(net "P3E_CPU0_PE2_SS_C_TXP<12>")
	)
	(arc
		(start 107.90809 -11.87958)
		(mid 107.849965 -12.171325)
		(end 107.68457 -12.418568)
		(width 0.127)
		(layer "In2.Cu")
		(net "P3E_CPU0_PE2_SS_C_TXP<12>")
	)
	(arc
		(start 99.02063 -27.005788)
		(mid 98.97143 -27.421885)
		(end 98.995738 -27.840178)
		(width 0.127)
		(layer "In2.Cu")
		(net "P3E_CPU0_PE2_SS_C_TXP<12>")
	)
	(arc
		(start 119.987822 5.564886)
		(mid 120.004769 5.234147)
		(end 119.968264 4.904994)
		(width 0.127)
		(layer "In2.Cu")
		(net "P3E_CPU0_PE2_SS_C_TXP<12>")
	)
	(arc
		(start 119.605806 7.742682)
		(mid 119.880972 7.589277)
		(end 119.984266 7.291578)
		(width 0.127)
		(layer "In2.Cu")
		(net "P3E_CPU0_PE2_SS_C_TXP<12>")
	)
	(arc
		(start 98.628962 -28.382468)
		(mid 98.532014 -28.389445)
		(end 98.458528 -28.325826)
		(width 0.127)
		(layer "In2.Cu")
		(net "P3E_CPU0_PE2_SS_C_TXP<12>")
	)
	(arc
		(start 107.462574 -12.640564)
		(mid 107.06665 -13.233296)
		(end 106.92765 -13.932408)
		(width 0.127)
		(layer "In2.Cu")
		(net "P3E_CPU0_PE2_SS_C_TXP<12>")
	)
	(arc
		(start 119.987822 6.28904)
		(mid 119.96414 5.926964)
		(end 119.987822 5.564886)
		(width 0.127)
		(layer "In2.Cu")
		(net "P3E_CPU0_PE2_SS_C_TXP<12>")
	)
	(arc
		(start 98.995738 -27.840178)
		(mid 98.947583 -28.124001)
		(end 98.742246 -28.325826)
		(width 0.127)
		(layer "In2.Cu")
		(net "P3E_CPU0_PE2_SS_C_TXP<12>")
	)
	(arc
		(start 119.984266 7.291578)
		(mid 119.997835 7.181519)
		(end 120.008142 7.071106)
		(width 0.127)
		(layer "In2.Cu")
		(net "P3E_CPU0_PE2_SS_C_TXP<12>")
	)
	(segment
		(start 117.383052 8.639556)
		(end 117.383052 8.04164)
		(width 0.127)
		(layer "F.Cu")
		(net "P3E_CPU0_PE2_SS_C_TXP<11>")
	)
	(segment
		(start 117.222778 9.577578)
		(end 117.220238 9.562846)
		(width 0.127)
		(layer "F.Cu")
		(net "P3E_CPU0_PE2_SS_C_TXP<11>")
	)
	(segment
		(start 117.084094 7.742682)
		(end 117.015006 7.742682)
		(width 0.127)
		(layer "F.Cu")
		(net "P3E_CPU0_PE2_SS_C_TXP<11>")
	)
	(segment
		(start 117.098572 10.783824)
		(end 117.098826 10.78357)
		(width 0.127)
		(layer "F.Cu")
		(net "P3E_CPU0_PE2_SS_C_TXP<11>")
	)
	(segment
		(start 116.975128 12.234672)
		(end 116.975128 11.082274)
		(width 0.127)
		(layer "F.Cu")
		(net "P3E_CPU0_PE2_SS_C_TXP<11>")
	)
	(segment
		(start 117.222778 10.484866)
		(end 117.222778 9.577578)
		(width 0.127)
		(layer "F.Cu")
		(net "P3E_CPU0_PE2_SS_C_TXP<11>")
	)
	(segment
		(start 117.220238 9.562846)
		(end 117.383052 8.639556)
		(width 0.127)
		(layer "F.Cu")
		(net "P3E_CPU0_PE2_SS_C_TXP<11>")
	)
	(via
		(at 117.015006 7.742682)
		(size 0.508)
		(drill 0.254)
		(layers "F.Cu" "B.Cu")
		(net "P3E_CPU0_PE2_SS_C_TXP<11>")
	)
	(arc
		(start 117.098826 10.78357)
		(mid 117.190481 10.646538)
		(end 117.222778 10.484866)
		(width 0.127)
		(layer "F.Cu")
		(net "P3E_CPU0_PE2_SS_C_TXP<11>")
	)
	(arc
		(start 117.383052 8.04164)
		(mid 117.295489 7.830245)
		(end 117.084094 7.742682)
		(width 0.127)
		(layer "F.Cu")
		(net "P3E_CPU0_PE2_SS_C_TXP<11>")
	)
	(arc
		(start 116.975128 11.082274)
		(mid 117.007213 10.920794)
		(end 117.098572 10.783824)
		(width 0.127)
		(layer "F.Cu")
		(net "P3E_CPU0_PE2_SS_C_TXP<11>")
	)
	(segment
		(start 103.90759 -9.298686)
		(end 103.90759 -11.87958)
		(width 0.127)
		(layer "In2.Cu")
		(net "P3E_CPU0_PE2_SS_C_TXP<11>")
	)
	(segment
		(start 94.628716 -28.382468)
		(end 94.628462 -28.382468)
		(width 0.127)
		(layer "In2.Cu")
		(net "P3E_CPU0_PE2_SS_C_TXP<11>")
	)
	(segment
		(start 103.378254 -8.174736)
		(end 103.486458 -8.28294)
		(width 0.127)
		(layer "In2.Cu")
		(net "P3E_CPU0_PE2_SS_C_TXP<11>")
	)
	(segment
		(start 117.393466 7.291578)
		(end 117.393466 6.601714)
		(width 0.127)
		(layer "In2.Cu")
		(net "P3E_CPU0_PE2_SS_C_TXP<11>")
	)
	(segment
		(start 102.896416 -14.341348)
		(end 96.65843 -23.250398)
		(width 0.127)
		(layer "In2.Cu")
		(net "P3E_CPU0_PE2_SS_C_TXP<11>")
	)
	(segment
		(start 95.41129 -25.031446)
		(end 95.015558 -27.029664)
		(width 0.127)
		(layer "In2.Cu")
		(net "P3E_CPU0_PE2_SS_C_TXP<11>")
	)
	(segment
		(start 96.03486 -24.140922)
		(end 95.808546 -24.1808)
		(width 0.127)
		(layer "In2.Cu")
		(net "P3E_CPU0_PE2_SS_C_TXP<11>")
	)
	(segment
		(start 95.62973 -24.71928)
		(end 95.41129 -25.031446)
		(width 0.127)
		(layer "In2.Cu")
		(net "P3E_CPU0_PE2_SS_C_TXP<11>")
	)
	(segment
		(start 102.92715 -13.932408)
		(end 102.92715 -14.19352)
		(width 0.127)
		(layer "In2.Cu")
		(net "P3E_CPU0_PE2_SS_C_TXP<11>")
	)
	(segment
		(start 103.68407 -12.418568)
		(end 103.462074 -12.640564)
		(width 0.127)
		(layer "In2.Cu")
		(net "P3E_CPU0_PE2_SS_C_TXP<11>")
	)
	(segment
		(start 95.589852 -24.492966)
		(end 95.62973 -24.71928)
		(width 0.127)
		(layer "In2.Cu")
		(net "P3E_CPU0_PE2_SS_C_TXP<11>")
	)
	(segment
		(start 96.2533 -23.828756)
		(end 96.03486 -24.140922)
		(width 0.127)
		(layer "In2.Cu")
		(net "P3E_CPU0_PE2_SS_C_TXP<11>")
	)
	(segment
		(start 115.999006 1.579118)
		(end 115.42776 1.179068)
		(width 0.127)
		(layer "In2.Cu")
		(net "P3E_CPU0_PE2_SS_C_TXP<11>")
	)
	(segment
		(start 106.731054 -2.182876)
		(end 104.375204 -3.832606)
		(width 0.127)
		(layer "In2.Cu")
		(net "P3E_CPU0_PE2_SS_C_TXP<11>")
	)
	(segment
		(start 117.393466 6.601714)
		(end 117.347746 6.06298)
		(width 0.127)
		(layer "In2.Cu")
		(net "P3E_CPU0_PE2_SS_C_TXP<11>")
	)
	(segment
		(start 117.347746 6.061456)
		(end 117.4115 5.54355)
		(width 0.127)
		(layer "In2.Cu")
		(net "P3E_CPU0_PE2_SS_C_TXP<11>")
	)
	(segment
		(start 96.431862 -23.290276)
		(end 96.213422 -23.602442)
		(width 0.127)
		(layer "In2.Cu")
		(net "P3E_CPU0_PE2_SS_C_TXP<11>")
	)
	(segment
		(start 117.310154 3.450844)
		(end 115.999006 1.579118)
		(width 0.127)
		(layer "In2.Cu")
		(net "P3E_CPU0_PE2_SS_C_TXP<11>")
	)
	(segment
		(start 102.93985 -6.743446)
		(end 102.93985 -7.115302)
		(width 0.127)
		(layer "In2.Cu")
		(net "P3E_CPU0_PE2_SS_C_TXP<11>")
	)
	(segment
		(start 95.808546 -24.1808)
		(end 95.589852 -24.492966)
		(width 0.127)
		(layer "In2.Cu")
		(net "P3E_CPU0_PE2_SS_C_TXP<11>")
	)
	(segment
		(start 104.375204 -3.832606)
		(end 103.142542 -5.592826)
		(width 0.127)
		(layer "In2.Cu")
		(net "P3E_CPU0_PE2_SS_C_TXP<11>")
	)
	(segment
		(start 96.65843 -23.250398)
		(end 96.431862 -23.290276)
		(width 0.127)
		(layer "In2.Cu")
		(net "P3E_CPU0_PE2_SS_C_TXP<11>")
	)
	(segment
		(start 117.347746 6.06298)
		(end 117.347746 6.061456)
		(width 0.127)
		(layer "In2.Cu")
		(net "P3E_CPU0_PE2_SS_C_TXP<11>")
	)
	(segment
		(start 94.458028 -28.325826)
		(end 94.079822 -27.570176)
		(width 0.127)
		(layer "In2.Cu")
		(net "P3E_CPU0_PE2_SS_C_TXP<11>")
	)
	(segment
		(start 96.213422 -23.602442)
		(end 96.2533 -23.828756)
		(width 0.127)
		(layer "In2.Cu")
		(net "P3E_CPU0_PE2_SS_C_TXP<11>")
	)
	(segment
		(start 102.92715 -14.19352)
		(end 102.896416 -14.341348)
		(width 0.127)
		(layer "In2.Cu")
		(net "P3E_CPU0_PE2_SS_C_TXP<11>")
	)
	(segment
		(start 117.4115 4.026154)
		(end 117.310154 3.450844)
		(width 0.127)
		(layer "In2.Cu")
		(net "P3E_CPU0_PE2_SS_C_TXP<11>")
	)
	(segment
		(start 117.4115 5.54355)
		(end 117.4115 4.026154)
		(width 0.127)
		(layer "In2.Cu")
		(net "P3E_CPU0_PE2_SS_C_TXP<11>")
	)
	(segment
		(start 94.741746 -28.325826)
		(end 94.628716 -28.382468)
		(width 0.127)
		(layer "In2.Cu")
		(net "P3E_CPU0_PE2_SS_C_TXP<11>")
	)
	(segment
		(start 103.142542 -5.592826)
		(end 102.93985 -6.743446)
		(width 0.127)
		(layer "In2.Cu")
		(net "P3E_CPU0_PE2_SS_C_TXP<11>")
	)
	(segment
		(start 111.937546 -1.264666)
		(end 106.731054 -2.182876)
		(width 0.127)
		(layer "In2.Cu")
		(net "P3E_CPU0_PE2_SS_C_TXP<11>")
	)
	(segment
		(start 115.42776 1.179068)
		(end 111.937546 -1.264666)
		(width 0.127)
		(layer "In2.Cu")
		(net "P3E_CPU0_PE2_SS_C_TXP<11>")
	)
	(arc
		(start 103.90759 -11.87958)
		(mid 103.849465 -12.171325)
		(end 103.68407 -12.418568)
		(width 0.127)
		(layer "In2.Cu")
		(net "P3E_CPU0_PE2_SS_C_TXP<11>")
	)
	(arc
		(start 103.486458 -8.28294)
		(mid 103.798014 -8.748938)
		(end 103.90759 -9.298686)
		(width 0.127)
		(layer "In2.Cu")
		(net "P3E_CPU0_PE2_SS_C_TXP<11>")
	)
	(arc
		(start 102.93985 -7.115302)
		(mid 103.053617 -7.688661)
		(end 103.378254 -8.174736)
		(width 0.127)
		(layer "In2.Cu")
		(net "P3E_CPU0_PE2_SS_C_TXP<11>")
	)
	(arc
		(start 117.015006 7.742682)
		(mid 117.290172 7.589277)
		(end 117.393466 7.291578)
		(width 0.127)
		(layer "In2.Cu")
		(net "P3E_CPU0_PE2_SS_C_TXP<11>")
	)
	(arc
		(start 103.462074 -12.640564)
		(mid 103.06615 -13.233296)
		(end 102.92715 -13.932408)
		(width 0.127)
		(layer "In2.Cu")
		(net "P3E_CPU0_PE2_SS_C_TXP<11>")
	)
	(arc
		(start 95.015558 -27.029664)
		(mid 94.970697 -27.434053)
		(end 94.995238 -27.840178)
		(width 0.127)
		(layer "In2.Cu")
		(net "P3E_CPU0_PE2_SS_C_TXP<11>")
	)
	(arc
		(start 94.995238 -27.840178)
		(mid 94.947083 -28.124001)
		(end 94.741746 -28.325826)
		(width 0.127)
		(layer "In2.Cu")
		(net "P3E_CPU0_PE2_SS_C_TXP<11>")
	)
	(arc
		(start 94.628462 -28.382468)
		(mid 94.531514 -28.389445)
		(end 94.458028 -28.325826)
		(width 0.127)
		(layer "In2.Cu")
		(net "P3E_CPU0_PE2_SS_C_TXP<11>")
	)
	(segment
		(start 114.792252 9.615678)
		(end 114.822478 9.786874)
		(width 0.127)
		(layer "F.Cu")
		(net "P3E_CPU0_PE2_SS_C_TXP<10>")
	)
	(segment
		(start 114.822478 9.786874)
		(end 114.822478 10.484866)
		(width 0.127)
		(layer "F.Cu")
		(net "P3E_CPU0_PE2_SS_C_TXP<10>")
	)
	(segment
		(start 114.575082 11.082274)
		(end 114.575082 12.234672)
		(width 0.127)
		(layer "F.Cu")
		(net "P3E_CPU0_PE2_SS_C_TXP<10>")
	)
	(segment
		(start 114.822478 10.484866)
		(end 114.822732 10.484866)
		(width 0.127)
		(layer "F.Cu")
		(net "P3E_CPU0_PE2_SS_C_TXP<10>")
	)
	(segment
		(start 114.69878 10.78357)
		(end 114.698526 10.783824)
		(width 0.127)
		(layer "F.Cu")
		(net "P3E_CPU0_PE2_SS_C_TXP<10>")
	)
	(segment
		(start 114.424206 7.742682)
		(end 114.493294 7.742682)
		(width 0.127)
		(layer "F.Cu")
		(net "P3E_CPU0_PE2_SS_C_TXP<10>")
	)
	(segment
		(start 114.792252 8.04164)
		(end 114.792252 9.615678)
		(width 0.127)
		(layer "F.Cu")
		(net "P3E_CPU0_PE2_SS_C_TXP<10>")
	)
	(via
		(at 114.424206 7.742682)
		(size 0.508)
		(drill 0.254)
		(layers "F.Cu" "B.Cu")
		(net "P3E_CPU0_PE2_SS_C_TXP<10>")
	)
	(arc
		(start 114.822732 10.484866)
		(mid 114.790476 10.646556)
		(end 114.69878 10.78357)
		(width 0.127)
		(layer "F.Cu")
		(net "P3E_CPU0_PE2_SS_C_TXP<10>")
	)
	(arc
		(start 114.493294 7.742682)
		(mid 114.704689 7.830245)
		(end 114.792252 8.04164)
		(width 0.127)
		(layer "F.Cu")
		(net "P3E_CPU0_PE2_SS_C_TXP<10>")
	)
	(arc
		(start 114.698526 10.783824)
		(mid 114.60714 10.920782)
		(end 114.575082 11.082274)
		(width 0.127)
		(layer "F.Cu")
		(net "P3E_CPU0_PE2_SS_C_TXP<10>")
	)
	(segment
		(start 114.802666 7.291578)
		(end 114.802666 6.601714)
		(width 0.127)
		(layer "In2.Cu")
		(net "P3E_CPU0_PE2_SS_C_TXP<10>")
	)
	(segment
		(start 114.820446 5.534406)
		(end 114.8207 5.534406)
		(width 0.127)
		(layer "In2.Cu")
		(net "P3E_CPU0_PE2_SS_C_TXP<10>")
	)
	(segment
		(start 91.02852 -26.976578)
		(end 91.022424 -26.99639)
		(width 0.127)
		(layer "In2.Cu")
		(net "P3E_CPU0_PE2_SS_C_TXP<10>")
	)
	(segment
		(start 91.029536 -26.974292)
		(end 91.029028 -26.975054)
		(width 0.127)
		(layer "In2.Cu")
		(net "P3E_CPU0_PE2_SS_C_TXP<10>")
	)
	(segment
		(start 91.06535 -26.8605)
		(end 91.029536 -26.974292)
		(width 0.127)
		(layer "In2.Cu")
		(net "P3E_CPU0_PE2_SS_C_TXP<10>")
	)
	(segment
		(start 114.759994 4.200906)
		(end 114.586512 3.21564)
		(width 0.127)
		(layer "In2.Cu")
		(net "P3E_CPU0_PE2_SS_C_TXP<10>")
	)
	(segment
		(start 90.741246 -28.325826)
		(end 90.628216 -28.382468)
		(width 0.127)
		(layer "In2.Cu")
		(net "P3E_CPU0_PE2_SS_C_TXP<10>")
	)
	(segment
		(start 91.650058 -25.513792)
		(end 91.498166 -25.863296)
		(width 0.127)
		(layer "In2.Cu")
		(net "P3E_CPU0_PE2_SS_C_TXP<10>")
	)
	(segment
		(start 114.586512 3.21564)
		(end 114.323876 2.840736)
		(width 0.127)
		(layer "In2.Cu")
		(net "P3E_CPU0_PE2_SS_C_TXP<10>")
	)
	(segment
		(start 114.802666 6.601714)
		(end 114.74323 5.940552)
		(width 0.127)
		(layer "In2.Cu")
		(net "P3E_CPU0_PE2_SS_C_TXP<10>")
	)
	(segment
		(start 91.717368 -24.95042)
		(end 91.565476 -25.299924)
		(width 0.127)
		(layer "In2.Cu")
		(net "P3E_CPU0_PE2_SS_C_TXP<10>")
	)
	(segment
		(start 104.374442 -0.612394)
		(end 104.068626 -0.705104)
		(width 0.127)
		(layer "In2.Cu")
		(net "P3E_CPU0_PE2_SS_C_TXP<10>")
	)
	(segment
		(start 91.029028 -26.975054)
		(end 91.02852 -26.976578)
		(width 0.127)
		(layer "In2.Cu")
		(net "P3E_CPU0_PE2_SS_C_TXP<10>")
	)
	(segment
		(start 91.565476 -25.299924)
		(end 91.650058 -25.513792)
		(width 0.127)
		(layer "In2.Cu")
		(net "P3E_CPU0_PE2_SS_C_TXP<10>")
	)
	(segment
		(start 114.74323 5.940552)
		(end 114.750342 5.875274)
		(width 0.127)
		(layer "In2.Cu")
		(net "P3E_CPU0_PE2_SS_C_TXP<10>")
	)
	(segment
		(start 104.068626 -0.705104)
		(end 102.421944 -2.351786)
		(width 0.127)
		(layer "In2.Cu")
		(net "P3E_CPU0_PE2_SS_C_TXP<10>")
	)
	(segment
		(start 114.8207 5.534406)
		(end 114.8207 4.557014)
		(width 0.127)
		(layer "In2.Cu")
		(net "P3E_CPU0_PE2_SS_C_TXP<10>")
	)
	(segment
		(start 91.021916 -26.997406)
		(end 91.021662 -26.997406)
		(width 0.127)
		(layer "In2.Cu")
		(net "P3E_CPU0_PE2_SS_C_TXP<10>")
	)
	(segment
		(start 99.90836 -9.298686)
		(end 99.90836 -11.87958)
		(width 0.127)
		(layer "In2.Cu")
		(net "P3E_CPU0_PE2_SS_C_TXP<10>")
	)
	(segment
		(start 91.021662 -26.997406)
		(end 91.021154 -26.998422)
		(width 0.127)
		(layer "In2.Cu")
		(net "P3E_CPU0_PE2_SS_C_TXP<10>")
	)
	(segment
		(start 91.931236 -24.866092)
		(end 91.717368 -24.95042)
		(width 0.127)
		(layer "In2.Cu")
		(net "P3E_CPU0_PE2_SS_C_TXP<10>")
	)
	(segment
		(start 90.628216 -28.382468)
		(end 90.627962 -28.382468)
		(width 0.127)
		(layer "In2.Cu")
		(net "P3E_CPU0_PE2_SS_C_TXP<10>")
	)
	(segment
		(start 99.212908 -6.2738)
		(end 98.993198 -6.587744)
		(width 0.127)
		(layer "In2.Cu")
		(net "P3E_CPU0_PE2_SS_C_TXP<10>")
	)
	(segment
		(start 98.993198 -6.587744)
		(end 98.94062 -6.886702)
		(width 0.127)
		(layer "In2.Cu")
		(net "P3E_CPU0_PE2_SS_C_TXP<10>")
	)
	(segment
		(start 92.68333 -23.133304)
		(end 91.931236 -24.866092)
		(width 0.127)
		(layer "In2.Cu")
		(net "P3E_CPU0_PE2_SS_C_TXP<10>")
	)
	(segment
		(start 114.323876 2.840736)
		(end 111.08182 0.570484)
		(width 0.127)
		(layer "In2.Cu")
		(net "P3E_CPU0_PE2_SS_C_TXP<10>")
	)
	(segment
		(start 114.8207 4.557014)
		(end 114.818414 4.531614)
		(width 0.127)
		(layer "In2.Cu")
		(net "P3E_CPU0_PE2_SS_C_TXP<10>")
	)
	(segment
		(start 91.022424 -26.99639)
		(end 91.021916 -26.997406)
		(width 0.127)
		(layer "In2.Cu")
		(net "P3E_CPU0_PE2_SS_C_TXP<10>")
	)
	(segment
		(start 99.379024 -8.174736)
		(end 99.487228 -8.28294)
		(width 0.127)
		(layer "In2.Cu")
		(net "P3E_CPU0_PE2_SS_C_TXP<10>")
	)
	(segment
		(start 111.08182 0.570484)
		(end 104.374442 -0.612394)
		(width 0.127)
		(layer "In2.Cu")
		(net "P3E_CPU0_PE2_SS_C_TXP<10>")
	)
	(segment
		(start 98.777298 -14.79296)
		(end 92.68333 -23.133304)
		(width 0.127)
		(layer "In2.Cu")
		(net "P3E_CPU0_PE2_SS_C_TXP<10>")
	)
	(segment
		(start 99.68484 -12.418568)
		(end 99.462844 -12.640564)
		(width 0.127)
		(layer "In2.Cu")
		(net "P3E_CPU0_PE2_SS_C_TXP<10>")
	)
	(segment
		(start 114.818414 4.531614)
		(end 114.759994 4.200906)
		(width 0.127)
		(layer "In2.Cu")
		(net "P3E_CPU0_PE2_SS_C_TXP<10>")
	)
	(segment
		(start 114.424206 7.742682)
		(end 114.751358 7.41553)
		(width 0.127)
		(layer "In2.Cu")
		(net "P3E_CPU0_PE2_SS_C_TXP<10>")
	)
	(segment
		(start 91.498166 -25.863296)
		(end 91.284298 -25.947624)
		(width 0.127)
		(layer "In2.Cu")
		(net "P3E_CPU0_PE2_SS_C_TXP<10>")
	)
	(segment
		(start 91.216988 -26.510996)
		(end 91.06535 -26.8605)
		(width 0.127)
		(layer "In2.Cu")
		(net "P3E_CPU0_PE2_SS_C_TXP<10>")
	)
	(segment
		(start 91.284298 -25.947624)
		(end 91.13266 -26.297128)
		(width 0.127)
		(layer "In2.Cu")
		(net "P3E_CPU0_PE2_SS_C_TXP<10>")
	)
	(segment
		(start 91.13266 -26.297128)
		(end 91.216988 -26.510996)
		(width 0.127)
		(layer "In2.Cu")
		(net "P3E_CPU0_PE2_SS_C_TXP<10>")
	)
	(segment
		(start 90.457528 -28.325826)
		(end 90.079322 -27.570176)
		(width 0.127)
		(layer "In2.Cu")
		(net "P3E_CPU0_PE2_SS_C_TXP<10>")
	)
	(segment
		(start 99.22637 -6.256274)
		(end 99.212908 -6.2738)
		(width 0.127)
		(layer "In2.Cu")
		(net "P3E_CPU0_PE2_SS_C_TXP<10>")
	)
	(segment
		(start 114.750342 5.875274)
		(end 114.820446 5.534406)
		(width 0.127)
		(layer "In2.Cu")
		(net "P3E_CPU0_PE2_SS_C_TXP<10>")
	)
	(segment
		(start 98.94062 -6.886702)
		(end 98.94062 -7.115302)
		(width 0.127)
		(layer "In2.Cu")
		(net "P3E_CPU0_PE2_SS_C_TXP<10>")
	)
	(segment
		(start 98.92792 -13.932408)
		(end 98.92792 -14.438122)
		(width 0.127)
		(layer "In2.Cu")
		(net "P3E_CPU0_PE2_SS_C_TXP<10>")
	)
	(segment
		(start 102.421944 -2.351786)
		(end 99.22637 -6.256274)
		(width 0.127)
		(layer "In2.Cu")
		(net "P3E_CPU0_PE2_SS_C_TXP<10>")
	)
	(segment
		(start 98.92792 -14.438122)
		(end 98.777298 -14.79296)
		(width 0.127)
		(layer "In2.Cu")
		(net "P3E_CPU0_PE2_SS_C_TXP<10>")
	)
	(arc
		(start 99.462844 -12.640564)
		(mid 99.06692 -13.233296)
		(end 98.92792 -13.932408)
		(width 0.127)
		(layer "In2.Cu")
		(net "P3E_CPU0_PE2_SS_C_TXP<10>")
	)
	(arc
		(start 90.627962 -28.382468)
		(mid 90.531014 -28.389445)
		(end 90.457528 -28.325826)
		(width 0.127)
		(layer "In2.Cu")
		(net "P3E_CPU0_PE2_SS_C_TXP<10>")
	)
	(arc
		(start 90.994738 -27.840178)
		(mid 90.946583 -28.124001)
		(end 90.741246 -28.325826)
		(width 0.127)
		(layer "In2.Cu")
		(net "P3E_CPU0_PE2_SS_C_TXP<10>")
	)
	(arc
		(start 99.487228 -8.28294)
		(mid 99.798784 -8.748938)
		(end 99.90836 -9.298686)
		(width 0.127)
		(layer "In2.Cu")
		(net "P3E_CPU0_PE2_SS_C_TXP<10>")
	)
	(arc
		(start 114.751358 7.41553)
		(mid 114.789357 7.35866)
		(end 114.802666 7.291578)
		(width 0.127)
		(layer "In2.Cu")
		(net "P3E_CPU0_PE2_SS_C_TXP<10>")
	)
	(arc
		(start 98.94062 -7.115302)
		(mid 99.054387 -7.688661)
		(end 99.379024 -8.174736)
		(width 0.127)
		(layer "In2.Cu")
		(net "P3E_CPU0_PE2_SS_C_TXP<10>")
	)
	(arc
		(start 91.021154 -26.998422)
		(mid 90.970522 -27.418125)
		(end 90.994738 -27.840178)
		(width 0.127)
		(layer "In2.Cu")
		(net "P3E_CPU0_PE2_SS_C_TXP<10>")
	)
	(arc
		(start 99.90836 -11.87958)
		(mid 99.850235 -12.171325)
		(end 99.68484 -12.418568)
		(width 0.127)
		(layer "In2.Cu")
		(net "P3E_CPU0_PE2_SS_C_TXP<10>")
	)
	(segment
		(start 81.427574 10.383266)
		(end 81.427574 9.189974)
		(width 0.127)
		(layer "F.Cu")
		(net "P3E_CPU0_PE2_SS_C_TXP<1>")
	)
	(segment
		(start 81.179924 12.133072)
		(end 81.179924 10.980674)
		(width 0.127)
		(layer "F.Cu")
		(net "P3E_CPU0_PE2_SS_C_TXP<1>")
	)
	(segment
		(start 80.597756 8.715502)
		(end 80.4291 8.546846)
		(width 0.127)
		(layer "F.Cu")
		(net "P3E_CPU0_PE2_SS_C_TXP<1>")
	)
	(segment
		(start 79.965042 7.702042)
		(end 79.895954 7.702042)
		(width 0.127)
		(layer "F.Cu")
		(net "P3E_CPU0_PE2_SS_C_TXP<1>")
	)
	(segment
		(start 80.264 8.147558)
		(end 80.264 8.001)
		(width 0.127)
		(layer "F.Cu")
		(net "P3E_CPU0_PE2_SS_C_TXP<1>")
	)
	(segment
		(start 81.303368 10.682224)
		(end 81.303622 10.68197)
		(width 0.127)
		(layer "F.Cu")
		(net "P3E_CPU0_PE2_SS_C_TXP<1>")
	)
	(via
		(at 79.895954 7.702042)
		(size 0.508)
		(drill 0.254)
		(layers "F.Cu" "B.Cu")
		(net "P3E_CPU0_PE2_SS_C_TXP<1>")
	)
	(arc
		(start 81.303622 10.68197)
		(mid 81.395277 10.544938)
		(end 81.427574 10.383266)
		(width 0.127)
		(layer "F.Cu")
		(net "P3E_CPU0_PE2_SS_C_TXP<1>")
	)
	(arc
		(start 80.264 8.001)
		(mid 80.176437 7.789605)
		(end 79.965042 7.702042)
		(width 0.127)
		(layer "F.Cu")
		(net "P3E_CPU0_PE2_SS_C_TXP<1>")
	)
	(arc
		(start 81.427574 9.189974)
		(mid 81.362032 9.031742)
		(end 81.2038 8.9662)
		(width 0.127)
		(layer "F.Cu")
		(net "P3E_CPU0_PE2_SS_C_TXP<1>")
	)
	(arc
		(start 80.4291 8.546846)
		(mid 80.306854 8.363608)
		(end 80.264 8.147558)
		(width 0.127)
		(layer "F.Cu")
		(net "P3E_CPU0_PE2_SS_C_TXP<1>")
	)
	(arc
		(start 81.179924 10.980674)
		(mid 81.212009 10.819194)
		(end 81.303368 10.682224)
		(width 0.127)
		(layer "F.Cu")
		(net "P3E_CPU0_PE2_SS_C_TXP<1>")
	)
	(arc
		(start 81.2038 8.9662)
		(mid 80.875817 8.901165)
		(end 80.597756 8.715502)
		(width 0.127)
		(layer "F.Cu")
		(net "P3E_CPU0_PE2_SS_C_TXP<1>")
	)
	(segment
		(start 59.945524 -11.63066)
		(end 59.945524 -9.472676)
		(width 0.127)
		(layer "In2.Cu")
		(net "P3E_CPU0_PE2_SS_C_TXP<1>")
	)
	(segment
		(start 62.26683 -5.037328)
		(end 66.41719 -1.427988)
		(width 0.127)
		(layer "In2.Cu")
		(net "P3E_CPU0_PE2_SS_C_TXP<1>")
	)
	(segment
		(start 58.9534 -19.887946)
		(end 59.587638 -18.509742)
		(width 0.127)
		(layer "In2.Cu")
		(net "P3E_CPU0_PE2_SS_C_TXP<1>")
	)
	(segment
		(start 80.202786 6.040882)
		(end 80.274414 6.561074)
		(width 0.127)
		(layer "In2.Cu")
		(net "P3E_CPU0_PE2_SS_C_TXP<1>")
	)
	(segment
		(start 51.40071 -28.643834)
		(end 51.39944 -28.643326)
		(width 0.127)
		(layer "In2.Cu")
		(net "P3E_CPU0_PE2_SS_C_TXP<1>")
	)
	(segment
		(start 60.351416 -15.937738)
		(end 60.93206 -14.264386)
		(width 0.127)
		(layer "In2.Cu")
		(net "P3E_CPU0_PE2_SS_C_TXP<1>")
	)
	(segment
		(start 51.39944 -28.643326)
		(end 51.287426 -28.587446)
		(width 0.127)
		(layer "In2.Cu")
		(net "P3E_CPU0_PE2_SS_C_TXP<1>")
	)
	(segment
		(start 51.400964 -28.643834)
		(end 51.40071 -28.643834)
		(width 0.127)
		(layer "In2.Cu")
		(net "P3E_CPU0_PE2_SS_C_TXP<1>")
	)
	(segment
		(start 60.933584 -6.88721)
		(end 60.933584 -6.753606)
		(width 0.127)
		(layer "In2.Cu")
		(net "P3E_CPU0_PE2_SS_C_TXP<1>")
	)
	(segment
		(start 60.93206 -13.894562)
		(end 60.931806 -13.894816)
		(width 0.127)
		(layer "In2.Cu")
		(net "P3E_CPU0_PE2_SS_C_TXP<1>")
	)
	(segment
		(start 50.86858 -27.64536)
		(end 51.143408 -26.652728)
		(width 0.127)
		(layer "In2.Cu")
		(net "P3E_CPU0_PE2_SS_C_TXP<1>")
	)
	(segment
		(start 58.337196 -20.649692)
		(end 58.9534 -19.887946)
		(width 0.127)
		(layer "In2.Cu")
		(net "P3E_CPU0_PE2_SS_C_TXP<1>")
	)
	(segment
		(start 51.143408 -26.652728)
		(end 53.826156 -23.808182)
		(width 0.127)
		(layer "In2.Cu")
		(net "P3E_CPU0_PE2_SS_C_TXP<1>")
	)
	(segment
		(start 79.839058 4.086098)
		(end 80.199992 4.601464)
		(width 0.127)
		(layer "In2.Cu")
		(net "P3E_CPU0_PE2_SS_C_TXP<1>")
	)
	(segment
		(start 61.008006 -6.43763)
		(end 61.19749 -6.114288)
		(width 0.127)
		(layer "In2.Cu")
		(net "P3E_CPU0_PE2_SS_C_TXP<1>")
	)
	(segment
		(start 61.478414 -5.723128)
		(end 62.26683 -5.037328)
		(width 0.127)
		(layer "In2.Cu")
		(net "P3E_CPU0_PE2_SS_C_TXP<1>")
	)
	(segment
		(start 60.524898 -12.911836)
		(end 60.441586 -12.828778)
		(width 0.127)
		(layer "In2.Cu")
		(net "P3E_CPU0_PE2_SS_C_TXP<1>")
	)
	(segment
		(start 80.199992 4.601464)
		(end 80.292194 5.124196)
		(width 0.127)
		(layer "In2.Cu")
		(net "P3E_CPU0_PE2_SS_C_TXP<1>")
	)
	(segment
		(start 60.933584 -6.753606)
		(end 60.963556 -6.583934)
		(width 0.127)
		(layer "In2.Cu")
		(net "P3E_CPU0_PE2_SS_C_TXP<1>")
	)
	(segment
		(start 61.19749 -6.114288)
		(end 61.478414 -5.723128)
		(width 0.127)
		(layer "In2.Cu")
		(net "P3E_CPU0_PE2_SS_C_TXP<1>")
	)
	(segment
		(start 80.292194 5.124196)
		(end 80.292448 5.12445)
		(width 0.127)
		(layer "In2.Cu")
		(net "P3E_CPU0_PE2_SS_C_TXP<1>")
	)
	(segment
		(start 80.292448 5.12445)
		(end 80.292448 5.498338)
		(width 0.127)
		(layer "In2.Cu")
		(net "P3E_CPU0_PE2_SS_C_TXP<1>")
	)
	(segment
		(start 66.41719 -1.427988)
		(end 71.536052 2.156206)
		(width 0.127)
		(layer "In2.Cu")
		(net "P3E_CPU0_PE2_SS_C_TXP<1>")
	)
	(segment
		(start 60.93333 -6.96468)
		(end 60.933584 -6.88721)
		(width 0.127)
		(layer "In2.Cu")
		(net "P3E_CPU0_PE2_SS_C_TXP<1>")
	)
	(segment
		(start 51.080162 -29.570426)
		(end 51.45786 -28.814268)
		(width 0.127)
		(layer "In2.Cu")
		(net "P3E_CPU0_PE2_SS_C_TXP<1>")
	)
	(segment
		(start 71.536052 2.156206)
		(end 78.953614 3.466084)
		(width 0.127)
		(layer "In2.Cu")
		(net "P3E_CPU0_PE2_SS_C_TXP<1>")
	)
	(segment
		(start 53.826156 -23.808182)
		(end 58.337196 -20.649692)
		(width 0.127)
		(layer "In2.Cu")
		(net "P3E_CPU0_PE2_SS_C_TXP<1>")
	)
	(segment
		(start 60.56757 -7.97052)
		(end 60.701682 -7.836408)
		(width 0.127)
		(layer "In2.Cu")
		(net "P3E_CPU0_PE2_SS_C_TXP<1>")
	)
	(segment
		(start 80.274414 6.561074)
		(end 80.274414 7.2263)
		(width 0.127)
		(layer "In2.Cu")
		(net "P3E_CPU0_PE2_SS_C_TXP<1>")
	)
	(segment
		(start 60.963556 -6.583934)
		(end 61.008006 -6.43763)
		(width 0.127)
		(layer "In2.Cu")
		(net "P3E_CPU0_PE2_SS_C_TXP<1>")
	)
	(segment
		(start 80.292448 5.498338)
		(end 80.202786 6.040882)
		(width 0.127)
		(layer "In2.Cu")
		(net "P3E_CPU0_PE2_SS_C_TXP<1>")
	)
	(segment
		(start 59.587638 -18.509742)
		(end 60.351416 -15.937738)
		(width 0.127)
		(layer "In2.Cu")
		(net "P3E_CPU0_PE2_SS_C_TXP<1>")
	)
	(segment
		(start 60.93333 -7.2771)
		(end 60.93333 -6.96468)
		(width 0.127)
		(layer "In2.Cu")
		(net "P3E_CPU0_PE2_SS_C_TXP<1>")
	)
	(segment
		(start 60.93206 -14.264386)
		(end 60.93206 -13.894562)
		(width 0.127)
		(layer "In2.Cu")
		(net "P3E_CPU0_PE2_SS_C_TXP<1>")
	)
	(segment
		(start 78.953614 3.466084)
		(end 79.839058 4.086098)
		(width 0.127)
		(layer "In2.Cu")
		(net "P3E_CPU0_PE2_SS_C_TXP<1>")
	)
	(arc
		(start 51.287426 -28.587446)
		(mid 50.909138 -28.19147)
		(end 50.86858 -27.64536)
		(width 0.127)
		(layer "In2.Cu")
		(net "P3E_CPU0_PE2_SS_C_TXP<1>")
	)
	(arc
		(start 60.441586 -12.828778)
		(mid 60.074317 -12.279076)
		(end 59.945524 -11.63066)
		(width 0.127)
		(layer "In2.Cu")
		(net "P3E_CPU0_PE2_SS_C_TXP<1>")
	)
	(arc
		(start 51.45786 -28.814268)
		(mid 51.464619 -28.717323)
		(end 51.400964 -28.643834)
		(width 0.127)
		(layer "In2.Cu")
		(net "P3E_CPU0_PE2_SS_C_TXP<1>")
	)
	(arc
		(start 60.701682 -7.836408)
		(mid 60.873145 -7.579795)
		(end 60.93333 -7.2771)
		(width 0.127)
		(layer "In2.Cu")
		(net "P3E_CPU0_PE2_SS_C_TXP<1>")
	)
	(arc
		(start 59.945524 -9.472676)
		(mid 60.107189 -8.659751)
		(end 60.56757 -7.97052)
		(width 0.127)
		(layer "In2.Cu")
		(net "P3E_CPU0_PE2_SS_C_TXP<1>")
	)
	(arc
		(start 60.931806 -13.894816)
		(mid 60.826105 -13.362861)
		(end 60.524898 -12.911836)
		(width 0.127)
		(layer "In2.Cu")
		(net "P3E_CPU0_PE2_SS_C_TXP<1>")
	)
	(arc
		(start 80.274414 7.2263)
		(mid 80.168254 7.530244)
		(end 79.895954 7.702042)
		(width 0.127)
		(layer "In2.Cu")
		(net "P3E_CPU0_PE2_SS_C_TXP<1>")
	)
	(segment
		(start 78.779878 12.133072)
		(end 78.779878 10.980674)
		(width 0.127)
		(layer "F.Cu")
		(net "P3E_CPU0_PE2_SS_C_TXP<0>")
	)
	(segment
		(start 78.834488 9.035288)
		(end 78.803246 9.003792)
		(width 0.127)
		(layer "F.Cu")
		(net "P3E_CPU0_PE2_SS_C_TXP<0>")
	)
	(segment
		(start 78.903322 10.682224)
		(end 78.903576 10.68197)
		(width 0.127)
		(layer "F.Cu")
		(net "P3E_CPU0_PE2_SS_C_TXP<0>")
	)
	(segment
		(start 77.663548 8.154924)
		(end 77.663548 8.060436)
		(width 0.127)
		(layer "F.Cu")
		(net "P3E_CPU0_PE2_SS_C_TXP<0>")
	)
	(segment
		(start 79.027528 10.383266)
		(end 79.027528 9.499854)
		(width 0.127)
		(layer "F.Cu")
		(net "P3E_CPU0_PE2_SS_C_TXP<0>")
	)
	(segment
		(start 78.467712 8.8646)
		(end 78.4352 8.8646)
		(width 0.127)
		(layer "F.Cu")
		(net "P3E_CPU0_PE2_SS_C_TXP<0>")
	)
	(segment
		(start 77.900022 8.643112)
		(end 77.841348 8.584184)
		(width 0.127)
		(layer "F.Cu")
		(net "P3E_CPU0_PE2_SS_C_TXP<0>")
	)
	(segment
		(start 78.834996 9.035542)
		(end 78.834488 9.035288)
		(width 0.127)
		(layer "F.Cu")
		(net "P3E_CPU0_PE2_SS_C_TXP<0>")
	)
	(via
		(at 77.305154 7.702042)
		(size 0.508)
		(drill 0.254)
		(layers "F.Cu" "B.Cu")
		(net "P3E_CPU0_PE2_SS_C_TXP<0>")
	)
	(arc
		(start 78.903576 10.68197)
		(mid 78.995231 10.544938)
		(end 79.027528 10.383266)
		(width 0.127)
		(layer "F.Cu")
		(net "P3E_CPU0_PE2_SS_C_TXP<0>")
	)
	(arc
		(start 78.779878 10.980674)
		(mid 78.811963 10.819194)
		(end 78.903322 10.682224)
		(width 0.127)
		(layer "F.Cu")
		(net "P3E_CPU0_PE2_SS_C_TXP<0>")
	)
	(arc
		(start 77.841348 8.584184)
		(mid 77.709753 8.387238)
		(end 77.663548 8.154924)
		(width 0.127)
		(layer "F.Cu")
		(net "P3E_CPU0_PE2_SS_C_TXP<0>")
	)
	(arc
		(start 78.803246 9.003792)
		(mid 78.649304 8.900842)
		(end 78.467712 8.8646)
		(width 0.127)
		(layer "F.Cu")
		(net "P3E_CPU0_PE2_SS_C_TXP<0>")
	)
	(arc
		(start 79.027528 9.499854)
		(mid 78.977416 9.248573)
		(end 78.834996 9.035542)
		(width 0.127)
		(layer "F.Cu")
		(net "P3E_CPU0_PE2_SS_C_TXP<0>")
	)
	(arc
		(start 77.663548 8.060436)
		(mid 77.558577 7.807013)
		(end 77.305154 7.702042)
		(width 0.127)
		(layer "F.Cu")
		(net "P3E_CPU0_PE2_SS_C_TXP<0>")
	)
	(arc
		(start 78.4352 8.8646)
		(mid 78.145543 8.807153)
		(end 77.900022 8.643112)
		(width 0.127)
		(layer "F.Cu")
		(net "P3E_CPU0_PE2_SS_C_TXP<0>")
	)
	(segment
		(start 54.110128 -20.892516)
		(end 50.667666 -23.302976)
		(width 0.127)
		(layer "In2.Cu")
		(net "P3E_CPU0_PE2_SS_C_TXP<0>")
	)
	(segment
		(start 57.050686 -6.020054)
		(end 56.934354 -6.555486)
		(width 0.127)
		(layer "In2.Cu")
		(net "P3E_CPU0_PE2_SS_C_TXP<0>")
	)
	(segment
		(start 56.934354 -6.88721)
		(end 56.9341 -6.96468)
		(width 0.127)
		(layer "In2.Cu")
		(net "P3E_CPU0_PE2_SS_C_TXP<0>")
	)
	(segment
		(start 46.457616 -28.325826)
		(end 46.080172 -27.570176)
		(width 0.127)
		(layer "In2.Cu")
		(net "P3E_CPU0_PE2_SS_C_TXP<0>")
	)
	(segment
		(start 77.683614 7.250938)
		(end 77.683614 6.508242)
		(width 0.127)
		(layer "In2.Cu")
		(net "P3E_CPU0_PE2_SS_C_TXP<0>")
	)
	(segment
		(start 47.821088 -26.271982)
		(end 47.591218 -26.276808)
		(width 0.127)
		(layer "In2.Cu")
		(net "P3E_CPU0_PE2_SS_C_TXP<0>")
	)
	(segment
		(start 48.573436 -25.487122)
		(end 48.343566 -25.491948)
		(width 0.127)
		(layer "In2.Cu")
		(net "P3E_CPU0_PE2_SS_C_TXP<0>")
	)
	(segment
		(start 48.08474 -25.9969)
		(end 47.821088 -26.271982)
		(width 0.127)
		(layer "In2.Cu")
		(net "P3E_CPU0_PE2_SS_C_TXP<0>")
	)
	(segment
		(start 76.77531 5.03936)
		(end 69.292216 3.71983)
		(width 0.127)
		(layer "In2.Cu")
		(net "P3E_CPU0_PE2_SS_C_TXP<0>")
	)
	(segment
		(start 56.630824 -17.975072)
		(end 56.555386 -18.554446)
		(width 0.127)
		(layer "In2.Cu")
		(net "P3E_CPU0_PE2_SS_C_TXP<0>")
	)
	(segment
		(start 48.079914 -25.76703)
		(end 48.08474 -25.9969)
		(width 0.127)
		(layer "In2.Cu")
		(net "P3E_CPU0_PE2_SS_C_TXP<0>")
	)
	(segment
		(start 56.932576 -13.894816)
		(end 56.93283 -13.894562)
		(width 0.127)
		(layer "In2.Cu")
		(net "P3E_CPU0_PE2_SS_C_TXP<0>")
	)
	(segment
		(start 58.197496 -4.634992)
		(end 57.349644 -5.482844)
		(width 0.127)
		(layer "In2.Cu")
		(net "P3E_CPU0_PE2_SS_C_TXP<0>")
	)
	(segment
		(start 62.726062 -0.87757)
		(end 58.197496 -4.634992)
		(width 0.127)
		(layer "In2.Cu")
		(net "P3E_CPU0_PE2_SS_C_TXP<0>")
	)
	(segment
		(start 55.946294 -9.472676)
		(end 55.946294 -11.63066)
		(width 0.127)
		(layer "In2.Cu")
		(net "P3E_CPU0_PE2_SS_C_TXP<0>")
	)
	(segment
		(start 55.194962 -20.133056)
		(end 54.110128 -20.892516)
		(width 0.127)
		(layer "In2.Cu")
		(net "P3E_CPU0_PE2_SS_C_TXP<0>")
	)
	(segment
		(start 56.706516 -17.394936)
		(end 56.630824 -17.975072)
		(width 0.127)
		(layer "In2.Cu")
		(net "P3E_CPU0_PE2_SS_C_TXP<0>")
	)
	(segment
		(start 69.292216 3.71983)
		(end 62.726062 -0.87757)
		(width 0.127)
		(layer "In2.Cu")
		(net "P3E_CPU0_PE2_SS_C_TXP<0>")
	)
	(segment
		(start 56.279796 -19.373342)
		(end 55.194962 -20.133056)
		(width 0.127)
		(layer "In2.Cu")
		(net "P3E_CPU0_PE2_SS_C_TXP<0>")
	)
	(segment
		(start 56.555386 -18.5547)
		(end 56.279796 -19.373342)
		(width 0.127)
		(layer "In2.Cu")
		(net "P3E_CPU0_PE2_SS_C_TXP<0>")
	)
	(segment
		(start 77.25283 5.373624)
		(end 76.77531 5.03936)
		(width 0.127)
		(layer "In2.Cu")
		(net "P3E_CPU0_PE2_SS_C_TXP<0>")
	)
	(segment
		(start 47.591218 -26.276808)
		(end 47.327566 -26.551636)
		(width 0.127)
		(layer "In2.Cu")
		(net "P3E_CPU0_PE2_SS_C_TXP<0>")
	)
	(segment
		(start 77.561186 5.814314)
		(end 77.25283 5.373624)
		(width 0.127)
		(layer "In2.Cu")
		(net "P3E_CPU0_PE2_SS_C_TXP<0>")
	)
	(segment
		(start 56.555386 -18.554446)
		(end 56.555386 -18.5547)
		(width 0.127)
		(layer "In2.Cu")
		(net "P3E_CPU0_PE2_SS_C_TXP<0>")
	)
	(segment
		(start 56.70677 -17.394936)
		(end 56.706516 -17.394936)
		(width 0.127)
		(layer "In2.Cu")
		(net "P3E_CPU0_PE2_SS_C_TXP<0>")
	)
	(segment
		(start 56.93283 -13.894562)
		(end 56.93283 -14.302994)
		(width 0.127)
		(layer "In2.Cu")
		(net "P3E_CPU0_PE2_SS_C_TXP<0>")
	)
	(segment
		(start 57.298336 -5.552694)
		(end 57.050686 -6.020054)
		(width 0.127)
		(layer "In2.Cu")
		(net "P3E_CPU0_PE2_SS_C_TXP<0>")
	)
	(segment
		(start 56.442356 -12.828778)
		(end 56.525668 -12.911836)
		(width 0.127)
		(layer "In2.Cu")
		(net "P3E_CPU0_PE2_SS_C_TXP<0>")
	)
	(segment
		(start 56.93283 -14.302994)
		(end 56.70677 -17.394936)
		(width 0.127)
		(layer "In2.Cu")
		(net "P3E_CPU0_PE2_SS_C_TXP<0>")
	)
	(segment
		(start 46.741842 -28.325826)
		(end 46.62805 -28.382722)
		(width 0.127)
		(layer "In2.Cu")
		(net "P3E_CPU0_PE2_SS_C_TXP<0>")
	)
	(segment
		(start 56.702452 -7.836408)
		(end 56.56834 -7.97052)
		(width 0.127)
		(layer "In2.Cu")
		(net "P3E_CPU0_PE2_SS_C_TXP<0>")
	)
	(segment
		(start 57.349644 -5.482844)
		(end 57.298336 -5.552694)
		(width 0.127)
		(layer "In2.Cu")
		(net "P3E_CPU0_PE2_SS_C_TXP<0>")
	)
	(segment
		(start 56.9341 -6.96468)
		(end 56.9341 -7.2771)
		(width 0.127)
		(layer "In2.Cu")
		(net "P3E_CPU0_PE2_SS_C_TXP<0>")
	)
	(segment
		(start 48.343566 -25.491948)
		(end 48.079914 -25.76703)
		(width 0.127)
		(layer "In2.Cu")
		(net "P3E_CPU0_PE2_SS_C_TXP<0>")
	)
	(segment
		(start 46.62805 -28.382722)
		(end 46.627796 -28.382722)
		(width 0.127)
		(layer "In2.Cu")
		(net "P3E_CPU0_PE2_SS_C_TXP<0>")
	)
	(segment
		(start 77.683614 6.508242)
		(end 77.561186 5.814314)
		(width 0.127)
		(layer "In2.Cu")
		(net "P3E_CPU0_PE2_SS_C_TXP<0>")
	)
	(segment
		(start 50.667666 -23.302976)
		(end 48.573436 -25.487122)
		(width 0.127)
		(layer "In2.Cu")
		(net "P3E_CPU0_PE2_SS_C_TXP<0>")
	)
	(segment
		(start 47.327566 -26.551636)
		(end 47.332392 -26.781506)
		(width 0.127)
		(layer "In2.Cu")
		(net "P3E_CPU0_PE2_SS_C_TXP<0>")
	)
	(segment
		(start 56.934354 -6.555486)
		(end 56.934354 -6.88721)
		(width 0.127)
		(layer "In2.Cu")
		(net "P3E_CPU0_PE2_SS_C_TXP<0>")
	)
	(segment
		(start 47.332392 -26.781506)
		(end 47.06874 -27.056588)
		(width 0.127)
		(layer "In2.Cu")
		(net "P3E_CPU0_PE2_SS_C_TXP<0>")
	)
	(arc
		(start 56.9341 -7.2771)
		(mid 56.873892 -7.579786)
		(end 56.702452 -7.836408)
		(width 0.127)
		(layer "In2.Cu")
		(net "P3E_CPU0_PE2_SS_C_TXP<0>")
	)
	(arc
		(start 56.129682 -12.39774)
		(mid 56.177209 -12.484931)
		(end 56.229758 -12.56919)
		(width 0.127)
		(layer "In2.Cu")
		(net "P3E_CPU0_PE2_SS_C_TXP<0>")
	)
	(arc
		(start 46.972474 -27.932888)
		(mid 46.915331 -28.163507)
		(end 46.741842 -28.325826)
		(width 0.127)
		(layer "In2.Cu")
		(net "P3E_CPU0_PE2_SS_C_TXP<0>")
	)
	(arc
		(start 56.56834 -7.97052)
		(mid 56.107942 -8.659743)
		(end 55.946294 -9.472676)
		(width 0.127)
		(layer "In2.Cu")
		(net "P3E_CPU0_PE2_SS_C_TXP<0>")
	)
	(arc
		(start 56.229758 -12.56919)
		(mid 56.329613 -12.704261)
		(end 56.442356 -12.828778)
		(width 0.127)
		(layer "In2.Cu")
		(net "P3E_CPU0_PE2_SS_C_TXP<0>")
	)
	(arc
		(start 47.06874 -27.056588)
		(mid 46.98662 -27.491004)
		(end 46.972474 -27.932888)
		(width 0.127)
		(layer "In2.Cu")
		(net "P3E_CPU0_PE2_SS_C_TXP<0>")
	)
	(arc
		(start 56.525668 -12.911836)
		(mid 56.826877 -13.36286)
		(end 56.932576 -13.894816)
		(width 0.127)
		(layer "In2.Cu")
		(net "P3E_CPU0_PE2_SS_C_TXP<0>")
	)
	(arc
		(start 55.946294 -11.63066)
		(mid 55.992711 -12.025027)
		(end 56.129682 -12.39774)
		(width 0.127)
		(layer "In2.Cu")
		(net "P3E_CPU0_PE2_SS_C_TXP<0>")
	)
	(arc
		(start 46.627796 -28.382722)
		(mid 46.530922 -28.389519)
		(end 46.457616 -28.325826)
		(width 0.127)
		(layer "In2.Cu")
		(net "P3E_CPU0_PE2_SS_C_TXP<0>")
	)
	(arc
		(start 77.305154 7.702042)
		(mid 77.58032 7.548637)
		(end 77.683614 7.250938)
		(width 0.127)
		(layer "In2.Cu")
		(net "P3E_CPU0_PE2_SS_C_TXP<0>")
	)
	(segment
		(start 112.506252 8.187944)
		(end 112.506252 8.04164)
		(width 0.127)
		(layer "F.Cu")
		(net "P3E_CPU0_PE2_SS_C_TXN<9>")
	)
	(segment
		(start 112.727486 10.475468)
		(end 112.727486 9.441688)
		(width 0.127)
		(layer "F.Cu")
		(net "P3E_CPU0_PE2_SS_C_TXN<9>")
	)
	(segment
		(start 112.674654 9.141968)
		(end 112.506252 8.187944)
		(width 0.127)
		(layer "F.Cu")
		(net "P3E_CPU0_PE2_SS_C_TXN<9>")
	)
	(segment
		(start 112.727486 9.441688)
		(end 112.674654 9.141968)
		(width 0.127)
		(layer "F.Cu")
		(net "P3E_CPU0_PE2_SS_C_TXN<9>")
	)
	(segment
		(start 112.975136 12.234672)
		(end 112.975136 11.073384)
		(width 0.127)
		(layer "F.Cu")
		(net "P3E_CPU0_PE2_SS_C_TXN<9>")
	)
	(segment
		(start 112.80521 7.742682)
		(end 112.849406 7.742682)
		(width 0.127)
		(layer "F.Cu")
		(net "P3E_CPU0_PE2_SS_C_TXN<9>")
	)
	(via
		(at 112.849406 7.742682)
		(size 0.508)
		(drill 0.254)
		(layers "F.Cu" "B.Cu")
		(net "P3E_CPU0_PE2_SS_C_TXN<9>")
	)
	(arc
		(start 112.506252 8.04164)
		(mid 112.593815 7.830245)
		(end 112.80521 7.742682)
		(width 0.127)
		(layer "F.Cu")
		(net "P3E_CPU0_PE2_SS_C_TXN<9>")
	)
	(arc
		(start 112.975136 11.073384)
		(mid 112.942983 10.911738)
		(end 112.851438 10.77468)
		(width 0.127)
		(layer "F.Cu")
		(net "P3E_CPU0_PE2_SS_C_TXN<9>")
	)
	(arc
		(start 112.851438 10.77468)
		(mid 112.759711 10.6374)
		(end 112.727486 10.475468)
		(width 0.127)
		(layer "F.Cu")
		(net "P3E_CPU0_PE2_SS_C_TXN<9>")
	)
	(segment
		(start 98.237802 -1.148334)
		(end 97.971102 -1.529334)
		(width 0.127)
		(layer "In2.Cu")
		(net "P3E_CPU0_PE2_SS_C_TXN<9>")
	)
	(segment
		(start 95.21952 -14.351508)
		(end 94.997524 -15.60957)
		(width 0.127)
		(layer "In2.Cu")
		(net "P3E_CPU0_PE2_SS_C_TXN<9>")
	)
	(segment
		(start 95.21952 -13.932662)
		(end 95.21952 -14.351508)
		(width 0.127)
		(layer "In2.Cu")
		(net "P3E_CPU0_PE2_SS_C_TXN<9>")
	)
	(segment
		(start 111.830866 3.567938)
		(end 110.82528 2.86385)
		(width 0.127)
		(layer "In2.Cu")
		(net "P3E_CPU0_PE2_SS_C_TXN<9>")
	)
	(segment
		(start 86.702646 -28.814522)
		(end 87.079582 -29.570426)
		(width 0.127)
		(layer "In2.Cu")
		(net "P3E_CPU0_PE2_SS_C_TXN<9>")
	)
	(segment
		(start 112.503966 6.581648)
		(end 112.435894 6.085586)
		(width 0.127)
		(layer "In2.Cu")
		(net "P3E_CPU0_PE2_SS_C_TXN<9>")
	)
	(segment
		(start 112.522 5.563108)
		(end 112.522 4.9784)
		(width 0.127)
		(layer "In2.Cu")
		(net "P3E_CPU0_PE2_SS_C_TXN<9>")
	)
	(segment
		(start 112.517682 4.927854)
		(end 112.428528 4.421124)
		(width 0.127)
		(layer "In2.Cu")
		(net "P3E_CPU0_PE2_SS_C_TXN<9>")
	)
	(segment
		(start 96.19996 -9.29894)
		(end 96.19996 -11.87958)
		(width 0.127)
		(layer "In2.Cu")
		(net "P3E_CPU0_PE2_SS_C_TXN<9>")
	)
	(segment
		(start 86.759542 -28.644088)
		(end 86.759288 -28.644088)
		(width 0.127)
		(layer "In2.Cu")
		(net "P3E_CPU0_PE2_SS_C_TXN<9>")
	)
	(segment
		(start 95.58528 -7.96798)
		(end 95.693484 -8.076184)
		(width 0.127)
		(layer "In2.Cu")
		(net "P3E_CPU0_PE2_SS_C_TXN<9>")
	)
	(segment
		(start 86.87308 -28.587192)
		(end 86.759542 -28.644088)
		(width 0.127)
		(layer "In2.Cu")
		(net "P3E_CPU0_PE2_SS_C_TXN<9>")
	)
	(segment
		(start 112.428528 4.421124)
		(end 111.830866 3.567938)
		(width 0.127)
		(layer "In2.Cu")
		(net "P3E_CPU0_PE2_SS_C_TXN<9>")
	)
	(segment
		(start 112.435894 6.085586)
		(end 112.522 5.563108)
		(width 0.127)
		(layer "In2.Cu")
		(net "P3E_CPU0_PE2_SS_C_TXN<9>")
	)
	(segment
		(start 110.82528 2.86385)
		(end 101.658928 1.24714)
		(width 0.127)
		(layer "In2.Cu")
		(net "P3E_CPU0_PE2_SS_C_TXN<9>")
	)
	(segment
		(start 101.658928 1.24714)
		(end 98.237802 -1.148334)
		(width 0.127)
		(layer "In2.Cu")
		(net "P3E_CPU0_PE2_SS_C_TXN<9>")
	)
	(segment
		(start 112.522 4.9784)
		(end 112.517682 4.927854)
		(width 0.127)
		(layer "In2.Cu")
		(net "P3E_CPU0_PE2_SS_C_TXN<9>")
	)
	(segment
		(start 95.891096 -12.625324)
		(end 95.6691 -12.84732)
		(width 0.127)
		(layer "In2.Cu")
		(net "P3E_CPU0_PE2_SS_C_TXN<9>")
	)
	(segment
		(start 95.62719 -4.876292)
		(end 95.23222 -7.115556)
		(width 0.127)
		(layer "In2.Cu")
		(net "P3E_CPU0_PE2_SS_C_TXN<9>")
	)
	(segment
		(start 112.503966 7.282688)
		(end 112.503966 6.581648)
		(width 0.127)
		(layer "In2.Cu")
		(net "P3E_CPU0_PE2_SS_C_TXN<9>")
	)
	(segment
		(start 87.437468 -26.406602)
		(end 87.30234 -27.08656)
		(width 0.127)
		(layer "In2.Cu")
		(net "P3E_CPU0_PE2_SS_C_TXN<9>")
	)
	(segment
		(start 97.861882 -1.685544)
		(end 95.62719 -4.876292)
		(width 0.127)
		(layer "In2.Cu")
		(net "P3E_CPU0_PE2_SS_C_TXN<9>")
	)
	(segment
		(start 97.971102 -1.529334)
		(end 97.861882 -1.685544)
		(width 0.127)
		(layer "In2.Cu")
		(net "P3E_CPU0_PE2_SS_C_TXN<9>")
	)
	(segment
		(start 94.997524 -15.60957)
		(end 87.437468 -26.406602)
		(width 0.127)
		(layer "In2.Cu")
		(net "P3E_CPU0_PE2_SS_C_TXN<9>")
	)
	(arc
		(start 87.28456 -27.79776)
		(mid 87.206586 -28.259053)
		(end 86.87308 -28.587192)
		(width 0.127)
		(layer "In2.Cu")
		(net "P3E_CPU0_PE2_SS_C_TXN<9>")
	)
	(arc
		(start 95.6691 -12.84732)
		(mid 95.336374 -13.345279)
		(end 95.21952 -13.932662)
		(width 0.127)
		(layer "In2.Cu")
		(net "P3E_CPU0_PE2_SS_C_TXN<9>")
	)
	(arc
		(start 112.849406 7.742682)
		(mid 112.603882 7.567358)
		(end 112.503966 7.282688)
		(width 0.127)
		(layer "In2.Cu")
		(net "P3E_CPU0_PE2_SS_C_TXN<9>")
	)
	(arc
		(start 86.759288 -28.644088)
		(mid 86.695669 -28.717574)
		(end 86.702646 -28.814522)
		(width 0.127)
		(layer "In2.Cu")
		(net "P3E_CPU0_PE2_SS_C_TXN<9>")
	)
	(arc
		(start 95.23222 -7.115556)
		(mid 95.323982 -7.576875)
		(end 95.58528 -7.96798)
		(width 0.127)
		(layer "In2.Cu")
		(net "P3E_CPU0_PE2_SS_C_TXN<9>")
	)
	(arc
		(start 87.30234 -27.08656)
		(mid 87.263029 -27.441399)
		(end 87.28456 -27.79776)
		(width 0.127)
		(layer "In2.Cu")
		(net "P3E_CPU0_PE2_SS_C_TXN<9>")
	)
	(arc
		(start 95.693484 -8.076184)
		(mid 96.068336 -8.637189)
		(end 96.19996 -9.29894)
		(width 0.127)
		(layer "In2.Cu")
		(net "P3E_CPU0_PE2_SS_C_TXN<9>")
	)
	(arc
		(start 96.19996 -11.87958)
		(mid 96.119683 -12.283161)
		(end 95.891096 -12.625324)
		(width 0.127)
		(layer "In2.Cu")
		(net "P3E_CPU0_PE2_SS_C_TXN<9>")
	)
	(segment
		(start 110.008924 8.777986)
		(end 110.207552 9.061704)
		(width 0.127)
		(layer "F.Cu")
		(net "P3E_CPU0_PE2_SS_C_TXN<8>")
	)
	(segment
		(start 109.9058 8.19404)
		(end 109.974126 8.580882)
		(width 0.127)
		(layer "F.Cu")
		(net "P3E_CPU0_PE2_SS_C_TXN<8>")
	)
	(segment
		(start 109.974126 8.580882)
		(end 110.008924 8.777986)
		(width 0.127)
		(layer "F.Cu")
		(net "P3E_CPU0_PE2_SS_C_TXN<8>")
	)
	(segment
		(start 110.32744 9.7409)
		(end 110.32744 10.475468)
		(width 0.127)
		(layer "F.Cu")
		(net "P3E_CPU0_PE2_SS_C_TXN<8>")
	)
	(segment
		(start 109.9058 8.095488)
		(end 109.9058 8.19404)
		(width 0.127)
		(layer "F.Cu")
		(net "P3E_CPU0_PE2_SS_C_TXN<8>")
	)
	(segment
		(start 110.207552 9.061704)
		(end 110.32744 9.7409)
		(width 0.127)
		(layer "F.Cu")
		(net "P3E_CPU0_PE2_SS_C_TXN<8>")
	)
	(segment
		(start 110.57509 11.073384)
		(end 110.57509 12.234672)
		(width 0.127)
		(layer "F.Cu")
		(net "P3E_CPU0_PE2_SS_C_TXN<8>")
	)
	(via
		(at 110.258606 7.742682)
		(size 0.508)
		(drill 0.254)
		(layers "F.Cu" "B.Cu")
		(net "P3E_CPU0_PE2_SS_C_TXN<8>")
	)
	(arc
		(start 110.32744 10.475468)
		(mid 110.359651 10.637406)
		(end 110.451392 10.77468)
		(width 0.127)
		(layer "F.Cu")
		(net "P3E_CPU0_PE2_SS_C_TXN<8>")
	)
	(arc
		(start 110.258606 7.742682)
		(mid 110.009134 7.846016)
		(end 109.9058 8.095488)
		(width 0.127)
		(layer "F.Cu")
		(net "P3E_CPU0_PE2_SS_C_TXN<8>")
	)
	(arc
		(start 110.451392 10.77468)
		(mid 110.542964 10.911727)
		(end 110.57509 11.073384)
		(width 0.127)
		(layer "F.Cu")
		(net "P3E_CPU0_PE2_SS_C_TXN<8>")
	)
	(segment
		(start 99.52609 3.540252)
		(end 100.3808 3.691128)
		(width 0.127)
		(layer "In2.Cu")
		(net "P3E_CPU0_PE2_SS_C_TXN<8>")
	)
	(segment
		(start 82.758788 -28.644088)
		(end 82.759042 -28.644088)
		(width 0.127)
		(layer "In2.Cu")
		(net "P3E_CPU0_PE2_SS_C_TXN<8>")
	)
	(segment
		(start 91.6686 -12.84732)
		(end 91.890596 -12.625324)
		(width 0.127)
		(layer "In2.Cu")
		(net "P3E_CPU0_PE2_SS_C_TXN<8>")
	)
	(segment
		(start 92.19946 -11.87958)
		(end 92.19946 -9.29894)
		(width 0.127)
		(layer "In2.Cu")
		(net "P3E_CPU0_PE2_SS_C_TXN<8>")
	)
	(segment
		(start 107.89539 4.511548)
		(end 109.6899 5.768594)
		(width 0.127)
		(layer "In2.Cu")
		(net "P3E_CPU0_PE2_SS_C_TXN<8>")
	)
	(segment
		(start 91.23172 -6.7691)
		(end 91.352116 -6.08584)
		(width 0.127)
		(layer "In2.Cu")
		(net "P3E_CPU0_PE2_SS_C_TXN<8>")
	)
	(segment
		(start 92.592398 -4.990084)
		(end 92.677234 -4.905248)
		(width 0.127)
		(layer "In2.Cu")
		(net "P3E_CPU0_PE2_SS_C_TXN<8>")
	)
	(segment
		(start 97.68586 2.250694)
		(end 99.52609 3.540252)
		(width 0.127)
		(layer "In2.Cu")
		(net "P3E_CPU0_PE2_SS_C_TXN<8>")
	)
	(segment
		(start 92.107512 -5.330444)
		(end 92.592398 -4.990084)
		(width 0.127)
		(layer "In2.Cu")
		(net "P3E_CPU0_PE2_SS_C_TXN<8>")
	)
	(segment
		(start 109.822996 6.08838)
		(end 109.827568 6.090412)
		(width 0.127)
		(layer "In2.Cu")
		(net "P3E_CPU0_PE2_SS_C_TXN<8>")
	)
	(segment
		(start 91.352116 -6.08584)
		(end 92.107512 -5.330444)
		(width 0.127)
		(layer "In2.Cu")
		(net "P3E_CPU0_PE2_SS_C_TXN<8>")
	)
	(segment
		(start 91.23172 -7.115556)
		(end 91.23172 -6.7691)
		(width 0.127)
		(layer "In2.Cu")
		(net "P3E_CPU0_PE2_SS_C_TXN<8>")
	)
	(segment
		(start 101.811328 3.438906)
		(end 107.89539 4.511548)
		(width 0.127)
		(layer "In2.Cu")
		(net "P3E_CPU0_PE2_SS_C_TXN<8>")
	)
	(segment
		(start 83.304888 -25.982168)
		(end 91.141804 -14.789658)
		(width 0.127)
		(layer "In2.Cu")
		(net "P3E_CPU0_PE2_SS_C_TXN<8>")
	)
	(segment
		(start 91.692984 -8.076184)
		(end 91.58478 -7.96798)
		(width 0.127)
		(layer "In2.Cu")
		(net "P3E_CPU0_PE2_SS_C_TXN<8>")
	)
	(segment
		(start 109.913166 6.57606)
		(end 109.913166 7.282688)
		(width 0.127)
		(layer "In2.Cu")
		(net "P3E_CPU0_PE2_SS_C_TXN<8>")
	)
	(segment
		(start 109.827568 6.090412)
		(end 109.913166 6.57606)
		(width 0.127)
		(layer "In2.Cu")
		(net "P3E_CPU0_PE2_SS_C_TXN<8>")
	)
	(segment
		(start 83.27517 -26.150062)
		(end 83.304888 -25.982168)
		(width 0.127)
		(layer "In2.Cu")
		(net "P3E_CPU0_PE2_SS_C_TXN<8>")
	)
	(segment
		(start 100.3808 3.691128)
		(end 101.811328 3.438906)
		(width 0.127)
		(layer "In2.Cu")
		(net "P3E_CPU0_PE2_SS_C_TXN<8>")
	)
	(segment
		(start 83.24088 -26.63698)
		(end 83.27517 -26.150062)
		(width 0.127)
		(layer "In2.Cu")
		(net "P3E_CPU0_PE2_SS_C_TXN<8>")
	)
	(segment
		(start 109.6899 5.768594)
		(end 109.822996 6.08838)
		(width 0.127)
		(layer "In2.Cu")
		(net "P3E_CPU0_PE2_SS_C_TXN<8>")
	)
	(segment
		(start 91.141804 -14.789658)
		(end 91.21902 -14.351508)
		(width 0.127)
		(layer "In2.Cu")
		(net "P3E_CPU0_PE2_SS_C_TXN<8>")
	)
	(segment
		(start 92.677234 -4.905248)
		(end 97.68586 2.250694)
		(width 0.127)
		(layer "In2.Cu")
		(net "P3E_CPU0_PE2_SS_C_TXN<8>")
	)
	(segment
		(start 83.080352 -29.570426)
		(end 82.702146 -28.814522)
		(width 0.127)
		(layer "In2.Cu")
		(net "P3E_CPU0_PE2_SS_C_TXN<8>")
	)
	(segment
		(start 91.21902 -14.351508)
		(end 91.21902 -13.932662)
		(width 0.127)
		(layer "In2.Cu")
		(net "P3E_CPU0_PE2_SS_C_TXN<8>")
	)
	(segment
		(start 82.759042 -28.644088)
		(end 82.87258 -28.587192)
		(width 0.127)
		(layer "In2.Cu")
		(net "P3E_CPU0_PE2_SS_C_TXN<8>")
	)
	(arc
		(start 91.58478 -7.96798)
		(mid 91.323458 -7.576885)
		(end 91.23172 -7.115556)
		(width 0.127)
		(layer "In2.Cu")
		(net "P3E_CPU0_PE2_SS_C_TXN<8>")
	)
	(arc
		(start 83.28406 -27.79776)
		(mid 83.230949 -27.218543)
		(end 83.24088 -26.63698)
		(width 0.127)
		(layer "In2.Cu")
		(net "P3E_CPU0_PE2_SS_C_TXN<8>")
	)
	(arc
		(start 109.913166 7.282688)
		(mid 110.013084 7.567357)
		(end 110.258606 7.742682)
		(width 0.127)
		(layer "In2.Cu")
		(net "P3E_CPU0_PE2_SS_C_TXN<8>")
	)
	(arc
		(start 82.702146 -28.814522)
		(mid 82.695169 -28.717574)
		(end 82.758788 -28.644088)
		(width 0.127)
		(layer "In2.Cu")
		(net "P3E_CPU0_PE2_SS_C_TXN<8>")
	)
	(arc
		(start 91.21902 -13.932662)
		(mid 91.335859 -13.345273)
		(end 91.6686 -12.84732)
		(width 0.127)
		(layer "In2.Cu")
		(net "P3E_CPU0_PE2_SS_C_TXN<8>")
	)
	(arc
		(start 82.87258 -28.587192)
		(mid 83.206176 -28.2591)
		(end 83.28406 -27.79776)
		(width 0.127)
		(layer "In2.Cu")
		(net "P3E_CPU0_PE2_SS_C_TXN<8>")
	)
	(arc
		(start 91.890596 -12.625324)
		(mid 92.119213 -12.283174)
		(end 92.19946 -11.87958)
		(width 0.127)
		(layer "In2.Cu")
		(net "P3E_CPU0_PE2_SS_C_TXN<8>")
	)
	(arc
		(start 92.19946 -9.29894)
		(mid 92.06783 -8.637192)
		(end 91.692984 -8.076184)
		(width 0.127)
		(layer "In2.Cu")
		(net "P3E_CPU0_PE2_SS_C_TXN<8>")
	)
	(segment
		(start 96.132142 10.373868)
		(end 96.132142 8.2296)
		(width 0.127)
		(layer "F.Cu")
		(net "P3E_CPU0_PE2_SS_C_TXN<7>")
	)
	(segment
		(start 96.379792 12.133072)
		(end 96.379792 10.971784)
		(width 0.127)
		(layer "F.Cu")
		(net "P3E_CPU0_PE2_SS_C_TXN<7>")
	)
	(via
		(at 96.456754 7.702042)
		(size 0.508)
		(drill 0.254)
		(layers "F.Cu" "B.Cu")
		(net "P3E_CPU0_PE2_SS_C_TXN<7>")
	)
	(arc
		(start 96.132142 8.2296)
		(mid 96.21979 7.919878)
		(end 96.456754 7.702042)
		(width 0.127)
		(layer "F.Cu")
		(net "P3E_CPU0_PE2_SS_C_TXN<7>")
	)
	(arc
		(start 96.379792 10.971784)
		(mid 96.347639 10.810138)
		(end 96.256094 10.67308)
		(width 0.127)
		(layer "F.Cu")
		(net "P3E_CPU0_PE2_SS_C_TXN<7>")
	)
	(arc
		(start 96.256094 10.67308)
		(mid 96.164367 10.5358)
		(end 96.132142 10.373868)
		(width 0.127)
		(layer "F.Cu")
		(net "P3E_CPU0_PE2_SS_C_TXN<7>")
	)
	(segment
		(start 96.112584 6.210554)
		(end 96.112584 7.237984)
		(width 0.127)
		(layer "In2.Cu")
		(net "P3E_CPU0_PE2_SS_C_TXN<7>")
	)
	(segment
		(start 77.531468 -28.382468)
		(end 77.418438 -28.325826)
		(width 0.127)
		(layer "In2.Cu")
		(net "P3E_CPU0_PE2_SS_C_TXN<7>")
	)
	(segment
		(start 91.648026 -3.002026)
		(end 95.697548 2.780538)
		(width 0.127)
		(layer "In2.Cu")
		(net "P3E_CPU0_PE2_SS_C_TXN<7>")
	)
	(segment
		(start 82.305906 -21.980398)
		(end 82.266028 -21.754084)
		(width 0.127)
		(layer "In2.Cu")
		(net "P3E_CPU0_PE2_SS_C_TXN<7>")
	)
	(segment
		(start 78.080362 -27.570176)
		(end 77.702156 -28.325826)
		(width 0.127)
		(layer "In2.Cu")
		(net "P3E_CPU0_PE2_SS_C_TXN<7>")
	)
	(segment
		(start 82.087466 -22.292564)
		(end 82.305906 -21.980398)
		(width 0.127)
		(layer "In2.Cu")
		(net "P3E_CPU0_PE2_SS_C_TXN<7>")
	)
	(segment
		(start 77.531722 -28.382468)
		(end 77.531468 -28.382468)
		(width 0.127)
		(layer "In2.Cu")
		(net "P3E_CPU0_PE2_SS_C_TXN<7>")
	)
	(segment
		(start 81.463896 -23.183088)
		(end 81.682336 -22.870922)
		(width 0.127)
		(layer "In2.Cu")
		(net "P3E_CPU0_PE2_SS_C_TXN<7>")
	)
	(segment
		(start 87.277702 -6.44017)
		(end 87.796624 -5.698744)
		(width 0.127)
		(layer "In2.Cu")
		(net "P3E_CPU0_PE2_SS_C_TXN<7>")
	)
	(segment
		(start 80.395318 -24.425656)
		(end 80.613758 -24.11349)
		(width 0.127)
		(layer "In2.Cu")
		(net "P3E_CPU0_PE2_SS_C_TXN<7>")
	)
	(segment
		(start 77.96276 -26.12898)
		(end 80.395318 -24.425656)
		(width 0.127)
		(layer "In2.Cu")
		(net "P3E_CPU0_PE2_SS_C_TXN<7>")
	)
	(segment
		(start 81.018888 -23.535132)
		(end 81.237328 -23.222966)
		(width 0.127)
		(layer "In2.Cu")
		(net "P3E_CPU0_PE2_SS_C_TXN<7>")
	)
	(segment
		(start 87.66937 -12.84732)
		(end 87.891366 -12.625324)
		(width 0.127)
		(layer "In2.Cu")
		(net "P3E_CPU0_PE2_SS_C_TXN<7>")
	)
	(segment
		(start 81.682336 -22.870922)
		(end 81.642458 -22.644608)
		(width 0.127)
		(layer "In2.Cu")
		(net "P3E_CPU0_PE2_SS_C_TXN<7>")
	)
	(segment
		(start 87.23249 -7.115556)
		(end 87.23249 -6.696202)
		(width 0.127)
		(layer "In2.Cu")
		(net "P3E_CPU0_PE2_SS_C_TXN<7>")
	)
	(segment
		(start 80.840326 -24.073612)
		(end 81.058766 -23.761446)
		(width 0.127)
		(layer "In2.Cu")
		(net "P3E_CPU0_PE2_SS_C_TXN<7>")
	)
	(segment
		(start 81.058766 -23.761446)
		(end 81.018888 -23.535132)
		(width 0.127)
		(layer "In2.Cu")
		(net "P3E_CPU0_PE2_SS_C_TXN<7>")
	)
	(segment
		(start 87.142574 -14.789404)
		(end 87.21979 -14.351508)
		(width 0.127)
		(layer "In2.Cu")
		(net "P3E_CPU0_PE2_SS_C_TXN<7>")
	)
	(segment
		(start 82.266028 -21.754084)
		(end 87.142574 -14.789404)
		(width 0.127)
		(layer "In2.Cu")
		(net "P3E_CPU0_PE2_SS_C_TXN<7>")
	)
	(segment
		(start 87.23249 -6.696202)
		(end 87.277702 -6.44017)
		(width 0.127)
		(layer "In2.Cu")
		(net "P3E_CPU0_PE2_SS_C_TXN<7>")
	)
	(segment
		(start 95.697548 2.780538)
		(end 96.090232 4.808728)
		(width 0.127)
		(layer "In2.Cu")
		(net "P3E_CPU0_PE2_SS_C_TXN<7>")
	)
	(segment
		(start 80.613758 -24.11349)
		(end 80.840326 -24.073612)
		(width 0.127)
		(layer "In2.Cu")
		(net "P3E_CPU0_PE2_SS_C_TXN<7>")
	)
	(segment
		(start 81.642458 -22.644608)
		(end 81.860898 -22.332442)
		(width 0.127)
		(layer "In2.Cu")
		(net "P3E_CPU0_PE2_SS_C_TXN<7>")
	)
	(segment
		(start 81.860898 -22.332442)
		(end 82.087466 -22.292564)
		(width 0.127)
		(layer "In2.Cu")
		(net "P3E_CPU0_PE2_SS_C_TXN<7>")
	)
	(segment
		(start 77.608938 -26.37663)
		(end 77.96276 -26.12898)
		(width 0.127)
		(layer "In2.Cu")
		(net "P3E_CPU0_PE2_SS_C_TXN<7>")
	)
	(segment
		(start 77.430884 -26.756106)
		(end 77.608938 -26.37663)
		(width 0.127)
		(layer "In2.Cu")
		(net "P3E_CPU0_PE2_SS_C_TXN<7>")
	)
	(segment
		(start 87.796624 -5.698744)
		(end 91.648026 -3.002026)
		(width 0.127)
		(layer "In2.Cu")
		(net "P3E_CPU0_PE2_SS_C_TXN<7>")
	)
	(segment
		(start 87.693754 -8.076184)
		(end 87.58555 -7.96798)
		(width 0.127)
		(layer "In2.Cu")
		(net "P3E_CPU0_PE2_SS_C_TXN<7>")
	)
	(segment
		(start 87.21979 -14.351508)
		(end 87.21979 -13.932662)
		(width 0.127)
		(layer "In2.Cu")
		(net "P3E_CPU0_PE2_SS_C_TXN<7>")
	)
	(segment
		(start 81.237328 -23.222966)
		(end 81.463896 -23.183088)
		(width 0.127)
		(layer "In2.Cu")
		(net "P3E_CPU0_PE2_SS_C_TXN<7>")
	)
	(segment
		(start 88.20023 -11.87958)
		(end 88.20023 -9.29894)
		(width 0.127)
		(layer "In2.Cu")
		(net "P3E_CPU0_PE2_SS_C_TXN<7>")
	)
	(arc
		(start 77.174344 -27.91206)
		(mid 77.238641 -27.319884)
		(end 77.430884 -26.756106)
		(width 0.127)
		(layer "In2.Cu")
		(net "P3E_CPU0_PE2_SS_C_TXN<7>")
	)
	(arc
		(start 96.112584 7.237984)
		(mid 96.208021 7.526851)
		(end 96.456754 7.702042)
		(width 0.127)
		(layer "In2.Cu")
		(net "P3E_CPU0_PE2_SS_C_TXN<7>")
	)
	(arc
		(start 88.20023 -9.29894)
		(mid 88.0686 -8.637192)
		(end 87.693754 -8.076184)
		(width 0.127)
		(layer "In2.Cu")
		(net "P3E_CPU0_PE2_SS_C_TXN<7>")
	)
	(arc
		(start 77.418438 -28.325826)
		(mid 77.235277 -28.154993)
		(end 77.174344 -27.91206)
		(width 0.127)
		(layer "In2.Cu")
		(net "P3E_CPU0_PE2_SS_C_TXN<7>")
	)
	(arc
		(start 77.702156 -28.325826)
		(mid 77.62867 -28.389445)
		(end 77.531722 -28.382468)
		(width 0.127)
		(layer "In2.Cu")
		(net "P3E_CPU0_PE2_SS_C_TXN<7>")
	)
	(arc
		(start 96.112584 5.5626)
		(mid 96.091362 5.886578)
		(end 96.112584 6.210554)
		(width 0.127)
		(layer "In2.Cu")
		(net "P3E_CPU0_PE2_SS_C_TXN<7>")
	)
	(arc
		(start 87.58555 -7.96798)
		(mid 87.324228 -7.576885)
		(end 87.23249 -7.115556)
		(width 0.127)
		(layer "In2.Cu")
		(net "P3E_CPU0_PE2_SS_C_TXN<7>")
	)
	(arc
		(start 87.891366 -12.625324)
		(mid 88.119983 -12.283174)
		(end 88.20023 -11.87958)
		(width 0.127)
		(layer "In2.Cu")
		(net "P3E_CPU0_PE2_SS_C_TXN<7>")
	)
	(arc
		(start 87.21979 -13.932662)
		(mid 87.336629 -13.345273)
		(end 87.66937 -12.84732)
		(width 0.127)
		(layer "In2.Cu")
		(net "P3E_CPU0_PE2_SS_C_TXN<7>")
	)
	(arc
		(start 96.090232 4.808728)
		(mid 96.13194 5.184759)
		(end 96.112584 5.5626)
		(width 0.127)
		(layer "In2.Cu")
		(net "P3E_CPU0_PE2_SS_C_TXN<7>")
	)
	(segment
		(start 93.5228 8.426704)
		(end 93.5228 8.001)
		(width 0.127)
		(layer "F.Cu")
		(net "P3E_CPU0_PE2_SS_C_TXN<6>")
	)
	(segment
		(start 93.821758 7.702042)
		(end 93.865954 7.702042)
		(width 0.127)
		(layer "F.Cu")
		(net "P3E_CPU0_PE2_SS_C_TXN<6>")
	)
	(segment
		(start 93.98 12.133072)
		(end 93.98 10.971784)
		(width 0.127)
		(layer "F.Cu")
		(net "P3E_CPU0_PE2_SS_C_TXN<6>")
	)
	(via
		(at 93.865954 7.702042)
		(size 0.508)
		(drill 0.254)
		(layers "F.Cu" "B.Cu")
		(net "P3E_CPU0_PE2_SS_C_TXN<6>")
	)
	(arc
		(start 93.5228 8.001)
		(mid 93.610363 7.789605)
		(end 93.821758 7.702042)
		(width 0.127)
		(layer "F.Cu")
		(net "P3E_CPU0_PE2_SS_C_TXN<6>")
	)
	(arc
		(start 93.856302 10.67308)
		(mid 93.764575 10.5358)
		(end 93.73235 10.373868)
		(width 0.127)
		(layer "F.Cu")
		(net "P3E_CPU0_PE2_SS_C_TXN<6>")
	)
	(arc
		(start 93.73235 10.373868)
		(mid 93.679811 9.394664)
		(end 93.5228 8.426704)
		(width 0.127)
		(layer "F.Cu")
		(net "P3E_CPU0_PE2_SS_C_TXN<6>")
	)
	(arc
		(start 93.98 10.971784)
		(mid 93.947847 10.810138)
		(end 93.856302 10.67308)
		(width 0.127)
		(layer "F.Cu")
		(net "P3E_CPU0_PE2_SS_C_TXN<6>")
	)
	(segment
		(start 73.843896 -26.190194)
		(end 73.572116 -26.457148)
		(width 0.127)
		(layer "In2.Cu")
		(net "P3E_CPU0_PE2_SS_C_TXN<6>")
	)
	(segment
		(start 75.123802 -24.93391)
		(end 75.121516 -25.16378)
		(width 0.127)
		(layer "In2.Cu")
		(net "P3E_CPU0_PE2_SS_C_TXN<6>")
	)
	(segment
		(start 75.625452 -24.669242)
		(end 75.395582 -24.66721)
		(width 0.127)
		(layer "In2.Cu")
		(net "P3E_CPU0_PE2_SS_C_TXN<6>")
	)
	(segment
		(start 93.277436 3.06324)
		(end 89.911682 -1.744726)
		(width 0.127)
		(layer "In2.Cu")
		(net "P3E_CPU0_PE2_SS_C_TXN<6>")
	)
	(segment
		(start 74.849736 -25.430734)
		(end 74.619866 -25.428702)
		(width 0.127)
		(layer "In2.Cu")
		(net "P3E_CPU0_PE2_SS_C_TXN<6>")
	)
	(segment
		(start 75.897232 -24.402288)
		(end 75.625452 -24.669242)
		(width 0.127)
		(layer "In2.Cu")
		(net "P3E_CPU0_PE2_SS_C_TXN<6>")
	)
	(segment
		(start 75.899518 -24.172418)
		(end 75.897232 -24.402288)
		(width 0.127)
		(layer "In2.Cu")
		(net "P3E_CPU0_PE2_SS_C_TXN<6>")
	)
	(segment
		(start 93.447616 4.543806)
		(end 93.447362 4.543806)
		(width 0.127)
		(layer "In2.Cu")
		(net "P3E_CPU0_PE2_SS_C_TXN<6>")
	)
	(segment
		(start 74.3458 -25.925526)
		(end 74.073766 -26.19248)
		(width 0.127)
		(layer "In2.Cu")
		(net "P3E_CPU0_PE2_SS_C_TXN<6>")
	)
	(segment
		(start 93.865954 7.702042)
		(end 93.649038 7.413244)
		(width 0.127)
		(layer "In2.Cu")
		(net "P3E_CPU0_PE2_SS_C_TXN<6>")
	)
	(segment
		(start 74.073766 -26.19248)
		(end 73.843896 -26.190194)
		(width 0.127)
		(layer "In2.Cu")
		(net "P3E_CPU0_PE2_SS_C_TXN<6>")
	)
	(segment
		(start 83.21929 -14.351508)
		(end 83.093052 -15.06728)
		(width 0.127)
		(layer "In2.Cu")
		(net "P3E_CPU0_PE2_SS_C_TXN<6>")
	)
	(segment
		(start 73.419208 -28.325826)
		(end 73.532238 -28.382468)
		(width 0.127)
		(layer "In2.Cu")
		(net "P3E_CPU0_PE2_SS_C_TXN<6>")
	)
	(segment
		(start 93.521784 7.03199)
		(end 93.521784 6.210554)
		(width 0.127)
		(layer "In2.Cu")
		(net "P3E_CPU0_PE2_SS_C_TXN<6>")
	)
	(segment
		(start 78.517242 -21.6027)
		(end 75.899518 -24.172418)
		(width 0.127)
		(layer "In2.Cu")
		(net "P3E_CPU0_PE2_SS_C_TXN<6>")
	)
	(segment
		(start 83.890866 -12.625324)
		(end 83.66887 -12.84732)
		(width 0.127)
		(layer "In2.Cu")
		(net "P3E_CPU0_PE2_SS_C_TXN<6>")
	)
	(segment
		(start 74.347832 -25.695656)
		(end 74.3458 -25.925526)
		(width 0.127)
		(layer "In2.Cu")
		(net "P3E_CPU0_PE2_SS_C_TXN<6>")
	)
	(segment
		(start 93.447108 4.543552)
		(end 93.277436 3.06324)
		(width 0.127)
		(layer "In2.Cu")
		(net "P3E_CPU0_PE2_SS_C_TXN<6>")
	)
	(segment
		(start 89.911682 -1.744726)
		(end 83.864196 -5.979668)
		(width 0.127)
		(layer "In2.Cu")
		(net "P3E_CPU0_PE2_SS_C_TXN<6>")
	)
	(segment
		(start 84.19973 -9.29894)
		(end 84.19973 -11.87958)
		(width 0.127)
		(layer "In2.Cu")
		(net "P3E_CPU0_PE2_SS_C_TXN<6>")
	)
	(segment
		(start 83.286854 -6.804152)
		(end 83.23199 -7.115556)
		(width 0.127)
		(layer "In2.Cu")
		(net "P3E_CPU0_PE2_SS_C_TXN<6>")
	)
	(segment
		(start 73.702926 -28.325826)
		(end 74.079862 -27.570176)
		(width 0.127)
		(layer "In2.Cu")
		(net "P3E_CPU0_PE2_SS_C_TXN<6>")
	)
	(segment
		(start 75.121516 -25.16378)
		(end 74.849736 -25.430734)
		(width 0.127)
		(layer "In2.Cu")
		(net "P3E_CPU0_PE2_SS_C_TXN<6>")
	)
	(segment
		(start 93.447362 4.543806)
		(end 93.447108 4.543552)
		(width 0.127)
		(layer "In2.Cu")
		(net "P3E_CPU0_PE2_SS_C_TXN<6>")
	)
	(segment
		(start 73.532238 -28.382468)
		(end 73.532492 -28.382468)
		(width 0.127)
		(layer "In2.Cu")
		(net "P3E_CPU0_PE2_SS_C_TXN<6>")
	)
	(segment
		(start 83.093052 -15.06728)
		(end 78.517242 -21.6027)
		(width 0.127)
		(layer "In2.Cu")
		(net "P3E_CPU0_PE2_SS_C_TXN<6>")
	)
	(segment
		(start 83.864196 -5.979668)
		(end 83.286854 -6.804152)
		(width 0.127)
		(layer "In2.Cu")
		(net "P3E_CPU0_PE2_SS_C_TXN<6>")
	)
	(segment
		(start 83.58505 -7.96798)
		(end 83.693254 -8.076184)
		(width 0.127)
		(layer "In2.Cu")
		(net "P3E_CPU0_PE2_SS_C_TXN<6>")
	)
	(segment
		(start 73.572116 -26.457148)
		(end 73.431654 -26.756106)
		(width 0.127)
		(layer "In2.Cu")
		(net "P3E_CPU0_PE2_SS_C_TXN<6>")
	)
	(segment
		(start 83.21929 -13.932662)
		(end 83.21929 -14.351508)
		(width 0.127)
		(layer "In2.Cu")
		(net "P3E_CPU0_PE2_SS_C_TXN<6>")
	)
	(segment
		(start 75.395582 -24.66721)
		(end 75.123802 -24.93391)
		(width 0.127)
		(layer "In2.Cu")
		(net "P3E_CPU0_PE2_SS_C_TXN<6>")
	)
	(segment
		(start 93.499178 4.808728)
		(end 93.44787 4.54406)
		(width 0.127)
		(layer "In2.Cu")
		(net "P3E_CPU0_PE2_SS_C_TXN<6>")
	)
	(segment
		(start 93.44787 4.54406)
		(end 93.447616 4.543806)
		(width 0.127)
		(layer "In2.Cu")
		(net "P3E_CPU0_PE2_SS_C_TXN<6>")
	)
	(segment
		(start 74.619866 -25.428702)
		(end 74.347832 -25.695656)
		(width 0.127)
		(layer "In2.Cu")
		(net "P3E_CPU0_PE2_SS_C_TXN<6>")
	)
	(arc
		(start 73.431654 -26.756106)
		(mid 73.239432 -27.319889)
		(end 73.175114 -27.91206)
		(width 0.127)
		(layer "In2.Cu")
		(net "P3E_CPU0_PE2_SS_C_TXN<6>")
	)
	(arc
		(start 83.693254 -8.076184)
		(mid 84.068106 -8.637189)
		(end 84.19973 -9.29894)
		(width 0.127)
		(layer "In2.Cu")
		(net "P3E_CPU0_PE2_SS_C_TXN<6>")
	)
	(arc
		(start 93.649038 7.413244)
		(mid 93.554437 7.232955)
		(end 93.521784 7.03199)
		(width 0.127)
		(layer "In2.Cu")
		(net "P3E_CPU0_PE2_SS_C_TXN<6>")
	)
	(arc
		(start 93.521784 5.5626)
		(mid 93.541006 5.184749)
		(end 93.499178 4.808728)
		(width 0.127)
		(layer "In2.Cu")
		(net "P3E_CPU0_PE2_SS_C_TXN<6>")
	)
	(arc
		(start 84.19973 -11.87958)
		(mid 84.119453 -12.283161)
		(end 83.890866 -12.625324)
		(width 0.127)
		(layer "In2.Cu")
		(net "P3E_CPU0_PE2_SS_C_TXN<6>")
	)
	(arc
		(start 73.175114 -27.91206)
		(mid 73.236062 -28.154985)
		(end 73.419208 -28.325826)
		(width 0.127)
		(layer "In2.Cu")
		(net "P3E_CPU0_PE2_SS_C_TXN<6>")
	)
	(arc
		(start 73.532492 -28.382468)
		(mid 73.62944 -28.389445)
		(end 73.702926 -28.325826)
		(width 0.127)
		(layer "In2.Cu")
		(net "P3E_CPU0_PE2_SS_C_TXN<6>")
	)
	(arc
		(start 83.23199 -7.115556)
		(mid 83.323752 -7.576875)
		(end 83.58505 -7.96798)
		(width 0.127)
		(layer "In2.Cu")
		(net "P3E_CPU0_PE2_SS_C_TXN<6>")
	)
	(arc
		(start 83.66887 -12.84732)
		(mid 83.336144 -13.345279)
		(end 83.21929 -13.932662)
		(width 0.127)
		(layer "In2.Cu")
		(net "P3E_CPU0_PE2_SS_C_TXN<6>")
	)
	(arc
		(start 93.521784 6.210554)
		(mid 93.500596 5.886578)
		(end 93.521784 5.5626)
		(width 0.127)
		(layer "In2.Cu")
		(net "P3E_CPU0_PE2_SS_C_TXN<6>")
	)
	(segment
		(start 90.932 8.382)
		(end 90.932 8.001)
		(width 0.127)
		(layer "F.Cu")
		(net "P3E_CPU0_PE2_SS_C_TXN<5>")
	)
	(segment
		(start 91.579954 12.133072)
		(end 91.579954 10.971784)
		(width 0.127)
		(layer "F.Cu")
		(net "P3E_CPU0_PE2_SS_C_TXN<5>")
	)
	(segment
		(start 91.230958 7.702042)
		(end 91.275154 7.702042)
		(width 0.127)
		(layer "F.Cu")
		(net "P3E_CPU0_PE2_SS_C_TXN<5>")
	)
	(segment
		(start 91.332304 10.373868)
		(end 91.332304 9.525)
		(width 0.127)
		(layer "F.Cu")
		(net "P3E_CPU0_PE2_SS_C_TXN<5>")
	)
	(via
		(at 91.275154 7.702042)
		(size 0.508)
		(drill 0.254)
		(layers "F.Cu" "B.Cu")
		(net "P3E_CPU0_PE2_SS_C_TXN<5>")
	)
	(arc
		(start 91.332304 9.525)
		(mid 91.268285 9.172303)
		(end 91.0844 8.8646)
		(width 0.127)
		(layer "F.Cu")
		(net "P3E_CPU0_PE2_SS_C_TXN<5>")
	)
	(arc
		(start 91.456256 10.67308)
		(mid 91.364529 10.5358)
		(end 91.332304 10.373868)
		(width 0.127)
		(layer "F.Cu")
		(net "P3E_CPU0_PE2_SS_C_TXN<5>")
	)
	(arc
		(start 91.0844 8.8646)
		(mid 90.957728 8.639236)
		(end 90.932 8.382)
		(width 0.127)
		(layer "F.Cu")
		(net "P3E_CPU0_PE2_SS_C_TXN<5>")
	)
	(arc
		(start 90.932 8.001)
		(mid 91.019563 7.789605)
		(end 91.230958 7.702042)
		(width 0.127)
		(layer "F.Cu")
		(net "P3E_CPU0_PE2_SS_C_TXN<5>")
	)
	(arc
		(start 91.579954 10.971784)
		(mid 91.547801 10.810138)
		(end 91.456256 10.67308)
		(width 0.127)
		(layer "F.Cu")
		(net "P3E_CPU0_PE2_SS_C_TXN<5>")
	)
	(segment
		(start 71.809864 -23.955756)
		(end 71.806308 -24.185626)
		(width 0.127)
		(layer "In2.Cu")
		(net "P3E_CPU0_PE2_SS_C_TXN<5>")
	)
	(segment
		(start 69.196712 -27.374088)
		(end 69.174614 -27.91206)
		(width 0.127)
		(layer "In2.Cu")
		(net "P3E_CPU0_PE2_SS_C_TXN<5>")
	)
	(segment
		(start 69.418708 -28.325826)
		(end 69.531738 -28.382468)
		(width 0.127)
		(layer "In2.Cu")
		(net "P3E_CPU0_PE2_SS_C_TXN<5>")
	)
	(segment
		(start 71.026274 -24.9428)
		(end 70.75297 -25.20823)
		(width 0.127)
		(layer "In2.Cu")
		(net "P3E_CPU0_PE2_SS_C_TXN<5>")
	)
	(segment
		(start 70.249542 -25.470104)
		(end 70.24624 -25.699974)
		(width 0.127)
		(layer "In2.Cu")
		(net "P3E_CPU0_PE2_SS_C_TXN<5>")
	)
	(segment
		(start 78.909418 -8.043164)
		(end 78.775306 -8.177276)
		(width 0.127)
		(layer "In2.Cu")
		(net "P3E_CPU0_PE2_SS_C_TXN<5>")
	)
	(segment
		(start 79.22514 -14.313662)
		(end 79.147924 -14.751304)
		(width 0.127)
		(layer "In2.Cu")
		(net "P3E_CPU0_PE2_SS_C_TXN<5>")
	)
	(segment
		(start 78.238604 -9.47293)
		(end 78.238604 -11.63066)
		(width 0.127)
		(layer "In2.Cu")
		(net "P3E_CPU0_PE2_SS_C_TXN<5>")
	)
	(segment
		(start 90.911172 4.823714)
		(end 90.909902 4.811268)
		(width 0.127)
		(layer "In2.Cu")
		(net "P3E_CPU0_PE2_SS_C_TXN<5>")
	)
	(segment
		(start 71.533004 -24.451056)
		(end 71.303134 -24.447754)
		(width 0.127)
		(layer "In2.Cu")
		(net "P3E_CPU0_PE2_SS_C_TXN<5>")
	)
	(segment
		(start 90.929714 7.242048)
		(end 90.929714 6.555486)
		(width 0.127)
		(layer "In2.Cu")
		(net "P3E_CPU0_PE2_SS_C_TXN<5>")
	)
	(segment
		(start 70.24624 -25.699974)
		(end 69.972682 -25.965404)
		(width 0.127)
		(layer "In2.Cu")
		(net "P3E_CPU0_PE2_SS_C_TXN<5>")
	)
	(segment
		(start 70.5231 -25.204674)
		(end 70.249542 -25.470104)
		(width 0.127)
		(layer "In2.Cu")
		(net "P3E_CPU0_PE2_SS_C_TXN<5>")
	)
	(segment
		(start 79.22514 -13.894816)
		(end 79.22514 -14.313662)
		(width 0.127)
		(layer "In2.Cu")
		(net "P3E_CPU0_PE2_SS_C_TXN<5>")
	)
	(segment
		(start 69.531738 -28.382468)
		(end 69.531992 -28.382468)
		(width 0.127)
		(layer "In2.Cu")
		(net "P3E_CPU0_PE2_SS_C_TXN<5>")
	)
	(segment
		(start 79.147924 -14.751304)
		(end 74.597514 -21.248878)
		(width 0.127)
		(layer "In2.Cu")
		(net "P3E_CPU0_PE2_SS_C_TXN<5>")
	)
	(segment
		(start 74.593958 -21.253704)
		(end 71.809864 -23.955756)
		(width 0.127)
		(layer "In2.Cu")
		(net "P3E_CPU0_PE2_SS_C_TXN<5>")
	)
	(segment
		(start 69.742812 -25.961848)
		(end 69.469508 -26.227278)
		(width 0.127)
		(layer "In2.Cu")
		(net "P3E_CPU0_PE2_SS_C_TXN<5>")
	)
	(segment
		(start 90.930984 5.5626)
		(end 90.930984 5.562346)
		(width 0.127)
		(layer "In2.Cu")
		(net "P3E_CPU0_PE2_SS_C_TXN<5>")
	)
	(segment
		(start 90.91676 4.357116)
		(end 90.670634 2.960624)
		(width 0.127)
		(layer "In2.Cu")
		(net "P3E_CPU0_PE2_SS_C_TXN<5>")
	)
	(segment
		(start 70.75297 -25.20823)
		(end 70.5231 -25.204674)
		(width 0.127)
		(layer "In2.Cu")
		(net "P3E_CPU0_PE2_SS_C_TXN<5>")
	)
	(segment
		(start 90.909902 4.811268)
		(end 90.909902 4.810506)
		(width 0.127)
		(layer "In2.Cu")
		(net "P3E_CPU0_PE2_SS_C_TXN<5>")
	)
	(segment
		(start 69.469508 -26.227278)
		(end 69.196712 -27.374088)
		(width 0.127)
		(layer "In2.Cu")
		(net "P3E_CPU0_PE2_SS_C_TXN<5>")
	)
	(segment
		(start 88.247728 -0.499618)
		(end 79.52867 -6.604254)
		(width 0.127)
		(layer "In2.Cu")
		(net "P3E_CPU0_PE2_SS_C_TXN<5>")
	)
	(segment
		(start 69.702426 -28.325826)
		(end 70.079362 -27.570176)
		(width 0.127)
		(layer "In2.Cu")
		(net "P3E_CPU0_PE2_SS_C_TXN<5>")
	)
	(segment
		(start 90.670634 2.960624)
		(end 88.247728 -0.499618)
		(width 0.127)
		(layer "In2.Cu")
		(net "P3E_CPU0_PE2_SS_C_TXN<5>")
	)
	(segment
		(start 71.806308 -24.185626)
		(end 71.533004 -24.451056)
		(width 0.127)
		(layer "In2.Cu")
		(net "P3E_CPU0_PE2_SS_C_TXN<5>")
	)
	(segment
		(start 78.649068 -12.622022)
		(end 78.73238 -12.70508)
		(width 0.127)
		(layer "In2.Cu")
		(net "P3E_CPU0_PE2_SS_C_TXN<5>")
	)
	(segment
		(start 69.972682 -25.965404)
		(end 69.742812 -25.961848)
		(width 0.127)
		(layer "In2.Cu")
		(net "P3E_CPU0_PE2_SS_C_TXN<5>")
	)
	(segment
		(start 90.908632 4.775962)
		(end 90.91676 4.357116)
		(width 0.127)
		(layer "In2.Cu")
		(net "P3E_CPU0_PE2_SS_C_TXN<5>")
	)
	(segment
		(start 79.28356 -6.954266)
		(end 79.226664 -7.2771)
		(width 0.127)
		(layer "In2.Cu")
		(net "P3E_CPU0_PE2_SS_C_TXN<5>")
	)
	(segment
		(start 79.52867 -6.604254)
		(end 79.28356 -6.954266)
		(width 0.127)
		(layer "In2.Cu")
		(net "P3E_CPU0_PE2_SS_C_TXN<5>")
	)
	(segment
		(start 71.303134 -24.447754)
		(end 71.02983 -24.71293)
		(width 0.127)
		(layer "In2.Cu")
		(net "P3E_CPU0_PE2_SS_C_TXN<5>")
	)
	(segment
		(start 71.02983 -24.71293)
		(end 71.026274 -24.9428)
		(width 0.127)
		(layer "In2.Cu")
		(net "P3E_CPU0_PE2_SS_C_TXN<5>")
	)
	(segment
		(start 74.597514 -21.248878)
		(end 74.593958 -21.253704)
		(width 0.127)
		(layer "In2.Cu")
		(net "P3E_CPU0_PE2_SS_C_TXN<5>")
	)
	(arc
		(start 90.930984 6.210554)
		(mid 90.909796 5.886578)
		(end 90.930984 5.5626)
		(width 0.127)
		(layer "In2.Cu")
		(net "P3E_CPU0_PE2_SS_C_TXN<5>")
	)
	(arc
		(start 78.238604 -11.63066)
		(mid 78.345229 -12.167169)
		(end 78.649068 -12.622022)
		(width 0.127)
		(layer "In2.Cu")
		(net "P3E_CPU0_PE2_SS_C_TXN<5>")
	)
	(arc
		(start 69.174614 -27.91206)
		(mid 69.235562 -28.154985)
		(end 69.418708 -28.325826)
		(width 0.127)
		(layer "In2.Cu")
		(net "P3E_CPU0_PE2_SS_C_TXN<5>")
	)
	(arc
		(start 90.930984 5.562346)
		(mid 90.950383 5.192243)
		(end 90.911172 4.823714)
		(width 0.127)
		(layer "In2.Cu")
		(net "P3E_CPU0_PE2_SS_C_TXN<5>")
	)
	(arc
		(start 90.909902 4.810506)
		(mid 90.908826 4.79325)
		(end 90.908632 4.775962)
		(width 0.127)
		(layer "In2.Cu")
		(net "P3E_CPU0_PE2_SS_C_TXN<5>")
	)
	(arc
		(start 90.929714 6.555486)
		(mid 90.933579 6.399808)
		(end 90.93327 6.244082)
		(width 0.127)
		(layer "In2.Cu")
		(net "P3E_CPU0_PE2_SS_C_TXN<5>")
	)
	(arc
		(start 79.226664 -7.2771)
		(mid 79.144217 -7.691679)
		(end 78.909418 -8.043164)
		(width 0.127)
		(layer "In2.Cu")
		(net "P3E_CPU0_PE2_SS_C_TXN<5>")
	)
	(arc
		(start 91.275154 7.702042)
		(mid 91.02963 7.526718)
		(end 90.929714 7.242048)
		(width 0.127)
		(layer "In2.Cu")
		(net "P3E_CPU0_PE2_SS_C_TXN<5>")
	)
	(arc
		(start 90.93327 6.244082)
		(mid 90.932698 6.227279)
		(end 90.930984 6.210554)
		(width 0.127)
		(layer "In2.Cu")
		(net "P3E_CPU0_PE2_SS_C_TXN<5>")
	)
	(arc
		(start 78.775306 -8.177276)
		(mid 78.378106 -8.771727)
		(end 78.238604 -9.47293)
		(width 0.127)
		(layer "In2.Cu")
		(net "P3E_CPU0_PE2_SS_C_TXN<5>")
	)
	(arc
		(start 69.531992 -28.382468)
		(mid 69.62894 -28.389445)
		(end 69.702426 -28.325826)
		(width 0.127)
		(layer "In2.Cu")
		(net "P3E_CPU0_PE2_SS_C_TXN<5>")
	)
	(arc
		(start 78.73238 -12.70508)
		(mid 79.097109 -13.250936)
		(end 79.22514 -13.894816)
		(width 0.127)
		(layer "In2.Cu")
		(net "P3E_CPU0_PE2_SS_C_TXN<5>")
	)
	(segment
		(start 88.640158 7.702042)
		(end 88.684354 7.702042)
		(width 0.127)
		(layer "F.Cu")
		(net "P3E_CPU0_PE2_SS_C_TXN<4>")
	)
	(segment
		(start 89.179908 12.133072)
		(end 89.179908 10.971784)
		(width 0.127)
		(layer "F.Cu")
		(net "P3E_CPU0_PE2_SS_C_TXN<4>")
	)
	(segment
		(start 88.3412 8.147304)
		(end 88.3412 8.001)
		(width 0.127)
		(layer "F.Cu")
		(net "P3E_CPU0_PE2_SS_C_TXN<4>")
	)
	(segment
		(start 88.5444 8.509)
		(end 88.453214 8.417814)
		(width 0.127)
		(layer "F.Cu")
		(net "P3E_CPU0_PE2_SS_C_TXN<4>")
	)
	(segment
		(start 88.932258 10.373868)
		(end 88.932258 9.445498)
		(width 0.127)
		(layer "F.Cu")
		(net "P3E_CPU0_PE2_SS_C_TXN<4>")
	)
	(via
		(at 88.684354 7.702042)
		(size 0.508)
		(drill 0.254)
		(layers "F.Cu" "B.Cu")
		(net "P3E_CPU0_PE2_SS_C_TXN<4>")
	)
	(arc
		(start 89.05621 10.67308)
		(mid 88.964483 10.5358)
		(end 88.932258 10.373868)
		(width 0.127)
		(layer "F.Cu")
		(net "P3E_CPU0_PE2_SS_C_TXN<4>")
	)
	(arc
		(start 88.932258 9.445498)
		(mid 88.831447 8.938689)
		(end 88.5444 8.509)
		(width 0.127)
		(layer "F.Cu")
		(net "P3E_CPU0_PE2_SS_C_TXN<4>")
	)
	(arc
		(start 88.3412 8.001)
		(mid 88.428763 7.789605)
		(end 88.640158 7.702042)
		(width 0.127)
		(layer "F.Cu")
		(net "P3E_CPU0_PE2_SS_C_TXN<4>")
	)
	(arc
		(start 88.453214 8.417814)
		(mid 88.370286 8.293703)
		(end 88.3412 8.147304)
		(width 0.127)
		(layer "F.Cu")
		(net "P3E_CPU0_PE2_SS_C_TXN<4>")
	)
	(arc
		(start 89.179908 10.971784)
		(mid 89.147755 10.810138)
		(end 89.05621 10.67308)
		(width 0.127)
		(layer "F.Cu")
		(net "P3E_CPU0_PE2_SS_C_TXN<4>")
	)
	(segment
		(start 66.85534 -24.634952)
		(end 66.642742 -24.951182)
		(width 0.127)
		(layer "In2.Cu")
		(net "P3E_CPU0_PE2_SS_C_TXN<4>")
	)
	(segment
		(start 86.319614 0.511302)
		(end 82.374486 -2.251202)
		(width 0.127)
		(layer "In2.Cu")
		(net "P3E_CPU0_PE2_SS_C_TXN<4>")
	)
	(segment
		(start 87.720424 3.126994)
		(end 86.319614 0.511302)
		(width 0.127)
		(layer "In2.Cu")
		(net "P3E_CPU0_PE2_SS_C_TXN<4>")
	)
	(segment
		(start 65.418208 -28.325826)
		(end 65.531238 -28.382468)
		(width 0.127)
		(layer "In2.Cu")
		(net "P3E_CPU0_PE2_SS_C_TXN<4>")
	)
	(segment
		(start 75.550268 -6.267196)
		(end 75.355196 -6.54558)
		(width 0.127)
		(layer "In2.Cu")
		(net "P3E_CPU0_PE2_SS_C_TXN<4>")
	)
	(segment
		(start 66.036698 -25.853644)
		(end 66.081148 -26.079196)
		(width 0.127)
		(layer "In2.Cu")
		(net "P3E_CPU0_PE2_SS_C_TXN<4>")
	)
	(segment
		(start 67.248786 -24.04872)
		(end 67.293236 -24.274272)
		(width 0.127)
		(layer "In2.Cu")
		(net "P3E_CPU0_PE2_SS_C_TXN<4>")
	)
	(segment
		(start 67.080892 -24.590502)
		(end 66.85534 -24.634952)
		(width 0.127)
		(layer "In2.Cu")
		(net "P3E_CPU0_PE2_SS_C_TXN<4>")
	)
	(segment
		(start 82.374486 -2.251202)
		(end 80.920336 -2.507488)
		(width 0.127)
		(layer "In2.Cu")
		(net "P3E_CPU0_PE2_SS_C_TXN<4>")
	)
	(segment
		(start 71.980298 -20.265644)
		(end 67.84467 -23.161498)
		(width 0.127)
		(layer "In2.Cu")
		(net "P3E_CPU0_PE2_SS_C_TXN<4>")
	)
	(segment
		(start 65.701926 -28.325826)
		(end 66.080132 -27.570176)
		(width 0.127)
		(layer "In2.Cu")
		(net "P3E_CPU0_PE2_SS_C_TXN<4>")
	)
	(segment
		(start 67.84467 -23.161498)
		(end 67.248786 -24.04872)
		(width 0.127)
		(layer "In2.Cu")
		(net "P3E_CPU0_PE2_SS_C_TXN<4>")
	)
	(segment
		(start 66.081148 -26.079196)
		(end 65.86855 -26.395426)
		(width 0.127)
		(layer "In2.Cu")
		(net "P3E_CPU0_PE2_SS_C_TXN<4>")
	)
	(segment
		(start 75.22464 -14.313662)
		(end 74.91349 -16.07693)
		(width 0.127)
		(layer "In2.Cu")
		(net "P3E_CPU0_PE2_SS_C_TXN<4>")
	)
	(segment
		(start 66.249042 -25.537414)
		(end 66.036698 -25.853644)
		(width 0.127)
		(layer "In2.Cu")
		(net "P3E_CPU0_PE2_SS_C_TXN<4>")
	)
	(segment
		(start 80.920336 -2.507488)
		(end 75.550268 -6.267196)
		(width 0.127)
		(layer "In2.Cu")
		(net "P3E_CPU0_PE2_SS_C_TXN<4>")
	)
	(segment
		(start 67.293236 -24.274272)
		(end 67.080892 -24.590502)
		(width 0.127)
		(layer "In2.Cu")
		(net "P3E_CPU0_PE2_SS_C_TXN<4>")
	)
	(segment
		(start 74.648568 -12.622022)
		(end 74.73188 -12.70508)
		(width 0.127)
		(layer "In2.Cu")
		(net "P3E_CPU0_PE2_SS_C_TXN<4>")
	)
	(segment
		(start 66.642742 -24.951182)
		(end 66.687192 -25.176734)
		(width 0.127)
		(layer "In2.Cu")
		(net "P3E_CPU0_PE2_SS_C_TXN<4>")
	)
	(segment
		(start 75.22464 -13.894816)
		(end 75.22464 -14.313662)
		(width 0.127)
		(layer "In2.Cu")
		(net "P3E_CPU0_PE2_SS_C_TXN<4>")
	)
	(segment
		(start 74.91349 -16.07693)
		(end 71.980298 -20.265644)
		(width 0.127)
		(layer "In2.Cu")
		(net "P3E_CPU0_PE2_SS_C_TXN<4>")
	)
	(segment
		(start 65.531238 -28.382468)
		(end 65.531492 -28.382468)
		(width 0.127)
		(layer "In2.Cu")
		(net "P3E_CPU0_PE2_SS_C_TXN<4>")
	)
	(segment
		(start 74.238104 -9.47293)
		(end 74.238104 -11.63066)
		(width 0.127)
		(layer "In2.Cu")
		(net "P3E_CPU0_PE2_SS_C_TXN<4>")
	)
	(segment
		(start 74.908918 -8.043164)
		(end 74.774806 -8.177276)
		(width 0.127)
		(layer "In2.Cu")
		(net "P3E_CPU0_PE2_SS_C_TXN<4>")
	)
	(segment
		(start 66.474848 -25.492964)
		(end 66.249042 -25.537414)
		(width 0.127)
		(layer "In2.Cu")
		(net "P3E_CPU0_PE2_SS_C_TXN<4>")
	)
	(segment
		(start 75.355196 -6.54558)
		(end 75.226164 -7.2771)
		(width 0.127)
		(layer "In2.Cu")
		(net "P3E_CPU0_PE2_SS_C_TXN<4>")
	)
	(segment
		(start 65.642998 -26.439876)
		(end 65.430654 -26.756106)
		(width 0.127)
		(layer "In2.Cu")
		(net "P3E_CPU0_PE2_SS_C_TXN<4>")
	)
	(segment
		(start 66.687192 -25.176734)
		(end 66.474848 -25.492964)
		(width 0.127)
		(layer "In2.Cu")
		(net "P3E_CPU0_PE2_SS_C_TXN<4>")
	)
	(segment
		(start 65.86855 -26.395426)
		(end 65.642998 -26.439876)
		(width 0.127)
		(layer "In2.Cu")
		(net "P3E_CPU0_PE2_SS_C_TXN<4>")
	)
	(arc
		(start 88.340184 6.210554)
		(mid 88.318996 5.886578)
		(end 88.340184 5.5626)
		(width 0.127)
		(layer "In2.Cu")
		(net "P3E_CPU0_PE2_SS_C_TXN<4>")
	)
	(arc
		(start 88.340184 5.5626)
		(mid 88.359406 5.184749)
		(end 88.317578 4.808728)
		(width 0.127)
		(layer "In2.Cu")
		(net "P3E_CPU0_PE2_SS_C_TXN<4>")
	)
	(arc
		(start 88.317578 4.808728)
		(mid 88.082362 3.945364)
		(end 87.720424 3.126994)
		(width 0.127)
		(layer "In2.Cu")
		(net "P3E_CPU0_PE2_SS_C_TXN<4>")
	)
	(arc
		(start 74.774806 -8.177276)
		(mid 74.377606 -8.771727)
		(end 74.238104 -9.47293)
		(width 0.127)
		(layer "In2.Cu")
		(net "P3E_CPU0_PE2_SS_C_TXN<4>")
	)
	(arc
		(start 75.226164 -7.2771)
		(mid 75.143717 -7.691679)
		(end 74.908918 -8.043164)
		(width 0.127)
		(layer "In2.Cu")
		(net "P3E_CPU0_PE2_SS_C_TXN<4>")
	)
	(arc
		(start 74.73188 -12.70508)
		(mid 75.096609 -13.250936)
		(end 75.22464 -13.894816)
		(width 0.127)
		(layer "In2.Cu")
		(net "P3E_CPU0_PE2_SS_C_TXN<4>")
	)
	(arc
		(start 65.531492 -28.382468)
		(mid 65.62844 -28.389445)
		(end 65.701926 -28.325826)
		(width 0.127)
		(layer "In2.Cu")
		(net "P3E_CPU0_PE2_SS_C_TXN<4>")
	)
	(arc
		(start 74.238104 -11.63066)
		(mid 74.344729 -12.167169)
		(end 74.648568 -12.622022)
		(width 0.127)
		(layer "In2.Cu")
		(net "P3E_CPU0_PE2_SS_C_TXN<4>")
	)
	(arc
		(start 88.684354 7.702042)
		(mid 88.447078 7.415507)
		(end 88.362028 7.053326)
		(width 0.127)
		(layer "In2.Cu")
		(net "P3E_CPU0_PE2_SS_C_TXN<4>")
	)
	(arc
		(start 88.362028 7.053326)
		(mid 88.373151 6.631369)
		(end 88.340184 6.210554)
		(width 0.127)
		(layer "In2.Cu")
		(net "P3E_CPU0_PE2_SS_C_TXN<4>")
	)
	(arc
		(start 65.430654 -26.756106)
		(mid 65.238432 -27.319889)
		(end 65.174114 -27.91206)
		(width 0.127)
		(layer "In2.Cu")
		(net "P3E_CPU0_PE2_SS_C_TXN<4>")
	)
	(arc
		(start 65.174114 -27.91206)
		(mid 65.235062 -28.154985)
		(end 65.418208 -28.325826)
		(width 0.127)
		(layer "In2.Cu")
		(net "P3E_CPU0_PE2_SS_C_TXN<4>")
	)
	(segment
		(start 86.2584 8.8138)
		(end 85.862414 8.417814)
		(width 0.127)
		(layer "F.Cu")
		(net "P3E_CPU0_PE2_SS_C_TXN<3>")
	)
	(segment
		(start 86.532212 10.373868)
		(end 86.532212 9.474962)
		(width 0.127)
		(layer "F.Cu")
		(net "P3E_CPU0_PE2_SS_C_TXN<3>")
	)
	(segment
		(start 86.049358 7.702042)
		(end 86.093554 7.702042)
		(width 0.127)
		(layer "F.Cu")
		(net "P3E_CPU0_PE2_SS_C_TXN<3>")
	)
	(segment
		(start 86.779862 12.133072)
		(end 86.779862 10.971784)
		(width 0.127)
		(layer "F.Cu")
		(net "P3E_CPU0_PE2_SS_C_TXN<3>")
	)
	(segment
		(start 85.7504 8.147304)
		(end 85.7504 8.001)
		(width 0.127)
		(layer "F.Cu")
		(net "P3E_CPU0_PE2_SS_C_TXN<3>")
	)
	(via
		(at 86.093554 7.702042)
		(size 0.508)
		(drill 0.254)
		(layers "F.Cu" "B.Cu")
		(net "P3E_CPU0_PE2_SS_C_TXN<3>")
	)
	(arc
		(start 86.779862 10.971784)
		(mid 86.747709 10.810138)
		(end 86.656164 10.67308)
		(width 0.127)
		(layer "F.Cu")
		(net "P3E_CPU0_PE2_SS_C_TXN<3>")
	)
	(arc
		(start 86.532212 9.474962)
		(mid 86.461041 9.117163)
		(end 86.2584 8.8138)
		(width 0.127)
		(layer "F.Cu")
		(net "P3E_CPU0_PE2_SS_C_TXN<3>")
	)
	(arc
		(start 85.7504 8.001)
		(mid 85.837963 7.789605)
		(end 86.049358 7.702042)
		(width 0.127)
		(layer "F.Cu")
		(net "P3E_CPU0_PE2_SS_C_TXN<3>")
	)
	(arc
		(start 86.656164 10.67308)
		(mid 86.564437 10.5358)
		(end 86.532212 10.373868)
		(width 0.127)
		(layer "F.Cu")
		(net "P3E_CPU0_PE2_SS_C_TXN<3>")
	)
	(arc
		(start 85.862414 8.417814)
		(mid 85.779486 8.293703)
		(end 85.7504 8.147304)
		(width 0.127)
		(layer "F.Cu")
		(net "P3E_CPU0_PE2_SS_C_TXN<3>")
	)
	(segment
		(start 70.771258 -16.854424)
		(end 70.771004 -16.855186)
		(width 0.127)
		(layer "In2.Cu")
		(net "P3E_CPU0_PE2_SS_C_TXN<3>")
	)
	(segment
		(start 62.173358 -24.319738)
		(end 62.13983 -24.547068)
		(width 0.127)
		(layer "In2.Cu")
		(net "P3E_CPU0_PE2_SS_C_TXN<3>")
	)
	(segment
		(start 59.531504 -28.382722)
		(end 59.531758 -28.382722)
		(width 0.127)
		(layer "In2.Cu")
		(net "P3E_CPU0_PE2_SS_C_TXN<3>")
	)
	(segment
		(start 60.733432 -25.388316)
		(end 60.427362 -25.615392)
		(width 0.127)
		(layer "In2.Cu")
		(net "P3E_CPU0_PE2_SS_C_TXN<3>")
	)
	(segment
		(start 85.766148 5.523484)
		(end 85.766148 4.58724)
		(width 0.127)
		(layer "In2.Cu")
		(net "P3E_CPU0_PE2_SS_C_TXN<3>")
	)
	(segment
		(start 61.60643 -24.740362)
		(end 61.30036 -24.967438)
		(width 0.127)
		(layer "In2.Cu")
		(net "P3E_CPU0_PE2_SS_C_TXN<3>")
	)
	(segment
		(start 60.960762 -25.421844)
		(end 60.733432 -25.388316)
		(width 0.127)
		(layer "In2.Cu")
		(net "P3E_CPU0_PE2_SS_C_TXN<3>")
	)
	(segment
		(start 71.22414 -13.894816)
		(end 71.22414 -14.313662)
		(width 0.127)
		(layer "In2.Cu")
		(net "P3E_CPU0_PE2_SS_C_TXN<3>")
	)
	(segment
		(start 76.811378 -1.22047)
		(end 73.128378 -3.799078)
		(width 0.127)
		(layer "In2.Cu")
		(net "P3E_CPU0_PE2_SS_C_TXN<3>")
	)
	(segment
		(start 60.393834 -25.842722)
		(end 60.087764 -26.069798)
		(width 0.127)
		(layer "In2.Cu")
		(net "P3E_CPU0_PE2_SS_C_TXN<3>")
	)
	(segment
		(start 70.772782 -16.851122)
		(end 70.771258 -16.854424)
		(width 0.127)
		(layer "In2.Cu")
		(net "P3E_CPU0_PE2_SS_C_TXN<3>")
	)
	(segment
		(start 61.30036 -24.967438)
		(end 61.266832 -25.195022)
		(width 0.127)
		(layer "In2.Cu")
		(net "P3E_CPU0_PE2_SS_C_TXN<3>")
	)
	(segment
		(start 70.908418 -8.043164)
		(end 70.774306 -8.177276)
		(width 0.127)
		(layer "In2.Cu")
		(net "P3E_CPU0_PE2_SS_C_TXN<3>")
	)
	(segment
		(start 60.427362 -25.615392)
		(end 60.393834 -25.842722)
		(width 0.127)
		(layer "In2.Cu")
		(net "P3E_CPU0_PE2_SS_C_TXN<3>")
	)
	(segment
		(start 83.67395 1.012444)
		(end 81.722722 -0.353822)
		(width 0.127)
		(layer "In2.Cu")
		(net "P3E_CPU0_PE2_SS_C_TXN<3>")
	)
	(segment
		(start 61.83376 -24.774144)
		(end 61.60643 -24.740362)
		(width 0.127)
		(layer "In2.Cu")
		(net "P3E_CPU0_PE2_SS_C_TXN<3>")
	)
	(segment
		(start 70.777354 -16.84909)
		(end 70.772782 -16.851122)
		(width 0.127)
		(layer "In2.Cu")
		(net "P3E_CPU0_PE2_SS_C_TXN<3>")
	)
	(segment
		(start 70.70217 -17.02054)
		(end 67.79387 -20.149312)
		(width 0.127)
		(layer "In2.Cu")
		(net "P3E_CPU0_PE2_SS_C_TXN<3>")
	)
	(segment
		(start 85.748114 6.548628)
		(end 85.703918 6.026404)
		(width 0.127)
		(layer "In2.Cu")
		(net "P3E_CPU0_PE2_SS_C_TXN<3>")
	)
	(segment
		(start 71.22414 -14.313662)
		(end 70.777354 -16.84909)
		(width 0.127)
		(layer "In2.Cu")
		(net "P3E_CPU0_PE2_SS_C_TXN<3>")
	)
	(segment
		(start 70.771004 -16.855186)
		(end 70.771004 -16.854932)
		(width 0.127)
		(layer "In2.Cu")
		(net "P3E_CPU0_PE2_SS_C_TXN<3>")
	)
	(segment
		(start 71.287386 -6.428232)
		(end 71.225664 -6.77926)
		(width 0.127)
		(layer "In2.Cu")
		(net "P3E_CPU0_PE2_SS_C_TXN<3>")
	)
	(segment
		(start 70.237604 -9.47293)
		(end 70.237604 -11.63066)
		(width 0.127)
		(layer "In2.Cu")
		(net "P3E_CPU0_PE2_SS_C_TXN<3>")
	)
	(segment
		(start 59.554364 -26.263092)
		(end 59.149996 -27.723338)
		(width 0.127)
		(layer "In2.Cu")
		(net "P3E_CPU0_PE2_SS_C_TXN<3>")
	)
	(segment
		(start 59.417712 -28.32608)
		(end 59.531504 -28.382722)
		(width 0.127)
		(layer "In2.Cu")
		(net "P3E_CPU0_PE2_SS_C_TXN<3>")
	)
	(segment
		(start 85.703918 6.026404)
		(end 85.766148 5.523484)
		(width 0.127)
		(layer "In2.Cu")
		(net "P3E_CPU0_PE2_SS_C_TXN<3>")
	)
	(segment
		(start 61.266832 -25.195022)
		(end 60.960762 -25.421844)
		(width 0.127)
		(layer "In2.Cu")
		(net "P3E_CPU0_PE2_SS_C_TXN<3>")
	)
	(segment
		(start 70.648068 -12.622022)
		(end 70.73138 -12.70508)
		(width 0.127)
		(layer "In2.Cu")
		(net "P3E_CPU0_PE2_SS_C_TXN<3>")
	)
	(segment
		(start 71.225664 -6.77926)
		(end 71.225664 -7.2771)
		(width 0.127)
		(layer "In2.Cu")
		(net "P3E_CPU0_PE2_SS_C_TXN<3>")
	)
	(segment
		(start 59.860434 -26.036016)
		(end 59.554364 -26.263092)
		(width 0.127)
		(layer "In2.Cu")
		(net "P3E_CPU0_PE2_SS_C_TXN<3>")
	)
	(segment
		(start 73.128378 -3.799078)
		(end 71.287386 -6.428232)
		(width 0.127)
		(layer "In2.Cu")
		(net "P3E_CPU0_PE2_SS_C_TXN<3>")
	)
	(segment
		(start 67.79387 -20.149312)
		(end 62.173358 -24.319738)
		(width 0.127)
		(layer "In2.Cu")
		(net "P3E_CPU0_PE2_SS_C_TXN<3>")
	)
	(segment
		(start 70.771004 -16.854932)
		(end 70.70217 -17.02054)
		(width 0.127)
		(layer "In2.Cu")
		(net "P3E_CPU0_PE2_SS_C_TXN<3>")
	)
	(segment
		(start 85.748114 7.242048)
		(end 85.748114 6.548628)
		(width 0.127)
		(layer "In2.Cu")
		(net "P3E_CPU0_PE2_SS_C_TXN<3>")
	)
	(segment
		(start 62.13983 -24.547068)
		(end 61.83376 -24.774144)
		(width 0.127)
		(layer "In2.Cu")
		(net "P3E_CPU0_PE2_SS_C_TXN<3>")
	)
	(segment
		(start 60.087764 -26.069798)
		(end 59.860434 -26.036016)
		(width 0.127)
		(layer "In2.Cu")
		(net "P3E_CPU0_PE2_SS_C_TXN<3>")
	)
	(segment
		(start 85.766148 4.58724)
		(end 85.76183 4.536694)
		(width 0.127)
		(layer "In2.Cu")
		(net "P3E_CPU0_PE2_SS_C_TXN<3>")
	)
	(segment
		(start 85.76183 4.536694)
		(end 85.634068 3.811524)
		(width 0.127)
		(layer "In2.Cu")
		(net "P3E_CPU0_PE2_SS_C_TXN<3>")
	)
	(segment
		(start 59.701938 -28.325826)
		(end 60.079382 -27.570176)
		(width 0.127)
		(layer "In2.Cu")
		(net "P3E_CPU0_PE2_SS_C_TXN<3>")
	)
	(segment
		(start 81.722722 -0.353822)
		(end 76.811378 -1.22047)
		(width 0.127)
		(layer "In2.Cu")
		(net "P3E_CPU0_PE2_SS_C_TXN<3>")
	)
	(segment
		(start 85.634068 3.811524)
		(end 83.67395 1.012444)
		(width 0.127)
		(layer "In2.Cu")
		(net "P3E_CPU0_PE2_SS_C_TXN<3>")
	)
	(arc
		(start 70.237604 -11.63066)
		(mid 70.344229 -12.167169)
		(end 70.648068 -12.622022)
		(width 0.127)
		(layer "In2.Cu")
		(net "P3E_CPU0_PE2_SS_C_TXN<3>")
	)
	(arc
		(start 70.73138 -12.70508)
		(mid 71.096109 -13.250936)
		(end 71.22414 -13.894816)
		(width 0.127)
		(layer "In2.Cu")
		(net "P3E_CPU0_PE2_SS_C_TXN<3>")
	)
	(arc
		(start 70.774306 -8.177276)
		(mid 70.377106 -8.771727)
		(end 70.237604 -9.47293)
		(width 0.127)
		(layer "In2.Cu")
		(net "P3E_CPU0_PE2_SS_C_TXN<3>")
	)
	(arc
		(start 59.531758 -28.382722)
		(mid 59.628632 -28.389519)
		(end 59.701938 -28.325826)
		(width 0.127)
		(layer "In2.Cu")
		(net "P3E_CPU0_PE2_SS_C_TXN<3>")
	)
	(arc
		(start 86.093554 7.702042)
		(mid 85.84803 7.526718)
		(end 85.748114 7.242048)
		(width 0.127)
		(layer "In2.Cu")
		(net "P3E_CPU0_PE2_SS_C_TXN<3>")
	)
	(arc
		(start 71.225664 -7.2771)
		(mid 71.143217 -7.691679)
		(end 70.908418 -8.043164)
		(width 0.127)
		(layer "In2.Cu")
		(net "P3E_CPU0_PE2_SS_C_TXN<3>")
	)
	(arc
		(start 59.149996 -27.723338)
		(mid 59.175805 -28.072725)
		(end 59.417712 -28.32608)
		(width 0.127)
		(layer "In2.Cu")
		(net "P3E_CPU0_PE2_SS_C_TXN<3>")
	)
	(segment
		(start 84.132166 10.373868)
		(end 84.132166 9.658604)
		(width 0.127)
		(layer "F.Cu")
		(net "P3E_CPU0_PE2_SS_C_TXN<2>")
	)
	(segment
		(start 83.8454 8.9662)
		(end 83.25358 8.374126)
		(width 0.127)
		(layer "F.Cu")
		(net "P3E_CPU0_PE2_SS_C_TXN<2>")
	)
	(segment
		(start 84.379816 12.133072)
		(end 84.379816 10.971784)
		(width 0.127)
		(layer "F.Cu")
		(net "P3E_CPU0_PE2_SS_C_TXN<2>")
	)
	(segment
		(start 83.1596 8.147304)
		(end 83.1596 8.001)
		(width 0.127)
		(layer "F.Cu")
		(net "P3E_CPU0_PE2_SS_C_TXN<2>")
	)
	(segment
		(start 83.458558 7.702042)
		(end 83.502754 7.702042)
		(width 0.127)
		(layer "F.Cu")
		(net "P3E_CPU0_PE2_SS_C_TXN<2>")
	)
	(via
		(at 83.502754 7.702042)
		(size 0.508)
		(drill 0.254)
		(layers "F.Cu" "B.Cu")
		(net "P3E_CPU0_PE2_SS_C_TXN<2>")
	)
	(arc
		(start 83.25358 8.374126)
		(mid 83.184045 8.270059)
		(end 83.1596 8.147304)
		(width 0.127)
		(layer "F.Cu")
		(net "P3E_CPU0_PE2_SS_C_TXN<2>")
	)
	(arc
		(start 84.132166 9.658604)
		(mid 84.057631 9.283892)
		(end 83.8454 8.9662)
		(width 0.127)
		(layer "F.Cu")
		(net "P3E_CPU0_PE2_SS_C_TXN<2>")
	)
	(arc
		(start 84.256118 10.67308)
		(mid 84.164391 10.5358)
		(end 84.132166 10.373868)
		(width 0.127)
		(layer "F.Cu")
		(net "P3E_CPU0_PE2_SS_C_TXN<2>")
	)
	(arc
		(start 83.1596 8.001)
		(mid 83.247163 7.789605)
		(end 83.458558 7.702042)
		(width 0.127)
		(layer "F.Cu")
		(net "P3E_CPU0_PE2_SS_C_TXN<2>")
	)
	(arc
		(start 84.379816 10.971784)
		(mid 84.347663 10.810138)
		(end 84.256118 10.67308)
		(width 0.127)
		(layer "F.Cu")
		(net "P3E_CPU0_PE2_SS_C_TXN<2>")
	)
	(segment
		(start 58.617866 -23.786846)
		(end 58.577988 -24.013414)
		(width 0.127)
		(layer "In2.Cu")
		(net "P3E_CPU0_PE2_SS_C_TXN<2>")
	)
	(segment
		(start 56.836818 -25.033986)
		(end 56.79694 -25.2603)
		(width 0.127)
		(layer "In2.Cu")
		(net "P3E_CPU0_PE2_SS_C_TXN<2>")
	)
	(segment
		(start 67.22491 -13.894816)
		(end 67.22491 -14.313662)
		(width 0.127)
		(layer "In2.Cu")
		(net "P3E_CPU0_PE2_SS_C_TXN<2>")
	)
	(segment
		(start 56.79694 -25.2603)
		(end 56.484774 -25.478994)
		(width 0.127)
		(layer "In2.Cu")
		(net "P3E_CPU0_PE2_SS_C_TXN<2>")
	)
	(segment
		(start 83.045046 3.764788)
		(end 82.159348 2.499868)
		(width 0.127)
		(layer "In2.Cu")
		(net "P3E_CPU0_PE2_SS_C_TXN<2>")
	)
	(segment
		(start 83.101942 5.880608)
		(end 83.175348 5.523484)
		(width 0.127)
		(layer "In2.Cu")
		(net "P3E_CPU0_PE2_SS_C_TXN<2>")
	)
	(segment
		(start 57.375298 -24.855424)
		(end 57.148984 -24.815546)
		(width 0.127)
		(layer "In2.Cu")
		(net "P3E_CPU0_PE2_SS_C_TXN<2>")
	)
	(segment
		(start 66.648838 -12.622022)
		(end 66.73215 -12.70508)
		(width 0.127)
		(layer "In2.Cu")
		(net "P3E_CPU0_PE2_SS_C_TXN<2>")
	)
	(segment
		(start 56.484774 -25.478994)
		(end 56.25846 -25.439116)
		(width 0.127)
		(layer "In2.Cu")
		(net "P3E_CPU0_PE2_SS_C_TXN<2>")
	)
	(segment
		(start 64.708532 -19.522186)
		(end 58.617866 -23.786846)
		(width 0.127)
		(layer "In2.Cu")
		(net "P3E_CPU0_PE2_SS_C_TXN<2>")
	)
	(segment
		(start 55.946294 -25.657556)
		(end 55.430674 -26.756106)
		(width 0.127)
		(layer "In2.Cu")
		(net "P3E_CPU0_PE2_SS_C_TXN<2>")
	)
	(segment
		(start 66.909188 -8.043164)
		(end 66.775076 -8.177276)
		(width 0.127)
		(layer "In2.Cu")
		(net "P3E_CPU0_PE2_SS_C_TXN<2>")
	)
	(segment
		(start 83.157314 7.242048)
		(end 83.157314 6.547866)
		(width 0.127)
		(layer "In2.Cu")
		(net "P3E_CPU0_PE2_SS_C_TXN<2>")
	)
	(segment
		(start 66.844418 -16.4719)
		(end 64.708532 -19.522186)
		(width 0.127)
		(layer "In2.Cu")
		(net "P3E_CPU0_PE2_SS_C_TXN<2>")
	)
	(segment
		(start 74.198226 0.267208)
		(end 69.76999 -2.833624)
		(width 0.127)
		(layer "In2.Cu")
		(net "P3E_CPU0_PE2_SS_C_TXN<2>")
	)
	(segment
		(start 57.148984 -24.815546)
		(end 56.836818 -25.033986)
		(width 0.127)
		(layer "In2.Cu")
		(net "P3E_CPU0_PE2_SS_C_TXN<2>")
	)
	(segment
		(start 58.577988 -24.013414)
		(end 58.265822 -24.231854)
		(width 0.127)
		(layer "In2.Cu")
		(net "P3E_CPU0_PE2_SS_C_TXN<2>")
	)
	(segment
		(start 80.576928 1.39192)
		(end 74.198226 0.267208)
		(width 0.127)
		(layer "In2.Cu")
		(net "P3E_CPU0_PE2_SS_C_TXN<2>")
	)
	(segment
		(start 82.159348 2.499868)
		(end 80.576928 1.39192)
		(width 0.127)
		(layer "In2.Cu")
		(net "P3E_CPU0_PE2_SS_C_TXN<2>")
	)
	(segment
		(start 57.727342 -24.410416)
		(end 57.687464 -24.636984)
		(width 0.127)
		(layer "In2.Cu")
		(net "P3E_CPU0_PE2_SS_C_TXN<2>")
	)
	(segment
		(start 58.039508 -24.191976)
		(end 57.727342 -24.410416)
		(width 0.127)
		(layer "In2.Cu")
		(net "P3E_CPU0_PE2_SS_C_TXN<2>")
	)
	(segment
		(start 55.701946 -28.325826)
		(end 56.080152 -27.570176)
		(width 0.127)
		(layer "In2.Cu")
		(net "P3E_CPU0_PE2_SS_C_TXN<2>")
	)
	(segment
		(start 83.175348 4.503928)
		(end 83.045046 3.764788)
		(width 0.127)
		(layer "In2.Cu")
		(net "P3E_CPU0_PE2_SS_C_TXN<2>")
	)
	(segment
		(start 55.531258 -28.382468)
		(end 55.531512 -28.382468)
		(width 0.127)
		(layer "In2.Cu")
		(net "P3E_CPU0_PE2_SS_C_TXN<2>")
	)
	(segment
		(start 83.099402 5.902706)
		(end 83.101942 5.880608)
		(width 0.127)
		(layer "In2.Cu")
		(net "P3E_CPU0_PE2_SS_C_TXN<2>")
	)
	(segment
		(start 57.687464 -24.636984)
		(end 57.375298 -24.855424)
		(width 0.127)
		(layer "In2.Cu")
		(net "P3E_CPU0_PE2_SS_C_TXN<2>")
	)
	(segment
		(start 66.238374 -9.47293)
		(end 66.238374 -11.63066)
		(width 0.127)
		(layer "In2.Cu")
		(net "P3E_CPU0_PE2_SS_C_TXN<2>")
	)
	(segment
		(start 55.418228 -28.325826)
		(end 55.531258 -28.382468)
		(width 0.127)
		(layer "In2.Cu")
		(net "P3E_CPU0_PE2_SS_C_TXN<2>")
	)
	(segment
		(start 67.226434 -6.77926)
		(end 67.226434 -7.2771)
		(width 0.127)
		(layer "In2.Cu")
		(net "P3E_CPU0_PE2_SS_C_TXN<2>")
	)
	(segment
		(start 56.25846 -25.439116)
		(end 55.946294 -25.657556)
		(width 0.127)
		(layer "In2.Cu")
		(net "P3E_CPU0_PE2_SS_C_TXN<2>")
	)
	(segment
		(start 58.265822 -24.231854)
		(end 58.039508 -24.191976)
		(width 0.127)
		(layer "In2.Cu")
		(net "P3E_CPU0_PE2_SS_C_TXN<2>")
	)
	(segment
		(start 69.76999 -2.833624)
		(end 67.300348 -6.36016)
		(width 0.127)
		(layer "In2.Cu")
		(net "P3E_CPU0_PE2_SS_C_TXN<2>")
	)
	(segment
		(start 67.300348 -6.36016)
		(end 67.226434 -6.77926)
		(width 0.127)
		(layer "In2.Cu")
		(net "P3E_CPU0_PE2_SS_C_TXN<2>")
	)
	(segment
		(start 83.175348 5.523484)
		(end 83.175348 4.503928)
		(width 0.127)
		(layer "In2.Cu")
		(net "P3E_CPU0_PE2_SS_C_TXN<2>")
	)
	(segment
		(start 67.22491 -14.313662)
		(end 66.844418 -16.4719)
		(width 0.127)
		(layer "In2.Cu")
		(net "P3E_CPU0_PE2_SS_C_TXN<2>")
	)
	(segment
		(start 83.157314 6.547866)
		(end 83.099402 5.902706)
		(width 0.127)
		(layer "In2.Cu")
		(net "P3E_CPU0_PE2_SS_C_TXN<2>")
	)
	(arc
		(start 66.238374 -11.63066)
		(mid 66.344999 -12.167169)
		(end 66.648838 -12.622022)
		(width 0.127)
		(layer "In2.Cu")
		(net "P3E_CPU0_PE2_SS_C_TXN<2>")
	)
	(arc
		(start 55.174134 -27.91206)
		(mid 55.235082 -28.154985)
		(end 55.418228 -28.325826)
		(width 0.127)
		(layer "In2.Cu")
		(net "P3E_CPU0_PE2_SS_C_TXN<2>")
	)
	(arc
		(start 55.531512 -28.382468)
		(mid 55.62846 -28.389445)
		(end 55.701946 -28.325826)
		(width 0.127)
		(layer "In2.Cu")
		(net "P3E_CPU0_PE2_SS_C_TXN<2>")
	)
	(arc
		(start 66.73215 -12.70508)
		(mid 67.096879 -13.250936)
		(end 67.22491 -13.894816)
		(width 0.127)
		(layer "In2.Cu")
		(net "P3E_CPU0_PE2_SS_C_TXN<2>")
	)
	(arc
		(start 67.226434 -7.2771)
		(mid 67.143987 -7.691679)
		(end 66.909188 -8.043164)
		(width 0.127)
		(layer "In2.Cu")
		(net "P3E_CPU0_PE2_SS_C_TXN<2>")
	)
	(arc
		(start 66.775076 -8.177276)
		(mid 66.377876 -8.771727)
		(end 66.238374 -9.47293)
		(width 0.127)
		(layer "In2.Cu")
		(net "P3E_CPU0_PE2_SS_C_TXN<2>")
	)
	(arc
		(start 55.430674 -26.756106)
		(mid 55.238452 -27.319889)
		(end 55.174134 -27.91206)
		(width 0.127)
		(layer "In2.Cu")
		(net "P3E_CPU0_PE2_SS_C_TXN<2>")
	)
	(arc
		(start 83.502754 7.702042)
		(mid 83.25723 7.526718)
		(end 83.157314 7.242048)
		(width 0.127)
		(layer "In2.Cu")
		(net "P3E_CPU0_PE2_SS_C_TXN<2>")
	)
	(segment
		(start 127.808736 9.091676)
		(end 127.240284 9.903714)
		(width 0.127)
		(layer "F.Cu")
		(net "P3E_CPU0_PE2_SS_C_TXN<15>")
	)
	(segment
		(start 128.394206 7.742682)
		(end 128.292098 7.742682)
		(width 0.127)
		(layer "F.Cu")
		(net "P3E_CPU0_PE2_SS_C_TXN<15>")
	)
	(segment
		(start 127.219202 9.954514)
		(end 127.127254 10.475468)
		(width 0.127)
		(layer "F.Cu")
		(net "P3E_CPU0_PE2_SS_C_TXN<15>")
	)
	(segment
		(start 128.04394 7.99084)
		(end 127.902462 8.792718)
		(width 0.127)
		(layer "F.Cu")
		(net "P3E_CPU0_PE2_SS_C_TXN<15>")
	)
	(segment
		(start 127.374904 11.073384)
		(end 127.375158 12.234672)
		(width 0.127)
		(layer "F.Cu")
		(net "P3E_CPU0_PE2_SS_C_TXN<15>")
	)
	(segment
		(start 127.902462 8.792718)
		(end 127.88011 8.918956)
		(width 0.127)
		(layer "F.Cu")
		(net "P3E_CPU0_PE2_SS_C_TXN<15>")
	)
	(via
		(at 128.394206 7.742682)
		(size 0.508)
		(drill 0.254)
		(layers "F.Cu" "B.Cu")
		(net "P3E_CPU0_PE2_SS_C_TXN<15>")
	)
	(arc
		(start 127.240284 9.903714)
		(mid 127.226956 9.927958)
		(end 127.219202 9.954514)
		(width 0.127)
		(layer "F.Cu")
		(net "P3E_CPU0_PE2_SS_C_TXN<15>")
	)
	(arc
		(start 127.251206 10.77468)
		(mid 127.342778 10.911727)
		(end 127.374904 11.073384)
		(width 0.127)
		(layer "F.Cu")
		(net "P3E_CPU0_PE2_SS_C_TXN<15>")
	)
	(arc
		(start 127.127254 10.475468)
		(mid 127.159465 10.637406)
		(end 127.251206 10.77468)
		(width 0.127)
		(layer "F.Cu")
		(net "P3E_CPU0_PE2_SS_C_TXN<15>")
	)
	(arc
		(start 128.292098 7.742682)
		(mid 128.116624 7.815366)
		(end 128.04394 7.99084)
		(width 0.127)
		(layer "F.Cu")
		(net "P3E_CPU0_PE2_SS_C_TXN<15>")
	)
	(arc
		(start 127.88011 8.918956)
		(mid 127.853868 9.009217)
		(end 127.808736 9.091676)
		(width 0.127)
		(layer "F.Cu")
		(net "P3E_CPU0_PE2_SS_C_TXN<15>")
	)
	(segment
		(start 128.394206 7.742682)
		(end 128.17729 7.453884)
		(width 0.127)
		(layer "In2.Cu")
		(net "P3E_CPU0_PE2_SS_C_TXN<15>")
	)
	(segment
		(start 120.469406 -8.210296)
		(end 119.801894 -11.995658)
		(width 0.127)
		(layer "In2.Cu")
		(net "P3E_CPU0_PE2_SS_C_TXN<15>")
	)
	(segment
		(start 110.87227 -28.587192)
		(end 110.758732 -28.644088)
		(width 0.127)
		(layer "In2.Cu")
		(net "P3E_CPU0_PE2_SS_C_TXN<15>")
	)
	(segment
		(start 113.019332 -21.682202)
		(end 111.252 -27.350212)
		(width 0.127)
		(layer "In2.Cu")
		(net "P3E_CPU0_PE2_SS_C_TXN<15>")
	)
	(segment
		(start 119.801894 -11.995658)
		(end 113.019332 -21.682202)
		(width 0.127)
		(layer "In2.Cu")
		(net "P3E_CPU0_PE2_SS_C_TXN<15>")
	)
	(segment
		(start 110.701836 -28.814522)
		(end 111.080042 -29.570426)
		(width 0.127)
		(layer "In2.Cu")
		(net "P3E_CPU0_PE2_SS_C_TXN<15>")
	)
	(segment
		(start 111.252 -27.350212)
		(end 111.26216 -27.46756)
		(width 0.127)
		(layer "In2.Cu")
		(net "P3E_CPU0_PE2_SS_C_TXN<15>")
	)
	(segment
		(start 128.027684 4.849368)
		(end 127.440436 1.745488)
		(width 0.127)
		(layer "In2.Cu")
		(net "P3E_CPU0_PE2_SS_C_TXN<15>")
	)
	(segment
		(start 128.050036 7.07263)
		(end 128.050036 6.251194)
		(width 0.127)
		(layer "In2.Cu")
		(net "P3E_CPU0_PE2_SS_C_TXN<15>")
	)
	(segment
		(start 110.758732 -28.644088)
		(end 110.758478 -28.644088)
		(width 0.127)
		(layer "In2.Cu")
		(net "P3E_CPU0_PE2_SS_C_TXN<15>")
	)
	(segment
		(start 127.440436 1.745488)
		(end 120.469406 -8.210296)
		(width 0.127)
		(layer "In2.Cu")
		(net "P3E_CPU0_PE2_SS_C_TXN<15>")
	)
	(arc
		(start 111.26216 -27.46756)
		(mid 111.299308 -27.745978)
		(end 111.28248 -28.02636)
		(width 0.127)
		(layer "In2.Cu")
		(net "P3E_CPU0_PE2_SS_C_TXN<15>")
	)
	(arc
		(start 128.050036 5.60324)
		(mid 128.069381 5.225399)
		(end 128.027684 4.849368)
		(width 0.127)
		(layer "In2.Cu")
		(net "P3E_CPU0_PE2_SS_C_TXN<15>")
	)
	(arc
		(start 128.050036 6.251194)
		(mid 128.028848 5.927218)
		(end 128.050036 5.60324)
		(width 0.127)
		(layer "In2.Cu")
		(net "P3E_CPU0_PE2_SS_C_TXN<15>")
	)
	(arc
		(start 111.28248 -28.02636)
		(mid 111.145235 -28.356391)
		(end 110.87227 -28.587192)
		(width 0.127)
		(layer "In2.Cu")
		(net "P3E_CPU0_PE2_SS_C_TXN<15>")
	)
	(arc
		(start 128.17729 7.453884)
		(mid 128.082689 7.273595)
		(end 128.050036 7.07263)
		(width 0.127)
		(layer "In2.Cu")
		(net "P3E_CPU0_PE2_SS_C_TXN<15>")
	)
	(arc
		(start 110.758478 -28.644088)
		(mid 110.694859 -28.717574)
		(end 110.701836 -28.814522)
		(width 0.127)
		(layer "In2.Cu")
		(net "P3E_CPU0_PE2_SS_C_TXN<15>")
	)
	(segment
		(start 125.3236 9.249156)
		(end 124.8156 9.974326)
		(width 0.127)
		(layer "F.Cu")
		(net "P3E_CPU0_PE2_SS_C_TXN<14>")
	)
	(segment
		(start 125.460252 8.47344)
		(end 125.3236 9.249156)
		(width 0.127)
		(layer "F.Cu")
		(net "P3E_CPU0_PE2_SS_C_TXN<14>")
	)
	(segment
		(start 125.460252 8.04164)
		(end 125.460252 8.47344)
		(width 0.127)
		(layer "F.Cu")
		(net "P3E_CPU0_PE2_SS_C_TXN<14>")
	)
	(segment
		(start 125.803406 7.742682)
		(end 125.75921 7.742682)
		(width 0.127)
		(layer "F.Cu")
		(net "P3E_CPU0_PE2_SS_C_TXN<14>")
	)
	(segment
		(start 124.8156 9.974326)
		(end 124.727462 10.475468)
		(width 0.127)
		(layer "F.Cu")
		(net "P3E_CPU0_PE2_SS_C_TXN<14>")
	)
	(segment
		(start 124.975112 11.073384)
		(end 124.975112 12.234672)
		(width 0.127)
		(layer "F.Cu")
		(net "P3E_CPU0_PE2_SS_C_TXN<14>")
	)
	(via
		(at 125.803406 7.742682)
		(size 0.508)
		(drill 0.254)
		(layers "F.Cu" "B.Cu")
		(net "P3E_CPU0_PE2_SS_C_TXN<14>")
	)
	(arc
		(start 124.727462 10.475468)
		(mid 124.759673 10.637406)
		(end 124.851414 10.77468)
		(width 0.127)
		(layer "F.Cu")
		(net "P3E_CPU0_PE2_SS_C_TXN<14>")
	)
	(arc
		(start 124.851414 10.77468)
		(mid 124.942986 10.911727)
		(end 124.975112 11.073384)
		(width 0.127)
		(layer "F.Cu")
		(net "P3E_CPU0_PE2_SS_C_TXN<14>")
	)
	(arc
		(start 125.75921 7.742682)
		(mid 125.547815 7.830245)
		(end 125.460252 8.04164)
		(width 0.127)
		(layer "F.Cu")
		(net "P3E_CPU0_PE2_SS_C_TXN<14>")
	)
	(segment
		(start 108.71835 -24.157432)
		(end 108.717842 -24.15794)
		(width 0.127)
		(layer "In2.Cu")
		(net "P3E_CPU0_PE2_SS_C_TXN<14>")
	)
	(segment
		(start 122.112786 -2.459736)
		(end 121.785888 -2.926334)
		(width 0.127)
		(layer "In2.Cu")
		(net "P3E_CPU0_PE2_SS_C_TXN<14>")
	)
	(segment
		(start 125.43663 4.849368)
		(end 124.817124 1.649984)
		(width 0.127)
		(layer "In2.Cu")
		(net "P3E_CPU0_PE2_SS_C_TXN<14>")
	)
	(segment
		(start 117.924072 -11.002518)
		(end 109.55274 -22.957282)
		(width 0.127)
		(layer "In2.Cu")
		(net "P3E_CPU0_PE2_SS_C_TXN<14>")
	)
	(segment
		(start 125.803406 7.742682)
		(end 125.58649 7.453884)
		(width 0.127)
		(layer "In2.Cu")
		(net "P3E_CPU0_PE2_SS_C_TXN<14>")
	)
	(segment
		(start 106.702606 -28.814522)
		(end 107.079542 -29.570426)
		(width 0.127)
		(layer "In2.Cu")
		(net "P3E_CPU0_PE2_SS_C_TXN<14>")
	)
	(segment
		(start 124.817124 1.649984)
		(end 124.758704 1.319022)
		(width 0.127)
		(layer "In2.Cu")
		(net "P3E_CPU0_PE2_SS_C_TXN<14>")
	)
	(segment
		(start 108.860844 -23.946104)
		(end 108.85932 -23.94839)
		(width 0.127)
		(layer "In2.Cu")
		(net "P3E_CPU0_PE2_SS_C_TXN<14>")
	)
	(segment
		(start 106.750104 -28.674568)
		(end 106.720132 -28.674568)
		(width 0.127)
		(layer "In2.Cu")
		(net "P3E_CPU0_PE2_SS_C_TXN<14>")
	)
	(segment
		(start 107.024424 -28.400248)
		(end 106.750104 -28.674568)
		(width 0.127)
		(layer "In2.Cu")
		(net "P3E_CPU0_PE2_SS_C_TXN<14>")
	)
	(segment
		(start 107.2896 -27.3558)
		(end 107.288076 -27.825446)
		(width 0.127)
		(layer "In2.Cu")
		(net "P3E_CPU0_PE2_SS_C_TXN<14>")
	)
	(segment
		(start 108.856272 -23.952454)
		(end 108.728002 -24.136096)
		(width 0.127)
		(layer "In2.Cu")
		(net "P3E_CPU0_PE2_SS_C_TXN<14>")
	)
	(segment
		(start 124.758704 1.319022)
		(end 122.660918 -1.676908)
		(width 0.127)
		(layer "In2.Cu")
		(net "P3E_CPU0_PE2_SS_C_TXN<14>")
	)
	(segment
		(start 108.727494 -24.137112)
		(end 108.71835 -24.157432)
		(width 0.127)
		(layer "In2.Cu")
		(net "P3E_CPU0_PE2_SS_C_TXN<14>")
	)
	(segment
		(start 125.459236 7.07263)
		(end 125.459236 6.251194)
		(width 0.127)
		(layer "In2.Cu")
		(net "P3E_CPU0_PE2_SS_C_TXN<14>")
	)
	(segment
		(start 108.85932 -23.94839)
		(end 108.859066 -23.948644)
		(width 0.127)
		(layer "In2.Cu")
		(net "P3E_CPU0_PE2_SS_C_TXN<14>")
	)
	(segment
		(start 117.944392 -10.88771)
		(end 117.944392 -10.973308)
		(width 0.127)
		(layer "In2.Cu")
		(net "P3E_CPU0_PE2_SS_C_TXN<14>")
	)
	(segment
		(start 107.288076 -27.825446)
		(end 107.024424 -28.400248)
		(width 0.127)
		(layer "In2.Cu")
		(net "P3E_CPU0_PE2_SS_C_TXN<14>")
	)
	(segment
		(start 122.660918 -1.676908)
		(end 122.112786 -2.459736)
		(width 0.127)
		(layer "In2.Cu")
		(net "P3E_CPU0_PE2_SS_C_TXN<14>")
	)
	(segment
		(start 117.944392 -10.973308)
		(end 117.924072 -11.002518)
		(width 0.127)
		(layer "In2.Cu")
		(net "P3E_CPU0_PE2_SS_C_TXN<14>")
	)
	(segment
		(start 121.785888 -2.926334)
		(end 118.526814 -7.580884)
		(width 0.127)
		(layer "In2.Cu")
		(net "P3E_CPU0_PE2_SS_C_TXN<14>")
	)
	(segment
		(start 118.526814 -7.580884)
		(end 117.944392 -10.88771)
		(width 0.127)
		(layer "In2.Cu")
		(net "P3E_CPU0_PE2_SS_C_TXN<14>")
	)
	(segment
		(start 108.930186 -23.84679)
		(end 108.860844 -23.946104)
		(width 0.127)
		(layer "In2.Cu")
		(net "P3E_CPU0_PE2_SS_C_TXN<14>")
	)
	(segment
		(start 108.728002 -24.136096)
		(end 108.727494 -24.137112)
		(width 0.127)
		(layer "In2.Cu")
		(net "P3E_CPU0_PE2_SS_C_TXN<14>")
	)
	(segment
		(start 108.859066 -23.948644)
		(end 108.856272 -23.952454)
		(width 0.127)
		(layer "In2.Cu")
		(net "P3E_CPU0_PE2_SS_C_TXN<14>")
	)
	(segment
		(start 108.717842 -24.15794)
		(end 107.2896 -27.3558)
		(width 0.127)
		(layer "In2.Cu")
		(net "P3E_CPU0_PE2_SS_C_TXN<14>")
	)
	(segment
		(start 109.55274 -22.957282)
		(end 108.930186 -23.84679)
		(width 0.127)
		(layer "In2.Cu")
		(net "P3E_CPU0_PE2_SS_C_TXN<14>")
	)
	(arc
		(start 125.459236 5.60324)
		(mid 125.478458 5.225389)
		(end 125.43663 4.849368)
		(width 0.127)
		(layer "In2.Cu")
		(net "P3E_CPU0_PE2_SS_C_TXN<14>")
	)
	(arc
		(start 125.58649 7.453884)
		(mid 125.491889 7.273595)
		(end 125.459236 7.07263)
		(width 0.127)
		(layer "In2.Cu")
		(net "P3E_CPU0_PE2_SS_C_TXN<14>")
	)
	(arc
		(start 125.459236 6.251194)
		(mid 125.438048 5.927218)
		(end 125.459236 5.60324)
		(width 0.127)
		(layer "In2.Cu")
		(net "P3E_CPU0_PE2_SS_C_TXN<14>")
	)
	(arc
		(start 106.720132 -28.674568)
		(mid 106.690171 -28.741884)
		(end 106.702606 -28.814522)
		(width 0.127)
		(layer "In2.Cu")
		(net "P3E_CPU0_PE2_SS_C_TXN<14>")
	)
	(segment
		(start 122.869452 8.47344)
		(end 122.869452 8.04164)
		(width 0.127)
		(layer "F.Cu")
		(net "P3E_CPU0_PE2_SS_C_TXN<13>")
	)
	(segment
		(start 122.575066 12.234672)
		(end 122.575066 11.073384)
		(width 0.127)
		(layer "F.Cu")
		(net "P3E_CPU0_PE2_SS_C_TXN<13>")
	)
	(segment
		(start 123.16841 7.742682)
		(end 123.212606 7.742682)
		(width 0.127)
		(layer "F.Cu")
		(net "P3E_CPU0_PE2_SS_C_TXN<13>")
	)
	(segment
		(start 122.327416 10.475468)
		(end 122.41403 9.984486)
		(width 0.127)
		(layer "F.Cu")
		(net "P3E_CPU0_PE2_SS_C_TXN<13>")
	)
	(segment
		(start 122.41403 9.984486)
		(end 122.66676 9.623806)
		(width 0.127)
		(layer "F.Cu")
		(net "P3E_CPU0_PE2_SS_C_TXN<13>")
	)
	(segment
		(start 122.66676 9.623806)
		(end 122.869452 8.47344)
		(width 0.127)
		(layer "F.Cu")
		(net "P3E_CPU0_PE2_SS_C_TXN<13>")
	)
	(via
		(at 123.212606 7.742682)
		(size 0.508)
		(drill 0.254)
		(layers "F.Cu" "B.Cu")
		(net "P3E_CPU0_PE2_SS_C_TXN<13>")
	)
	(arc
		(start 122.869452 8.04164)
		(mid 122.957015 7.830245)
		(end 123.16841 7.742682)
		(width 0.127)
		(layer "F.Cu")
		(net "P3E_CPU0_PE2_SS_C_TXN<13>")
	)
	(arc
		(start 122.575066 11.073384)
		(mid 122.542913 10.911738)
		(end 122.451368 10.77468)
		(width 0.127)
		(layer "F.Cu")
		(net "P3E_CPU0_PE2_SS_C_TXN<13>")
	)
	(arc
		(start 122.451368 10.77468)
		(mid 122.359641 10.6374)
		(end 122.327416 10.475468)
		(width 0.127)
		(layer "F.Cu")
		(net "P3E_CPU0_PE2_SS_C_TXN<13>")
	)
	(segment
		(start 118.871492 -2.504186)
		(end 121.693178 1.52527)
		(width 0.127)
		(layer "In2.Cu")
		(net "P3E_CPU0_PE2_SS_C_TXN<13>")
	)
	(segment
		(start 103.28275 -27.79522)
		(end 103.279956 -27.668474)
		(width 0.127)
		(layer "In2.Cu")
		(net "P3E_CPU0_PE2_SS_C_TXN<13>")
	)
	(segment
		(start 122.868436 5.602986)
		(end 122.868436 5.60324)
		(width 0.127)
		(layer "In2.Cu")
		(net "P3E_CPU0_PE2_SS_C_TXN<13>")
	)
	(segment
		(start 112.19942 -11.87958)
		(end 112.19942 -9.385046)
		(width 0.127)
		(layer "In2.Cu")
		(net "P3E_CPU0_PE2_SS_C_TXN<13>")
	)
	(segment
		(start 122.867166 6.596126)
		(end 122.867166 7.282688)
		(width 0.127)
		(layer "In2.Cu")
		(net "P3E_CPU0_PE2_SS_C_TXN<13>")
	)
	(segment
		(start 102.759002 -28.644088)
		(end 102.87254 -28.587192)
		(width 0.127)
		(layer "In2.Cu")
		(net "P3E_CPU0_PE2_SS_C_TXN<13>")
	)
	(segment
		(start 103.378 -26.67)
		(end 103.6701 -25.8826)
		(width 0.127)
		(layer "In2.Cu")
		(net "P3E_CPU0_PE2_SS_C_TXN<13>")
	)
	(segment
		(start 102.758748 -28.644088)
		(end 102.759002 -28.644088)
		(width 0.127)
		(layer "In2.Cu")
		(net "P3E_CPU0_PE2_SS_C_TXN<13>")
	)
	(segment
		(start 122.41784 2.560066)
		(end 122.848624 4.864354)
		(width 0.127)
		(layer "In2.Cu")
		(net "P3E_CPU0_PE2_SS_C_TXN<13>")
	)
	(segment
		(start 103.28275 -27.79649)
		(end 103.28275 -27.79522)
		(width 0.127)
		(layer "In2.Cu")
		(net "P3E_CPU0_PE2_SS_C_TXN<13>")
	)
	(segment
		(start 103.279956 -27.668474)
		(end 103.279956 -27.66822)
		(width 0.127)
		(layer "In2.Cu")
		(net "P3E_CPU0_PE2_SS_C_TXN<13>")
	)
	(segment
		(start 111.154972 -14.65326)
		(end 111.15548 -14.651736)
		(width 0.127)
		(layer "In2.Cu")
		(net "P3E_CPU0_PE2_SS_C_TXN<13>")
	)
	(segment
		(start 111.157512 -14.650466)
		(end 111.207296 -14.08684)
		(width 0.127)
		(layer "In2.Cu")
		(net "P3E_CPU0_PE2_SS_C_TXN<13>")
	)
	(segment
		(start 111.157004 -14.65199)
		(end 111.157512 -14.650466)
		(width 0.127)
		(layer "In2.Cu")
		(net "P3E_CPU0_PE2_SS_C_TXN<13>")
	)
	(segment
		(start 111.15548 -14.651736)
		(end 111.157004 -14.65199)
		(width 0.127)
		(layer "In2.Cu")
		(net "P3E_CPU0_PE2_SS_C_TXN<13>")
	)
	(segment
		(start 111.218726 -13.958824)
		(end 111.219234 -13.958316)
		(width 0.127)
		(layer "In2.Cu")
		(net "P3E_CPU0_PE2_SS_C_TXN<13>")
	)
	(segment
		(start 103.279956 -27.66822)
		(end 103.378 -26.67)
		(width 0.127)
		(layer "In2.Cu")
		(net "P3E_CPU0_PE2_SS_C_TXN<13>")
	)
	(segment
		(start 103.080312 -29.570426)
		(end 102.702106 -28.814522)
		(width 0.127)
		(layer "In2.Cu")
		(net "P3E_CPU0_PE2_SS_C_TXN<13>")
	)
	(segment
		(start 111.218726 -13.959586)
		(end 111.218726 -13.958824)
		(width 0.127)
		(layer "In2.Cu")
		(net "P3E_CPU0_PE2_SS_C_TXN<13>")
	)
	(segment
		(start 111.219234 -13.958316)
		(end 111.219234 -13.932408)
		(width 0.127)
		(layer "In2.Cu")
		(net "P3E_CPU0_PE2_SS_C_TXN<13>")
	)
	(segment
		(start 111.209582 -14.061694)
		(end 111.218726 -13.959586)
		(width 0.127)
		(layer "In2.Cu")
		(net "P3E_CPU0_PE2_SS_C_TXN<13>")
	)
	(segment
		(start 112.5728 -8.4836)
		(end 112.647984 -8.408416)
		(width 0.127)
		(layer "In2.Cu")
		(net "P3E_CPU0_PE2_SS_C_TXN<13>")
	)
	(segment
		(start 103.28402 -27.79776)
		(end 103.28275 -27.79649)
		(width 0.127)
		(layer "In2.Cu")
		(net "P3E_CPU0_PE2_SS_C_TXN<13>")
	)
	(segment
		(start 111.207296 -14.08684)
		(end 111.209582 -14.061694)
		(width 0.127)
		(layer "In2.Cu")
		(net "P3E_CPU0_PE2_SS_C_TXN<13>")
	)
	(segment
		(start 113.2586 -6.9342)
		(end 113.2586 -6.83006)
		(width 0.127)
		(layer "In2.Cu")
		(net "P3E_CPU0_PE2_SS_C_TXN<13>")
	)
	(segment
		(start 103.6701 -25.8826)
		(end 111.060484 -15.0622)
		(width 0.127)
		(layer "In2.Cu")
		(net "P3E_CPU0_PE2_SS_C_TXN<13>")
	)
	(segment
		(start 111.060484 -15.0622)
		(end 111.154972 -14.65326)
		(width 0.127)
		(layer "In2.Cu")
		(net "P3E_CPU0_PE2_SS_C_TXN<13>")
	)
	(segment
		(start 113.488216 -6.275832)
		(end 118.871492 -2.504186)
		(width 0.127)
		(layer "In2.Cu")
		(net "P3E_CPU0_PE2_SS_C_TXN<13>")
	)
	(segment
		(start 111.66856 -12.84732)
		(end 111.890556 -12.625324)
		(width 0.127)
		(layer "In2.Cu")
		(net "P3E_CPU0_PE2_SS_C_TXN<13>")
	)
	(segment
		(start 121.693178 1.52527)
		(end 122.41784 2.560066)
		(width 0.127)
		(layer "In2.Cu")
		(net "P3E_CPU0_PE2_SS_C_TXN<13>")
	)
	(arc
		(start 102.702106 -28.814522)
		(mid 102.695129 -28.717574)
		(end 102.758748 -28.644088)
		(width 0.127)
		(layer "In2.Cu")
		(net "P3E_CPU0_PE2_SS_C_TXN<13>")
	)
	(arc
		(start 102.87254 -28.587192)
		(mid 103.206136 -28.2591)
		(end 103.28402 -27.79776)
		(width 0.127)
		(layer "In2.Cu")
		(net "P3E_CPU0_PE2_SS_C_TXN<13>")
	)
	(arc
		(start 111.219234 -13.932408)
		(mid 111.336004 -13.345185)
		(end 111.66856 -12.84732)
		(width 0.127)
		(layer "In2.Cu")
		(net "P3E_CPU0_PE2_SS_C_TXN<13>")
	)
	(arc
		(start 112.19942 -9.385046)
		(mid 112.29646 -8.897191)
		(end 112.5728 -8.4836)
		(width 0.127)
		(layer "In2.Cu")
		(net "P3E_CPU0_PE2_SS_C_TXN<13>")
	)
	(arc
		(start 122.868436 6.251194)
		(mid 122.870151 6.267919)
		(end 122.870722 6.284722)
		(width 0.127)
		(layer "In2.Cu")
		(net "P3E_CPU0_PE2_SS_C_TXN<13>")
	)
	(arc
		(start 122.848624 4.864354)
		(mid 122.870518 5.004283)
		(end 122.88393 5.145278)
		(width 0.127)
		(layer "In2.Cu")
		(net "P3E_CPU0_PE2_SS_C_TXN<13>")
	)
	(arc
		(start 113.2586 -6.83006)
		(mid 113.318267 -6.530096)
		(end 113.488216 -6.275832)
		(width 0.127)
		(layer "In2.Cu")
		(net "P3E_CPU0_PE2_SS_C_TXN<13>")
	)
	(arc
		(start 111.890556 -12.625324)
		(mid 112.119173 -12.283174)
		(end 112.19942 -11.87958)
		(width 0.127)
		(layer "In2.Cu")
		(net "P3E_CPU0_PE2_SS_C_TXN<13>")
	)
	(arc
		(start 122.88393 5.145278)
		(mid 122.887382 5.374511)
		(end 122.868436 5.602986)
		(width 0.127)
		(layer "In2.Cu")
		(net "P3E_CPU0_PE2_SS_C_TXN<13>")
	)
	(arc
		(start 122.868436 5.60324)
		(mid 122.847214 5.927218)
		(end 122.868436 6.251194)
		(width 0.127)
		(layer "In2.Cu")
		(net "P3E_CPU0_PE2_SS_C_TXN<13>")
	)
	(arc
		(start 122.870722 6.284722)
		(mid 122.871032 6.440448)
		(end 122.867166 6.596126)
		(width 0.127)
		(layer "In2.Cu")
		(net "P3E_CPU0_PE2_SS_C_TXN<13>")
	)
	(arc
		(start 112.647984 -8.408416)
		(mid 113.099924 -7.73204)
		(end 113.2586 -6.9342)
		(width 0.127)
		(layer "In2.Cu")
		(net "P3E_CPU0_PE2_SS_C_TXN<13>")
	)
	(arc
		(start 122.867166 7.282688)
		(mid 122.967084 7.567357)
		(end 123.212606 7.742682)
		(width 0.127)
		(layer "In2.Cu")
		(net "P3E_CPU0_PE2_SS_C_TXN<13>")
	)
	(segment
		(start 120.278652 8.04164)
		(end 120.278652 8.47344)
		(width 0.127)
		(layer "F.Cu")
		(net "P3E_CPU0_PE2_SS_C_TXN<12>")
	)
	(segment
		(start 120.621806 7.742682)
		(end 120.57761 7.742682)
		(width 0.127)
		(layer "F.Cu")
		(net "P3E_CPU0_PE2_SS_C_TXN<12>")
	)
	(segment
		(start 120.17502 11.073384)
		(end 120.17502 12.234672)
		(width 0.127)
		(layer "F.Cu")
		(net "P3E_CPU0_PE2_SS_C_TXN<12>")
	)
	(segment
		(start 120.279414 8.47725)
		(end 119.92737 10.475468)
		(width 0.127)
		(layer "F.Cu")
		(net "P3E_CPU0_PE2_SS_C_TXN<12>")
	)
	(segment
		(start 120.278652 8.47344)
		(end 120.279414 8.47725)
		(width 0.127)
		(layer "F.Cu")
		(net "P3E_CPU0_PE2_SS_C_TXN<12>")
	)
	(via
		(at 120.621806 7.742682)
		(size 0.508)
		(drill 0.254)
		(layers "F.Cu" "B.Cu")
		(net "P3E_CPU0_PE2_SS_C_TXN<12>")
	)
	(arc
		(start 120.57761 7.742682)
		(mid 120.366215 7.830245)
		(end 120.278652 8.04164)
		(width 0.127)
		(layer "F.Cu")
		(net "P3E_CPU0_PE2_SS_C_TXN<12>")
	)
	(arc
		(start 120.051322 10.77468)
		(mid 120.142894 10.911727)
		(end 120.17502 11.073384)
		(width 0.127)
		(layer "F.Cu")
		(net "P3E_CPU0_PE2_SS_C_TXN<12>")
	)
	(arc
		(start 119.92737 10.475468)
		(mid 119.959581 10.637406)
		(end 120.051322 10.77468)
		(width 0.127)
		(layer "F.Cu")
		(net "P3E_CPU0_PE2_SS_C_TXN<12>")
	)
	(segment
		(start 119.825008 2.627376)
		(end 120.25503 4.849368)
		(width 0.127)
		(layer "In2.Cu")
		(net "P3E_CPU0_PE2_SS_C_TXN<12>")
	)
	(segment
		(start 99.079812 -29.570426)
		(end 98.702876 -28.814522)
		(width 0.127)
		(layer "In2.Cu")
		(net "P3E_CPU0_PE2_SS_C_TXN<12>")
	)
	(segment
		(start 107.23245 -7.115556)
		(end 107.23245 -6.600698)
		(width 0.127)
		(layer "In2.Cu")
		(net "P3E_CPU0_PE2_SS_C_TXN<12>")
	)
	(segment
		(start 100.410772 -24.110696)
		(end 107.119166 -14.530324)
		(width 0.127)
		(layer "In2.Cu")
		(net "P3E_CPU0_PE2_SS_C_TXN<12>")
	)
	(segment
		(start 107.693714 -8.076184)
		(end 107.58551 -7.96798)
		(width 0.127)
		(layer "In2.Cu")
		(net "P3E_CPU0_PE2_SS_C_TXN<12>")
	)
	(segment
		(start 107.66933 -12.84732)
		(end 107.891326 -12.625324)
		(width 0.127)
		(layer "In2.Cu")
		(net "P3E_CPU0_PE2_SS_C_TXN<12>")
	)
	(segment
		(start 107.119166 -14.530324)
		(end 107.220004 -13.958062)
		(width 0.127)
		(layer "In2.Cu")
		(net "P3E_CPU0_PE2_SS_C_TXN<12>")
	)
	(segment
		(start 117.143784 -1.201928)
		(end 119.472456 2.123948)
		(width 0.127)
		(layer "In2.Cu")
		(net "P3E_CPU0_PE2_SS_C_TXN<12>")
	)
	(segment
		(start 119.472456 2.123948)
		(end 119.825008 2.627376)
		(width 0.127)
		(layer "In2.Cu")
		(net "P3E_CPU0_PE2_SS_C_TXN<12>")
	)
	(segment
		(start 100.410518 -24.111458)
		(end 100.410772 -24.110696)
		(width 0.127)
		(layer "In2.Cu")
		(net "P3E_CPU0_PE2_SS_C_TXN<12>")
	)
	(segment
		(start 99.30257 -27.08656)
		(end 100.410518 -24.111458)
		(width 0.127)
		(layer "In2.Cu")
		(net "P3E_CPU0_PE2_SS_C_TXN<12>")
	)
	(segment
		(start 107.220004 -13.958062)
		(end 107.220004 -13.932408)
		(width 0.127)
		(layer "In2.Cu")
		(net "P3E_CPU0_PE2_SS_C_TXN<12>")
	)
	(segment
		(start 107.413552 -5.573776)
		(end 108.204 -4.445)
		(width 0.127)
		(layer "In2.Cu")
		(net "P3E_CPU0_PE2_SS_C_TXN<12>")
	)
	(segment
		(start 114.405664 -3.118866)
		(end 117.143784 -1.201928)
		(width 0.127)
		(layer "In2.Cu")
		(net "P3E_CPU0_PE2_SS_C_TXN<12>")
	)
	(segment
		(start 98.759772 -28.644088)
		(end 98.87331 -28.587192)
		(width 0.127)
		(layer "In2.Cu")
		(net "P3E_CPU0_PE2_SS_C_TXN<12>")
	)
	(segment
		(start 108.64723 -4.134612)
		(end 114.405664 -3.118866)
		(width 0.127)
		(layer "In2.Cu")
		(net "P3E_CPU0_PE2_SS_C_TXN<12>")
	)
	(segment
		(start 98.759518 -28.644088)
		(end 98.759772 -28.644088)
		(width 0.127)
		(layer "In2.Cu")
		(net "P3E_CPU0_PE2_SS_C_TXN<12>")
	)
	(segment
		(start 108.20019 -11.87958)
		(end 108.20019 -9.29894)
		(width 0.127)
		(layer "In2.Cu")
		(net "P3E_CPU0_PE2_SS_C_TXN<12>")
	)
	(segment
		(start 108.204 -4.445)
		(end 108.64723 -4.134612)
		(width 0.127)
		(layer "In2.Cu")
		(net "P3E_CPU0_PE2_SS_C_TXN<12>")
	)
	(segment
		(start 107.23245 -6.600698)
		(end 107.413552 -5.573776)
		(width 0.127)
		(layer "In2.Cu")
		(net "P3E_CPU0_PE2_SS_C_TXN<12>")
	)
	(arc
		(start 107.220004 -13.932408)
		(mid 107.336774 -13.345185)
		(end 107.66933 -12.84732)
		(width 0.127)
		(layer "In2.Cu")
		(net "P3E_CPU0_PE2_SS_C_TXN<12>")
	)
	(arc
		(start 120.25503 4.849368)
		(mid 120.296864 5.225389)
		(end 120.277636 5.60324)
		(width 0.127)
		(layer "In2.Cu")
		(net "P3E_CPU0_PE2_SS_C_TXN<12>")
	)
	(arc
		(start 120.29948 7.093966)
		(mid 120.293056 7.168327)
		(end 120.285256 7.242556)
		(width 0.127)
		(layer "In2.Cu")
		(net "P3E_CPU0_PE2_SS_C_TXN<12>")
	)
	(arc
		(start 108.20019 -9.29894)
		(mid 108.06856 -8.637192)
		(end 107.693714 -8.076184)
		(width 0.127)
		(layer "In2.Cu")
		(net "P3E_CPU0_PE2_SS_C_TXN<12>")
	)
	(arc
		(start 120.277636 5.60324)
		(mid 120.256414 5.927218)
		(end 120.277636 6.251194)
		(width 0.127)
		(layer "In2.Cu")
		(net "P3E_CPU0_PE2_SS_C_TXN<12>")
	)
	(arc
		(start 107.891326 -12.625324)
		(mid 108.119943 -12.283174)
		(end 108.20019 -11.87958)
		(width 0.127)
		(layer "In2.Cu")
		(net "P3E_CPU0_PE2_SS_C_TXN<12>")
	)
	(arc
		(start 99.28479 -27.79776)
		(mid 99.263255 -27.441399)
		(end 99.30257 -27.08656)
		(width 0.127)
		(layer "In2.Cu")
		(net "P3E_CPU0_PE2_SS_C_TXN<12>")
	)
	(arc
		(start 120.285256 7.242556)
		(mid 120.361342 7.55468)
		(end 120.621806 7.742682)
		(width 0.127)
		(layer "In2.Cu")
		(net "P3E_CPU0_PE2_SS_C_TXN<12>")
	)
	(arc
		(start 107.58551 -7.96798)
		(mid 107.324188 -7.576885)
		(end 107.23245 -7.115556)
		(width 0.127)
		(layer "In2.Cu")
		(net "P3E_CPU0_PE2_SS_C_TXN<12>")
	)
	(arc
		(start 98.702876 -28.814522)
		(mid 98.695899 -28.717574)
		(end 98.759518 -28.644088)
		(width 0.127)
		(layer "In2.Cu")
		(net "P3E_CPU0_PE2_SS_C_TXN<12>")
	)
	(arc
		(start 120.277636 6.251194)
		(mid 120.31062 6.672009)
		(end 120.29948 7.093966)
		(width 0.127)
		(layer "In2.Cu")
		(net "P3E_CPU0_PE2_SS_C_TXN<12>")
	)
	(arc
		(start 98.87331 -28.587192)
		(mid 99.206906 -28.2591)
		(end 99.28479 -27.79776)
		(width 0.127)
		(layer "In2.Cu")
		(net "P3E_CPU0_PE2_SS_C_TXN<12>")
	)
	(segment
		(start 117.687852 8.666226)
		(end 117.687852 8.04164)
		(width 0.127)
		(layer "F.Cu")
		(net "P3E_CPU0_PE2_SS_C_TXN<11>")
	)
	(segment
		(start 117.774974 12.234672)
		(end 117.774974 11.073384)
		(width 0.127)
		(layer "F.Cu")
		(net "P3E_CPU0_PE2_SS_C_TXN<11>")
	)
	(segment
		(start 117.98681 7.742682)
		(end 118.031006 7.742682)
		(width 0.127)
		(layer "F.Cu")
		(net "P3E_CPU0_PE2_SS_C_TXN<11>")
	)
	(segment
		(start 117.527324 9.576562)
		(end 117.687852 8.666226)
		(width 0.127)
		(layer "F.Cu")
		(net "P3E_CPU0_PE2_SS_C_TXN<11>")
	)
	(segment
		(start 117.527324 10.475468)
		(end 117.527324 9.576562)
		(width 0.127)
		(layer "F.Cu")
		(net "P3E_CPU0_PE2_SS_C_TXN<11>")
	)
	(via
		(at 118.031006 7.742682)
		(size 0.508)
		(drill 0.254)
		(layers "F.Cu" "B.Cu")
		(net "P3E_CPU0_PE2_SS_C_TXN<11>")
	)
	(arc
		(start 117.651276 10.77468)
		(mid 117.559549 10.6374)
		(end 117.527324 10.475468)
		(width 0.127)
		(layer "F.Cu")
		(net "P3E_CPU0_PE2_SS_C_TXN<11>")
	)
	(arc
		(start 117.774974 11.073384)
		(mid 117.742821 10.911738)
		(end 117.651276 10.77468)
		(width 0.127)
		(layer "F.Cu")
		(net "P3E_CPU0_PE2_SS_C_TXN<11>")
	)
	(arc
		(start 117.687852 8.04164)
		(mid 117.775415 7.830245)
		(end 117.98681 7.742682)
		(width 0.127)
		(layer "F.Cu")
		(net "P3E_CPU0_PE2_SS_C_TXN<11>")
	)
	(segment
		(start 94.702376 -28.814522)
		(end 95.079312 -29.570426)
		(width 0.127)
		(layer "In2.Cu")
		(net "P3E_CPU0_PE2_SS_C_TXN<11>")
	)
	(segment
		(start 106.845608 -2.459482)
		(end 104.585008 -4.04241)
		(width 0.127)
		(layer "In2.Cu")
		(net "P3E_CPU0_PE2_SS_C_TXN<11>")
	)
	(segment
		(start 103.21925 -13.932662)
		(end 103.21925 -14.223746)
		(width 0.127)
		(layer "In2.Cu")
		(net "P3E_CPU0_PE2_SS_C_TXN<11>")
	)
	(segment
		(start 104.19969 -9.29894)
		(end 104.19969 -11.87958)
		(width 0.127)
		(layer "In2.Cu")
		(net "P3E_CPU0_PE2_SS_C_TXN<11>")
	)
	(segment
		(start 94.759272 -28.644088)
		(end 94.759018 -28.644088)
		(width 0.127)
		(layer "In2.Cu")
		(net "P3E_CPU0_PE2_SS_C_TXN<11>")
	)
	(segment
		(start 112.0521 -1.541272)
		(end 106.845608 -2.459482)
		(width 0.127)
		(layer "In2.Cu")
		(net "P3E_CPU0_PE2_SS_C_TXN<11>")
	)
	(segment
		(start 95.686118 -25.148794)
		(end 95.30207 -27.08656)
		(width 0.127)
		(layer "In2.Cu")
		(net "P3E_CPU0_PE2_SS_C_TXN<11>")
	)
	(segment
		(start 117.7036 4.0005)
		(end 117.58676 3.33629)
		(width 0.127)
		(layer "In2.Cu")
		(net "P3E_CPU0_PE2_SS_C_TXN<11>")
	)
	(segment
		(start 117.58676 3.33629)
		(end 116.20881 1.369314)
		(width 0.127)
		(layer "In2.Cu")
		(net "P3E_CPU0_PE2_SS_C_TXN<11>")
	)
	(segment
		(start 103.21925 -14.223746)
		(end 103.170228 -14.459712)
		(width 0.127)
		(layer "In2.Cu")
		(net "P3E_CPU0_PE2_SS_C_TXN<11>")
	)
	(segment
		(start 104.585008 -4.04241)
		(end 103.419148 -5.70738)
		(width 0.127)
		(layer "In2.Cu")
		(net "P3E_CPU0_PE2_SS_C_TXN<11>")
	)
	(segment
		(start 103.170228 -14.459712)
		(end 95.686118 -25.148794)
		(width 0.127)
		(layer "In2.Cu")
		(net "P3E_CPU0_PE2_SS_C_TXN<11>")
	)
	(segment
		(start 116.20881 1.369314)
		(end 115.5954 0.9398)
		(width 0.127)
		(layer "In2.Cu")
		(net "P3E_CPU0_PE2_SS_C_TXN<11>")
	)
	(segment
		(start 103.23195 -6.7691)
		(end 103.23195 -7.115556)
		(width 0.127)
		(layer "In2.Cu")
		(net "P3E_CPU0_PE2_SS_C_TXN<11>")
	)
	(segment
		(start 103.58501 -7.96798)
		(end 103.693214 -8.076184)
		(width 0.127)
		(layer "In2.Cu")
		(net "P3E_CPU0_PE2_SS_C_TXN<11>")
	)
	(segment
		(start 117.685566 6.589268)
		(end 117.64137 6.067044)
		(width 0.127)
		(layer "In2.Cu")
		(net "P3E_CPU0_PE2_SS_C_TXN<11>")
	)
	(segment
		(start 117.7036 5.561584)
		(end 117.7036 4.0005)
		(width 0.127)
		(layer "In2.Cu")
		(net "P3E_CPU0_PE2_SS_C_TXN<11>")
	)
	(segment
		(start 117.685566 7.282688)
		(end 117.685566 6.589268)
		(width 0.127)
		(layer "In2.Cu")
		(net "P3E_CPU0_PE2_SS_C_TXN<11>")
	)
	(segment
		(start 103.890826 -12.625324)
		(end 103.66883 -12.84732)
		(width 0.127)
		(layer "In2.Cu")
		(net "P3E_CPU0_PE2_SS_C_TXN<11>")
	)
	(segment
		(start 117.64137 6.067044)
		(end 117.7036 5.561584)
		(width 0.127)
		(layer "In2.Cu")
		(net "P3E_CPU0_PE2_SS_C_TXN<11>")
	)
	(segment
		(start 103.419148 -5.70738)
		(end 103.23195 -6.7691)
		(width 0.127)
		(layer "In2.Cu")
		(net "P3E_CPU0_PE2_SS_C_TXN<11>")
	)
	(segment
		(start 94.87281 -28.587192)
		(end 94.759272 -28.644088)
		(width 0.127)
		(layer "In2.Cu")
		(net "P3E_CPU0_PE2_SS_C_TXN<11>")
	)
	(segment
		(start 115.5954 0.9398)
		(end 112.0521 -1.541272)
		(width 0.127)
		(layer "In2.Cu")
		(net "P3E_CPU0_PE2_SS_C_TXN<11>")
	)
	(arc
		(start 118.031006 7.742682)
		(mid 117.785482 7.567358)
		(end 117.685566 7.282688)
		(width 0.127)
		(layer "In2.Cu")
		(net "P3E_CPU0_PE2_SS_C_TXN<11>")
	)
	(arc
		(start 95.30207 -27.08656)
		(mid 95.262759 -27.441399)
		(end 95.28429 -27.79776)
		(width 0.127)
		(layer "In2.Cu")
		(net "P3E_CPU0_PE2_SS_C_TXN<11>")
	)
	(arc
		(start 104.19969 -11.87958)
		(mid 104.119413 -12.283161)
		(end 103.890826 -12.625324)
		(width 0.127)
		(layer "In2.Cu")
		(net "P3E_CPU0_PE2_SS_C_TXN<11>")
	)
	(arc
		(start 103.23195 -7.115556)
		(mid 103.323712 -7.576875)
		(end 103.58501 -7.96798)
		(width 0.127)
		(layer "In2.Cu")
		(net "P3E_CPU0_PE2_SS_C_TXN<11>")
	)
	(arc
		(start 95.28429 -27.79776)
		(mid 95.206316 -28.259053)
		(end 94.87281 -28.587192)
		(width 0.127)
		(layer "In2.Cu")
		(net "P3E_CPU0_PE2_SS_C_TXN<11>")
	)
	(arc
		(start 103.66883 -12.84732)
		(mid 103.336104 -13.345279)
		(end 103.21925 -13.932662)
		(width 0.127)
		(layer "In2.Cu")
		(net "P3E_CPU0_PE2_SS_C_TXN<11>")
	)
	(arc
		(start 94.759018 -28.644088)
		(mid 94.695399 -28.717574)
		(end 94.702376 -28.814522)
		(width 0.127)
		(layer "In2.Cu")
		(net "P3E_CPU0_PE2_SS_C_TXN<11>")
	)
	(arc
		(start 103.693214 -8.076184)
		(mid 104.068066 -8.637189)
		(end 104.19969 -9.29894)
		(width 0.127)
		(layer "In2.Cu")
		(net "P3E_CPU0_PE2_SS_C_TXN<11>")
	)
	(segment
		(start 115.440206 7.742682)
		(end 115.39601 7.742682)
		(width 0.127)
		(layer "F.Cu")
		(net "P3E_CPU0_PE2_SS_C_TXN<10>")
	)
	(segment
		(start 115.097052 9.588754)
		(end 115.127278 9.760204)
		(width 0.127)
		(layer "F.Cu")
		(net "P3E_CPU0_PE2_SS_C_TXN<10>")
	)
	(segment
		(start 115.127278 9.760204)
		(end 115.127278 10.475468)
		(width 0.127)
		(layer "F.Cu")
		(net "P3E_CPU0_PE2_SS_C_TXN<10>")
	)
	(segment
		(start 115.374928 11.073384)
		(end 115.375182 12.234672)
		(width 0.127)
		(layer "F.Cu")
		(net "P3E_CPU0_PE2_SS_C_TXN<10>")
	)
	(segment
		(start 115.097052 8.04164)
		(end 115.097052 9.588754)
		(width 0.127)
		(layer "F.Cu")
		(net "P3E_CPU0_PE2_SS_C_TXN<10>")
	)
	(via
		(at 115.440206 7.742682)
		(size 0.508)
		(drill 0.254)
		(layers "F.Cu" "B.Cu")
		(net "P3E_CPU0_PE2_SS_C_TXN<10>")
	)
	(arc
		(start 115.127278 10.475468)
		(mid 115.159489 10.637406)
		(end 115.25123 10.77468)
		(width 0.127)
		(layer "F.Cu")
		(net "P3E_CPU0_PE2_SS_C_TXN<10>")
	)
	(arc
		(start 115.25123 10.77468)
		(mid 115.342802 10.911727)
		(end 115.374928 11.073384)
		(width 0.127)
		(layer "F.Cu")
		(net "P3E_CPU0_PE2_SS_C_TXN<10>")
	)
	(arc
		(start 115.39601 7.742682)
		(mid 115.184615 7.830245)
		(end 115.097052 8.04164)
		(width 0.127)
		(layer "F.Cu")
		(net "P3E_CPU0_PE2_SS_C_TXN<10>")
	)
	(segment
		(start 115.094766 6.588506)
		(end 115.036854 5.943346)
		(width 0.127)
		(layer "In2.Cu")
		(net "P3E_CPU0_PE2_SS_C_TXN<10>")
	)
	(segment
		(start 91.339416 -26.962862)
		(end 91.30792 -27.062938)
		(width 0.127)
		(layer "In2.Cu")
		(net "P3E_CPU0_PE2_SS_C_TXN<10>")
	)
	(segment
		(start 104.442514 -0.897128)
		(end 104.223566 -0.963676)
		(width 0.127)
		(layer "In2.Cu")
		(net "P3E_CPU0_PE2_SS_C_TXN<10>")
	)
	(segment
		(start 99.36099 -6.57225)
		(end 99.298506 -6.661404)
		(width 0.127)
		(layer "In2.Cu")
		(net "P3E_CPU0_PE2_SS_C_TXN<10>")
	)
	(segment
		(start 99.220274 -13.932408)
		(end 99.22002 -13.932154)
		(width 0.127)
		(layer "In2.Cu")
		(net "P3E_CPU0_PE2_SS_C_TXN<10>")
	)
	(segment
		(start 99.269804 -6.702298)
		(end 99.23272 -6.912356)
		(width 0.127)
		(layer "In2.Cu")
		(net "P3E_CPU0_PE2_SS_C_TXN<10>")
	)
	(segment
		(start 99.03333 -14.938248)
		(end 92.9386 -23.2791)
		(width 0.127)
		(layer "In2.Cu")
		(net "P3E_CPU0_PE2_SS_C_TXN<10>")
	)
	(segment
		(start 112.870234 1.466088)
		(end 111.196374 0.293878)
		(width 0.127)
		(layer "In2.Cu")
		(net "P3E_CPU0_PE2_SS_C_TXN<10>")
	)
	(segment
		(start 115.094766 7.282688)
		(end 115.094766 6.588506)
		(width 0.127)
		(layer "In2.Cu")
		(net "P3E_CPU0_PE2_SS_C_TXN<10>")
	)
	(segment
		(start 99.455224 -6.437884)
		(end 99.44862 -6.44652)
		(width 0.127)
		(layer "In2.Cu")
		(net "P3E_CPU0_PE2_SS_C_TXN<10>")
	)
	(segment
		(start 99.298506 -6.661404)
		(end 99.269804 -6.702298)
		(width 0.127)
		(layer "In2.Cu")
		(net "P3E_CPU0_PE2_SS_C_TXN<10>")
	)
	(segment
		(start 90.87231 -28.587192)
		(end 90.758772 -28.644088)
		(width 0.127)
		(layer "In2.Cu")
		(net "P3E_CPU0_PE2_SS_C_TXN<10>")
	)
	(segment
		(start 102.63886 -2.548128)
		(end 99.455224 -6.437884)
		(width 0.127)
		(layer "In2.Cu")
		(net "P3E_CPU0_PE2_SS_C_TXN<10>")
	)
	(segment
		(start 90.701876 -28.814522)
		(end 91.080082 -29.570426)
		(width 0.127)
		(layer "In2.Cu")
		(net "P3E_CPU0_PE2_SS_C_TXN<10>")
	)
	(segment
		(start 91.30792 -27.062938)
		(end 91.301316 -27.08402)
		(width 0.127)
		(layer "In2.Cu")
		(net "P3E_CPU0_PE2_SS_C_TXN<10>")
	)
	(segment
		(start 99.23272 -6.912356)
		(end 99.23272 -7.115556)
		(width 0.127)
		(layer "In2.Cu")
		(net "P3E_CPU0_PE2_SS_C_TXN<10>")
	)
	(segment
		(start 91.300808 -27.085036)
		(end 91.302078 -27.085544)
		(width 0.127)
		(layer "In2.Cu")
		(net "P3E_CPU0_PE2_SS_C_TXN<10>")
	)
	(segment
		(start 99.891596 -12.625324)
		(end 99.6696 -12.84732)
		(width 0.127)
		(layer "In2.Cu")
		(net "P3E_CPU0_PE2_SS_C_TXN<10>")
	)
	(segment
		(start 114.863118 3.101086)
		(end 114.53368 2.630932)
		(width 0.127)
		(layer "In2.Cu")
		(net "P3E_CPU0_PE2_SS_C_TXN<10>")
	)
	(segment
		(start 99.58578 -7.96798)
		(end 99.693984 -8.076184)
		(width 0.127)
		(layer "In2.Cu")
		(net "P3E_CPU0_PE2_SS_C_TXN<10>")
	)
	(segment
		(start 115.036854 5.943346)
		(end 115.039394 5.921248)
		(width 0.127)
		(layer "In2.Cu")
		(net "P3E_CPU0_PE2_SS_C_TXN<10>")
	)
	(segment
		(start 115.039394 5.921248)
		(end 115.1128 5.564124)
		(width 0.127)
		(layer "In2.Cu")
		(net "P3E_CPU0_PE2_SS_C_TXN<10>")
	)
	(segment
		(start 90.758772 -28.644088)
		(end 90.758518 -28.644088)
		(width 0.127)
		(layer "In2.Cu")
		(net "P3E_CPU0_PE2_SS_C_TXN<10>")
	)
	(segment
		(start 115.1128 5.564124)
		(end 115.1128 4.544568)
		(width 0.127)
		(layer "In2.Cu")
		(net "P3E_CPU0_PE2_SS_C_TXN<10>")
	)
	(segment
		(start 100.20046 -9.29894)
		(end 100.20046 -11.87958)
		(width 0.127)
		(layer "In2.Cu")
		(net "P3E_CPU0_PE2_SS_C_TXN<10>")
	)
	(segment
		(start 111.196374 0.293878)
		(end 104.442514 -0.897128)
		(width 0.127)
		(layer "In2.Cu")
		(net "P3E_CPU0_PE2_SS_C_TXN<10>")
	)
	(segment
		(start 99.44862 -6.44652)
		(end 99.36099 -6.57225)
		(width 0.127)
		(layer "In2.Cu")
		(net "P3E_CPU0_PE2_SS_C_TXN<10>")
	)
	(segment
		(start 104.223566 -0.963676)
		(end 102.63886 -2.548128)
		(width 0.127)
		(layer "In2.Cu")
		(net "P3E_CPU0_PE2_SS_C_TXN<10>")
	)
	(segment
		(start 99.22002 -14.497558)
		(end 99.03333 -14.938248)
		(width 0.127)
		(layer "In2.Cu")
		(net "P3E_CPU0_PE2_SS_C_TXN<10>")
	)
	(segment
		(start 91.302078 -27.085544)
		(end 91.30157 -27.08656)
		(width 0.127)
		(layer "In2.Cu")
		(net "P3E_CPU0_PE2_SS_C_TXN<10>")
	)
	(segment
		(start 115.1128 4.544568)
		(end 115.108482 4.493768)
		(width 0.127)
		(layer "In2.Cu")
		(net "P3E_CPU0_PE2_SS_C_TXN<10>")
	)
	(segment
		(start 115.108482 4.493768)
		(end 114.863118 3.101086)
		(width 0.127)
		(layer "In2.Cu")
		(net "P3E_CPU0_PE2_SS_C_TXN<10>")
	)
	(segment
		(start 91.301316 -27.08402)
		(end 91.300808 -27.085036)
		(width 0.127)
		(layer "In2.Cu")
		(net "P3E_CPU0_PE2_SS_C_TXN<10>")
	)
	(segment
		(start 114.53368 2.630932)
		(end 112.870234 1.466088)
		(width 0.127)
		(layer "In2.Cu")
		(net "P3E_CPU0_PE2_SS_C_TXN<10>")
	)
	(segment
		(start 92.9386 -23.2791)
		(end 91.339416 -26.962862)
		(width 0.127)
		(layer "In2.Cu")
		(net "P3E_CPU0_PE2_SS_C_TXN<10>")
	)
	(segment
		(start 99.22002 -13.932154)
		(end 99.22002 -14.497558)
		(width 0.127)
		(layer "In2.Cu")
		(net "P3E_CPU0_PE2_SS_C_TXN<10>")
	)
	(arc
		(start 99.693984 -8.076184)
		(mid 100.068836 -8.637189)
		(end 100.20046 -9.29894)
		(width 0.127)
		(layer "In2.Cu")
		(net "P3E_CPU0_PE2_SS_C_TXN<10>")
	)
	(arc
		(start 115.440206 7.742682)
		(mid 115.194682 7.567358)
		(end 115.094766 7.282688)
		(width 0.127)
		(layer "In2.Cu")
		(net "P3E_CPU0_PE2_SS_C_TXN<10>")
	)
	(arc
		(start 91.30157 -27.08656)
		(mid 91.262259 -27.441399)
		(end 91.28379 -27.79776)
		(width 0.127)
		(layer "In2.Cu")
		(net "P3E_CPU0_PE2_SS_C_TXN<10>")
	)
	(arc
		(start 90.758518 -28.644088)
		(mid 90.694899 -28.717574)
		(end 90.701876 -28.814522)
		(width 0.127)
		(layer "In2.Cu")
		(net "P3E_CPU0_PE2_SS_C_TXN<10>")
	)
	(arc
		(start 91.28379 -27.79776)
		(mid 91.205816 -28.259053)
		(end 90.87231 -28.587192)
		(width 0.127)
		(layer "In2.Cu")
		(net "P3E_CPU0_PE2_SS_C_TXN<10>")
	)
	(arc
		(start 99.6696 -12.84732)
		(mid 99.33706 -13.345191)
		(end 99.220274 -13.932408)
		(width 0.127)
		(layer "In2.Cu")
		(net "P3E_CPU0_PE2_SS_C_TXN<10>")
	)
	(arc
		(start 99.23272 -7.115556)
		(mid 99.324482 -7.576875)
		(end 99.58578 -7.96798)
		(width 0.127)
		(layer "In2.Cu")
		(net "P3E_CPU0_PE2_SS_C_TXN<10>")
	)
	(arc
		(start 100.20046 -11.87958)
		(mid 100.120183 -12.283161)
		(end 99.891596 -12.625324)
		(width 0.127)
		(layer "In2.Cu")
		(net "P3E_CPU0_PE2_SS_C_TXN<10>")
	)
	(segment
		(start 80.813402 8.499856)
		(end 80.645 8.3312)
		(width 0.127)
		(layer "F.Cu")
		(net "P3E_CPU0_PE2_SS_C_TXN<1>")
	)
	(segment
		(start 80.5688 8.147304)
		(end 80.5688 8.001)
		(width 0.127)
		(layer "F.Cu")
		(net "P3E_CPU0_PE2_SS_C_TXN<1>")
	)
	(segment
		(start 81.980024 12.133072)
		(end 81.980024 10.971784)
		(width 0.127)
		(layer "F.Cu")
		(net "P3E_CPU0_PE2_SS_C_TXN<1>")
	)
	(segment
		(start 80.867758 7.702042)
		(end 80.911954 7.702042)
		(width 0.127)
		(layer "F.Cu")
		(net "P3E_CPU0_PE2_SS_C_TXN<1>")
	)
	(segment
		(start 81.732374 10.373868)
		(end 81.732374 9.189974)
		(width 0.127)
		(layer "F.Cu")
		(net "P3E_CPU0_PE2_SS_C_TXN<1>")
	)
	(via
		(at 80.911954 7.702042)
		(size 0.508)
		(drill 0.254)
		(layers "F.Cu" "B.Cu")
		(net "P3E_CPU0_PE2_SS_C_TXN<1>")
	)
	(arc
		(start 81.732374 9.189974)
		(mid 81.577558 8.816216)
		(end 81.2038 8.6614)
		(width 0.127)
		(layer "F.Cu")
		(net "P3E_CPU0_PE2_SS_C_TXN<1>")
	)
	(arc
		(start 81.2038 8.6614)
		(mid 80.992527 8.619469)
		(end 80.813402 8.499856)
		(width 0.127)
		(layer "F.Cu")
		(net "P3E_CPU0_PE2_SS_C_TXN<1>")
	)
	(arc
		(start 81.980024 10.971784)
		(mid 81.947871 10.810138)
		(end 81.856326 10.67308)
		(width 0.127)
		(layer "F.Cu")
		(net "P3E_CPU0_PE2_SS_C_TXN<1>")
	)
	(arc
		(start 81.856326 10.67308)
		(mid 81.764599 10.5358)
		(end 81.732374 10.373868)
		(width 0.127)
		(layer "F.Cu")
		(net "P3E_CPU0_PE2_SS_C_TXN<1>")
	)
	(arc
		(start 80.645 8.3312)
		(mid 80.588624 8.246828)
		(end 80.5688 8.147304)
		(width 0.127)
		(layer "F.Cu")
		(net "P3E_CPU0_PE2_SS_C_TXN<1>")
	)
	(arc
		(start 80.5688 8.001)
		(mid 80.656363 7.789605)
		(end 80.867758 7.702042)
		(width 0.127)
		(layer "F.Cu")
		(net "P3E_CPU0_PE2_SS_C_TXN<1>")
	)
	(segment
		(start 61.695838 -5.921248)
		(end 62.4586 -5.2578)
		(width 0.127)
		(layer "In2.Cu")
		(net "P3E_CPU0_PE2_SS_C_TXN<1>")
	)
	(segment
		(start 53.650896 -24.65832)
		(end 53.644038 -24.428704)
		(width 0.127)
		(layer "In2.Cu")
		(net "P3E_CPU0_PE2_SS_C_TXN<1>")
	)
	(segment
		(start 61.259974 -6.585458)
		(end 61.4426 -6.2738)
		(width 0.127)
		(layer "In2.Cu")
		(net "P3E_CPU0_PE2_SS_C_TXN<1>")
	)
	(segment
		(start 52.89804 -25.219152)
		(end 53.159406 -24.942038)
		(width 0.127)
		(layer "In2.Cu")
		(net "P3E_CPU0_PE2_SS_C_TXN<1>")
	)
	(segment
		(start 53.644038 -24.428704)
		(end 53.644038 -24.406098)
		(width 0.127)
		(layer "In2.Cu")
		(net "P3E_CPU0_PE2_SS_C_TXN<1>")
	)
	(segment
		(start 52.643278 -25.726136)
		(end 52.904644 -25.449022)
		(width 0.127)
		(layer "In2.Cu")
		(net "P3E_CPU0_PE2_SS_C_TXN<1>")
	)
	(segment
		(start 54.023006 -24.02713)
		(end 58.538618 -20.865592)
		(width 0.127)
		(layer "In2.Cu")
		(net "P3E_CPU0_PE2_SS_C_TXN<1>")
	)
	(segment
		(start 66.59753 -1.65862)
		(end 71.650606 1.8796)
		(width 0.127)
		(layer "In2.Cu")
		(net "P3E_CPU0_PE2_SS_C_TXN<1>")
	)
	(segment
		(start 53.389276 -24.935434)
		(end 53.650896 -24.65832)
		(width 0.127)
		(layer "In2.Cu")
		(net "P3E_CPU0_PE2_SS_C_TXN<1>")
	)
	(segment
		(start 52.151788 -26.009854)
		(end 52.413408 -25.73274)
		(width 0.127)
		(layer "In2.Cu")
		(net "P3E_CPU0_PE2_SS_C_TXN<1>")
	)
	(segment
		(start 52.079652 -27.570176)
		(end 51.702208 -28.325826)
		(width 0.127)
		(layer "In2.Cu")
		(net "P3E_CPU0_PE2_SS_C_TXN<1>")
	)
	(segment
		(start 51.150266 -27.723338)
		(end 51.40579 -26.800556)
		(width 0.127)
		(layer "In2.Cu")
		(net "P3E_CPU0_PE2_SS_C_TXN<1>")
	)
	(segment
		(start 58.538618 -20.865592)
		(end 59.180476 -20.071842)
		(width 0.127)
		(layer "In2.Cu")
		(net "P3E_CPU0_PE2_SS_C_TXN<1>")
	)
	(segment
		(start 80.498442 6.044946)
		(end 80.566514 6.541008)
		(width 0.127)
		(layer "In2.Cu")
		(net "P3E_CPU0_PE2_SS_C_TXN<1>")
	)
	(segment
		(start 51.667156 -26.523442)
		(end 51.897026 -26.516838)
		(width 0.127)
		(layer "In2.Cu")
		(net "P3E_CPU0_PE2_SS_C_TXN<1>")
	)
	(segment
		(start 52.904644 -25.449022)
		(end 52.89804 -25.219152)
		(width 0.127)
		(layer "In2.Cu")
		(net "P3E_CPU0_PE2_SS_C_TXN<1>")
	)
	(segment
		(start 80.078326 3.918458)
		(end 80.439514 4.434078)
		(width 0.127)
		(layer "In2.Cu")
		(net "P3E_CPU0_PE2_SS_C_TXN<1>")
	)
	(segment
		(start 60.237624 -11.63066)
		(end 60.237624 -9.47293)
		(width 0.127)
		(layer "In2.Cu")
		(net "P3E_CPU0_PE2_SS_C_TXN<1>")
	)
	(segment
		(start 61.4426 -6.2738)
		(end 61.695838 -5.921248)
		(width 0.127)
		(layer "In2.Cu")
		(net "P3E_CPU0_PE2_SS_C_TXN<1>")
	)
	(segment
		(start 79.121254 3.226816)
		(end 80.006698 3.84683)
		(width 0.127)
		(layer "In2.Cu")
		(net "P3E_CPU0_PE2_SS_C_TXN<1>")
	)
	(segment
		(start 52.413408 -25.73274)
		(end 52.643278 -25.726136)
		(width 0.127)
		(layer "In2.Cu")
		(net "P3E_CPU0_PE2_SS_C_TXN<1>")
	)
	(segment
		(start 61.225684 -7.2771)
		(end 61.225684 -6.77926)
		(width 0.127)
		(layer "In2.Cu")
		(net "P3E_CPU0_PE2_SS_C_TXN<1>")
	)
	(segment
		(start 60.774326 -8.177276)
		(end 60.908438 -8.043164)
		(width 0.127)
		(layer "In2.Cu")
		(net "P3E_CPU0_PE2_SS_C_TXN<1>")
	)
	(segment
		(start 51.40579 -26.800556)
		(end 51.667156 -26.523442)
		(width 0.127)
		(layer "In2.Cu")
		(net "P3E_CPU0_PE2_SS_C_TXN<1>")
	)
	(segment
		(start 52.158646 -26.239724)
		(end 52.151788 -26.009854)
		(width 0.127)
		(layer "In2.Cu")
		(net "P3E_CPU0_PE2_SS_C_TXN<1>")
	)
	(segment
		(start 59.180476 -20.071842)
		(end 59.20359 -20.04314)
		(width 0.127)
		(layer "In2.Cu")
		(net "P3E_CPU0_PE2_SS_C_TXN<1>")
	)
	(segment
		(start 61.22416 -14.313662)
		(end 61.22416 -13.894816)
		(width 0.127)
		(layer "In2.Cu")
		(net "P3E_CPU0_PE2_SS_C_TXN<1>")
	)
	(segment
		(start 59.20359 -20.04314)
		(end 59.861958 -18.612866)
		(width 0.127)
		(layer "In2.Cu")
		(net "P3E_CPU0_PE2_SS_C_TXN<1>")
	)
	(segment
		(start 80.566514 6.541008)
		(end 80.566514 7.1628)
		(width 0.127)
		(layer "In2.Cu")
		(net "P3E_CPU0_PE2_SS_C_TXN<1>")
	)
	(segment
		(start 53.644038 -24.406098)
		(end 54.023006 -24.02713)
		(width 0.127)
		(layer "In2.Cu")
		(net "P3E_CPU0_PE2_SS_C_TXN<1>")
	)
	(segment
		(start 51.532028 -28.382722)
		(end 51.531774 -28.382722)
		(width 0.127)
		(layer "In2.Cu")
		(net "P3E_CPU0_PE2_SS_C_TXN<1>")
	)
	(segment
		(start 80.487774 4.550918)
		(end 80.58023 5.074158)
		(width 0.127)
		(layer "In2.Cu")
		(net "P3E_CPU0_PE2_SS_C_TXN<1>")
	)
	(segment
		(start 60.6298 -16.0274)
		(end 61.22416 -14.313662)
		(width 0.127)
		(layer "In2.Cu")
		(net "P3E_CPU0_PE2_SS_C_TXN<1>")
	)
	(segment
		(start 62.4586 -5.2578)
		(end 66.59753 -1.65862)
		(width 0.127)
		(layer "In2.Cu")
		(net "P3E_CPU0_PE2_SS_C_TXN<1>")
	)
	(segment
		(start 80.584548 5.522468)
		(end 80.498442 6.044946)
		(width 0.127)
		(layer "In2.Cu")
		(net "P3E_CPU0_PE2_SS_C_TXN<1>")
	)
	(segment
		(start 51.531774 -28.382722)
		(end 51.417982 -28.32608)
		(width 0.127)
		(layer "In2.Cu")
		(net "P3E_CPU0_PE2_SS_C_TXN<1>")
	)
	(segment
		(start 80.584548 5.124958)
		(end 80.584548 5.522468)
		(width 0.127)
		(layer "In2.Cu")
		(net "P3E_CPU0_PE2_SS_C_TXN<1>")
	)
	(segment
		(start 53.159406 -24.942038)
		(end 53.389276 -24.935434)
		(width 0.127)
		(layer "In2.Cu")
		(net "P3E_CPU0_PE2_SS_C_TXN<1>")
	)
	(segment
		(start 71.650606 1.8796)
		(end 79.00416 3.178302)
		(width 0.127)
		(layer "In2.Cu")
		(net "P3E_CPU0_PE2_SS_C_TXN<1>")
	)
	(segment
		(start 61.225684 -6.77926)
		(end 61.259974 -6.585458)
		(width 0.127)
		(layer "In2.Cu")
		(net "P3E_CPU0_PE2_SS_C_TXN<1>")
	)
	(segment
		(start 59.861958 -18.612866)
		(end 60.6298 -16.0274)
		(width 0.127)
		(layer "In2.Cu")
		(net "P3E_CPU0_PE2_SS_C_TXN<1>")
	)
	(segment
		(start 60.7314 -12.70508)
		(end 60.648088 -12.622022)
		(width 0.127)
		(layer "In2.Cu")
		(net "P3E_CPU0_PE2_SS_C_TXN<1>")
	)
	(segment
		(start 51.897026 -26.516838)
		(end 52.158646 -26.239724)
		(width 0.127)
		(layer "In2.Cu")
		(net "P3E_CPU0_PE2_SS_C_TXN<1>")
	)
	(arc
		(start 61.22416 -13.894816)
		(mid 61.096088 -13.250953)
		(end 60.7314 -12.70508)
		(width 0.127)
		(layer "In2.Cu")
		(net "P3E_CPU0_PE2_SS_C_TXN<1>")
	)
	(arc
		(start 60.648088 -12.622022)
		(mid 60.344256 -12.167166)
		(end 60.237624 -11.63066)
		(width 0.127)
		(layer "In2.Cu")
		(net "P3E_CPU0_PE2_SS_C_TXN<1>")
	)
	(arc
		(start 51.702208 -28.325826)
		(mid 51.628902 -28.389519)
		(end 51.532028 -28.382722)
		(width 0.127)
		(layer "In2.Cu")
		(net "P3E_CPU0_PE2_SS_C_TXN<1>")
	)
	(arc
		(start 51.417982 -28.32608)
		(mid 51.17619 -28.072674)
		(end 51.150266 -27.723338)
		(width 0.127)
		(layer "In2.Cu")
		(net "P3E_CPU0_PE2_SS_C_TXN<1>")
	)
	(arc
		(start 80.566514 7.1628)
		(mid 80.66028 7.482998)
		(end 80.911954 7.702042)
		(width 0.127)
		(layer "In2.Cu")
		(net "P3E_CPU0_PE2_SS_C_TXN<1>")
	)
	(arc
		(start 80.58023 5.074158)
		(mid 80.583499 5.099464)
		(end 80.584548 5.124958)
		(width 0.127)
		(layer "In2.Cu")
		(net "P3E_CPU0_PE2_SS_C_TXN<1>")
	)
	(arc
		(start 80.006698 3.84683)
		(mid 80.04564 3.879516)
		(end 80.078326 3.918458)
		(width 0.127)
		(layer "In2.Cu")
		(net "P3E_CPU0_PE2_SS_C_TXN<1>")
	)
	(arc
		(start 79.00416 3.178302)
		(mid 79.06537 3.19613)
		(end 79.121254 3.226816)
		(width 0.127)
		(layer "In2.Cu")
		(net "P3E_CPU0_PE2_SS_C_TXN<1>")
	)
	(arc
		(start 60.908438 -8.043164)
		(mid 61.143231 -7.691677)
		(end 61.225684 -7.2771)
		(width 0.127)
		(layer "In2.Cu")
		(net "P3E_CPU0_PE2_SS_C_TXN<1>")
	)
	(arc
		(start 60.237624 -9.47293)
		(mid 60.377104 -8.771718)
		(end 60.774326 -8.177276)
		(width 0.127)
		(layer "In2.Cu")
		(net "P3E_CPU0_PE2_SS_C_TXN<1>")
	)
	(arc
		(start 80.439514 4.434078)
		(mid 80.470051 4.489853)
		(end 80.487774 4.550918)
		(width 0.127)
		(layer "In2.Cu")
		(net "P3E_CPU0_PE2_SS_C_TXN<1>")
	)
	(segment
		(start 79.579978 12.133072)
		(end 79.579978 10.971784)
		(width 0.127)
		(layer "F.Cu")
		(net "P3E_CPU0_PE2_SS_C_TXN<0>")
	)
	(segment
		(start 77.968348 8.1534)
		(end 77.968348 8.054848)
		(width 0.127)
		(layer "F.Cu")
		(net "P3E_CPU0_PE2_SS_C_TXN<0>")
	)
	(segment
		(start 78.115922 8.42772)
		(end 78.057502 8.369046)
		(width 0.127)
		(layer "F.Cu")
		(net "P3E_CPU0_PE2_SS_C_TXN<0>")
	)
	(segment
		(start 78.467458 8.5598)
		(end 78.4352 8.5598)
		(width 0.127)
		(layer "F.Cu")
		(net "P3E_CPU0_PE2_SS_C_TXN<0>")
	)
	(segment
		(start 79.332328 10.373868)
		(end 79.332328 9.4996)
		(width 0.127)
		(layer "F.Cu")
		(net "P3E_CPU0_PE2_SS_C_TXN<0>")
	)
	(segment
		(start 79.050642 8.819896)
		(end 79.0194 8.7884)
		(width 0.127)
		(layer "F.Cu")
		(net "P3E_CPU0_PE2_SS_C_TXN<0>")
	)
	(via
		(at 78.321154 7.702042)
		(size 0.508)
		(drill 0.254)
		(layers "F.Cu" "B.Cu")
		(net "P3E_CPU0_PE2_SS_C_TXN<0>")
	)
	(arc
		(start 77.968348 8.054848)
		(mid 78.071682 7.805376)
		(end 78.321154 7.702042)
		(width 0.127)
		(layer "F.Cu")
		(net "P3E_CPU0_PE2_SS_C_TXN<0>")
	)
	(arc
		(start 79.579978 10.971784)
		(mid 79.547825 10.810138)
		(end 79.45628 10.67308)
		(width 0.127)
		(layer "F.Cu")
		(net "P3E_CPU0_PE2_SS_C_TXN<0>")
	)
	(arc
		(start 78.4352 8.5598)
		(mid 78.262419 8.525525)
		(end 78.115922 8.42772)
		(width 0.127)
		(layer "F.Cu")
		(net "P3E_CPU0_PE2_SS_C_TXN<0>")
	)
	(arc
		(start 79.332328 9.4996)
		(mid 79.259064 9.131746)
		(end 79.050642 8.819896)
		(width 0.127)
		(layer "F.Cu")
		(net "P3E_CPU0_PE2_SS_C_TXN<0>")
	)
	(arc
		(start 79.0194 8.7884)
		(mid 78.766167 8.619195)
		(end 78.467458 8.5598)
		(width 0.127)
		(layer "F.Cu")
		(net "P3E_CPU0_PE2_SS_C_TXN<0>")
	)
	(arc
		(start 78.057502 8.369046)
		(mid 77.991476 8.270092)
		(end 77.968348 8.1534)
		(width 0.127)
		(layer "F.Cu")
		(net "P3E_CPU0_PE2_SS_C_TXN<0>")
	)
	(arc
		(start 79.45628 10.67308)
		(mid 79.364553 10.5358)
		(end 79.332328 10.373868)
		(width 0.127)
		(layer "F.Cu")
		(net "P3E_CPU0_PE2_SS_C_TXN<0>")
	)
	(segment
		(start 57.22493 -14.313662)
		(end 56.9976 -17.4244)
		(width 0.127)
		(layer "In2.Cu")
		(net "P3E_CPU0_PE2_SS_C_TXN<0>")
	)
	(segment
		(start 76.889864 4.762754)
		(end 69.40677 3.443224)
		(width 0.127)
		(layer "In2.Cu")
		(net "P3E_CPU0_PE2_SS_C_TXN<0>")
	)
	(segment
		(start 58.3946 -4.8514)
		(end 57.5564 -5.6896)
		(width 0.127)
		(layer "In2.Cu")
		(net "P3E_CPU0_PE2_SS_C_TXN<0>")
	)
	(segment
		(start 57.5564 -5.6896)
		(end 57.3278 -6.1214)
		(width 0.127)
		(layer "In2.Cu")
		(net "P3E_CPU0_PE2_SS_C_TXN<0>")
	)
	(segment
		(start 56.526176 -19.557746)
		(end 54.277768 -21.131784)
		(width 0.127)
		(layer "In2.Cu")
		(net "P3E_CPU0_PE2_SS_C_TXN<0>")
	)
	(segment
		(start 56.648858 -12.622022)
		(end 56.73217 -12.70508)
		(width 0.127)
		(layer "In2.Cu")
		(net "P3E_CPU0_PE2_SS_C_TXN<0>")
	)
	(segment
		(start 57.226454 -6.586982)
		(end 57.226454 -7.2771)
		(width 0.127)
		(layer "In2.Cu")
		(net "P3E_CPU0_PE2_SS_C_TXN<0>")
	)
	(segment
		(start 50.858928 -23.525988)
		(end 47.3329 -27.2034)
		(width 0.127)
		(layer "In2.Cu")
		(net "P3E_CPU0_PE2_SS_C_TXN<0>")
	)
	(segment
		(start 77.837792 5.69976)
		(end 77.462634 5.16382)
		(width 0.127)
		(layer "In2.Cu")
		(net "P3E_CPU0_PE2_SS_C_TXN<0>")
	)
	(segment
		(start 54.277768 -21.131784)
		(end 50.858928 -23.525988)
		(width 0.127)
		(layer "In2.Cu")
		(net "P3E_CPU0_PE2_SS_C_TXN<0>")
	)
	(segment
		(start 69.40677 3.443224)
		(end 62.903608 -1.110234)
		(width 0.127)
		(layer "In2.Cu")
		(net "P3E_CPU0_PE2_SS_C_TXN<0>")
	)
	(segment
		(start 62.903608 -1.110234)
		(end 58.3946 -4.8514)
		(width 0.127)
		(layer "In2.Cu")
		(net "P3E_CPU0_PE2_SS_C_TXN<0>")
	)
	(segment
		(start 77.975714 6.482588)
		(end 77.837792 5.69976)
		(width 0.127)
		(layer "In2.Cu")
		(net "P3E_CPU0_PE2_SS_C_TXN<0>")
	)
	(segment
		(start 56.84139 -18.621248)
		(end 56.526176 -19.557746)
		(width 0.127)
		(layer "In2.Cu")
		(net "P3E_CPU0_PE2_SS_C_TXN<0>")
	)
	(segment
		(start 46.701964 -28.814268)
		(end 47.079662 -29.570426)
		(width 0.127)
		(layer "In2.Cu")
		(net "P3E_CPU0_PE2_SS_C_TXN<0>")
	)
	(segment
		(start 77.975714 7.242048)
		(end 77.975714 6.482588)
		(width 0.127)
		(layer "In2.Cu")
		(net "P3E_CPU0_PE2_SS_C_TXN<0>")
	)
	(segment
		(start 46.872398 -28.587446)
		(end 46.760384 -28.643326)
		(width 0.127)
		(layer "In2.Cu")
		(net "P3E_CPU0_PE2_SS_C_TXN<0>")
	)
	(segment
		(start 57.22493 -13.894816)
		(end 57.22493 -14.313662)
		(width 0.127)
		(layer "In2.Cu")
		(net "P3E_CPU0_PE2_SS_C_TXN<0>")
	)
	(segment
		(start 56.9976 -17.4244)
		(end 56.8452 -18.5928)
		(width 0.127)
		(layer "In2.Cu")
		(net "P3E_CPU0_PE2_SS_C_TXN<0>")
	)
	(segment
		(start 46.760384 -28.643326)
		(end 46.759114 -28.643834)
		(width 0.127)
		(layer "In2.Cu")
		(net "P3E_CPU0_PE2_SS_C_TXN<0>")
	)
	(segment
		(start 56.909208 -8.043164)
		(end 56.775096 -8.177276)
		(width 0.127)
		(layer "In2.Cu")
		(net "P3E_CPU0_PE2_SS_C_TXN<0>")
	)
	(segment
		(start 56.238394 -9.47293)
		(end 56.238394 -11.63066)
		(width 0.127)
		(layer "In2.Cu")
		(net "P3E_CPU0_PE2_SS_C_TXN<0>")
	)
	(segment
		(start 77.462634 5.16382)
		(end 76.889864 4.762754)
		(width 0.127)
		(layer "In2.Cu")
		(net "P3E_CPU0_PE2_SS_C_TXN<0>")
	)
	(segment
		(start 46.759114 -28.643834)
		(end 46.75886 -28.643834)
		(width 0.127)
		(layer "In2.Cu")
		(net "P3E_CPU0_PE2_SS_C_TXN<0>")
	)
	(segment
		(start 56.8452 -18.5928)
		(end 56.84139 -18.621248)
		(width 0.127)
		(layer "In2.Cu")
		(net "P3E_CPU0_PE2_SS_C_TXN<0>")
	)
	(segment
		(start 57.3278 -6.1214)
		(end 57.226454 -6.586982)
		(width 0.127)
		(layer "In2.Cu")
		(net "P3E_CPU0_PE2_SS_C_TXN<0>")
	)
	(arc
		(start 57.226454 -7.2771)
		(mid 57.144007 -7.691679)
		(end 56.909208 -8.043164)
		(width 0.127)
		(layer "In2.Cu")
		(net "P3E_CPU0_PE2_SS_C_TXN<0>")
	)
	(arc
		(start 56.775096 -8.177276)
		(mid 56.377896 -8.771727)
		(end 56.238394 -9.47293)
		(width 0.127)
		(layer "In2.Cu")
		(net "P3E_CPU0_PE2_SS_C_TXN<0>")
	)
	(arc
		(start 47.3329 -27.2034)
		(mid 47.27339 -27.559124)
		(end 47.26432 -27.91968)
		(width 0.127)
		(layer "In2.Cu")
		(net "P3E_CPU0_PE2_SS_C_TXN<0>")
	)
	(arc
		(start 78.321154 7.702042)
		(mid 78.07563 7.526718)
		(end 77.975714 7.242048)
		(width 0.127)
		(layer "In2.Cu")
		(net "P3E_CPU0_PE2_SS_C_TXN<0>")
	)
	(arc
		(start 56.390032 -12.265406)
		(mid 56.429361 -12.337483)
		(end 56.472836 -12.407138)
		(width 0.127)
		(layer "In2.Cu")
		(net "P3E_CPU0_PE2_SS_C_TXN<0>")
	)
	(arc
		(start 56.472836 -12.407138)
		(mid 56.555509 -12.518953)
		(end 56.648858 -12.622022)
		(width 0.127)
		(layer "In2.Cu")
		(net "P3E_CPU0_PE2_SS_C_TXN<0>")
	)
	(arc
		(start 56.238394 -11.63066)
		(mid 56.276774 -11.956976)
		(end 56.390032 -12.265406)
		(width 0.127)
		(layer "In2.Cu")
		(net "P3E_CPU0_PE2_SS_C_TXN<0>")
	)
	(arc
		(start 47.26432 -27.91968)
		(mid 47.167299 -28.311637)
		(end 46.872398 -28.587446)
		(width 0.127)
		(layer "In2.Cu")
		(net "P3E_CPU0_PE2_SS_C_TXN<0>")
	)
	(arc
		(start 46.75886 -28.643834)
		(mid 46.695097 -28.717287)
		(end 46.701964 -28.814268)
		(width 0.127)
		(layer "In2.Cu")
		(net "P3E_CPU0_PE2_SS_C_TXN<0>")
	)
	(arc
		(start 56.73217 -12.70508)
		(mid 57.096899 -13.250936)
		(end 57.22493 -13.894816)
		(width 0.127)
		(layer "In2.Cu")
		(net "P3E_CPU0_PE2_SS_C_TXN<0>")
	)
	(via
		(at 22.0218 7.1374)
		(size 0.508)
		(drill 0.254)
		(layers "F.Cu" "B.Cu")
		(net "IRQ_OOB_MGMT_RISER_ALERT_N")
	)
	(via
		(at 102.2096 4.572)
		(size 0.508)
		(drill 0.254)
		(layers "F.Cu" "B.Cu")
		(net "IRQ_OOB_MGMT_RISER_ALERT_N")
	)
	(via
		(at 21.634704 8.021828)
		(size 0.7112)
		(drill 0.3556)
		(layers "F.Cu" "B.Cu")
		(net "IRQ_OOB_MGMT_RISER_ALERT_N")
	)
	(segment
		(start 21.17979 8.476742)
		(end 21.634704 8.021828)
		(width 0.1016)
		(layer "B.Cu")
		(net "IRQ_OOB_MGMT_RISER_ALERT_N")
	)
	(segment
		(start 105.0544 3.8227)
		(end 105.4735 3.4036)
		(width 0.1016)
		(layer "B.Cu")
		(net "IRQ_OOB_MGMT_RISER_ALERT_N")
	)
	(segment
		(start 104.8385 4.0386)
		(end 105.0544 3.8227)
		(width 0.1016)
		(layer "B.Cu")
		(net "IRQ_OOB_MGMT_RISER_ALERT_N")
	)
	(segment
		(start 102.743 4.0386)
		(end 104.8385 4.0386)
		(width 0.1016)
		(layer "B.Cu")
		(net "IRQ_OOB_MGMT_RISER_ALERT_N")
	)
	(segment
		(start 111.21644 1.02616)
		(end 112.4966 1.02616)
		(width 0.1016)
		(layer "B.Cu")
		(net "IRQ_OOB_MGMT_RISER_ALERT_N")
	)
	(segment
		(start 22.0218 7.634732)
		(end 22.0218 7.1374)
		(width 0.1016)
		(layer "B.Cu")
		(net "IRQ_OOB_MGMT_RISER_ALERT_N")
	)
	(segment
		(start 105.4735 3.4036)
		(end 108.839 3.4036)
		(width 0.1016)
		(layer "B.Cu")
		(net "IRQ_OOB_MGMT_RISER_ALERT_N")
	)
	(segment
		(start 21.17979 12.514072)
		(end 21.17979 8.476742)
		(width 0.1016)
		(layer "B.Cu")
		(net "IRQ_OOB_MGMT_RISER_ALERT_N")
	)
	(segment
		(start 102.2096 4.572)
		(end 102.743 4.0386)
		(width 0.1016)
		(layer "B.Cu")
		(net "IRQ_OOB_MGMT_RISER_ALERT_N")
	)
	(segment
		(start 108.839 3.4036)
		(end 111.21644 1.02616)
		(width 0.1016)
		(layer "B.Cu")
		(net "IRQ_OOB_MGMT_RISER_ALERT_N")
	)
	(segment
		(start 21.634704 8.021828)
		(end 22.0218 7.634732)
		(width 0.1016)
		(layer "B.Cu")
		(net "IRQ_OOB_MGMT_RISER_ALERT_N")
	)
	(segment
		(start 101.5238 3.937)
		(end 102.1588 4.572)
		(width 0.127)
		(layer "In3.Cu")
		(net "IRQ_OOB_MGMT_RISER_ALERT_N")
	)
	(segment
		(start 50.319432 2.935732)
		(end 98.713798 2.935732)
		(width 0.127)
		(layer "In3.Cu")
		(net "IRQ_OOB_MGMT_RISER_ALERT_N")
	)
	(segment
		(start 30.537912 2.6289)
		(end 38.0238 2.6289)
		(width 0.127)
		(layer "In3.Cu")
		(net "IRQ_OOB_MGMT_RISER_ALERT_N")
	)
	(segment
		(start 48.1457 4.2672)
		(end 49.477422 2.935478)
		(width 0.127)
		(layer "In3.Cu")
		(net "IRQ_OOB_MGMT_RISER_ALERT_N")
	)
	(segment
		(start 24.77135 5.08)
		(end 28.086812 5.08)
		(width 0.127)
		(layer "In3.Cu")
		(net "IRQ_OOB_MGMT_RISER_ALERT_N")
	)
	(segment
		(start 98.713798 2.935732)
		(end 99.715066 3.937)
		(width 0.127)
		(layer "In3.Cu")
		(net "IRQ_OOB_MGMT_RISER_ALERT_N")
	)
	(segment
		(start 22.0218 7.1374)
		(end 22.71395 7.1374)
		(width 0.127)
		(layer "In3.Cu")
		(net "IRQ_OOB_MGMT_RISER_ALERT_N")
	)
	(segment
		(start 38.0238 2.6289)
		(end 39.6621 4.2672)
		(width 0.127)
		(layer "In3.Cu")
		(net "IRQ_OOB_MGMT_RISER_ALERT_N")
	)
	(segment
		(start 39.6621 4.2672)
		(end 48.1457 4.2672)
		(width 0.127)
		(layer "In3.Cu")
		(net "IRQ_OOB_MGMT_RISER_ALERT_N")
	)
	(segment
		(start 22.71395 7.1374)
		(end 24.77135 5.08)
		(width 0.127)
		(layer "In3.Cu")
		(net "IRQ_OOB_MGMT_RISER_ALERT_N")
	)
	(segment
		(start 102.1588 4.572)
		(end 102.2096 4.572)
		(width 0.127)
		(layer "In3.Cu")
		(net "IRQ_OOB_MGMT_RISER_ALERT_N")
	)
	(segment
		(start 99.715066 3.937)
		(end 101.5238 3.937)
		(width 0.127)
		(layer "In3.Cu")
		(net "IRQ_OOB_MGMT_RISER_ALERT_N")
	)
	(segment
		(start 49.477422 2.935478)
		(end 50.319178 2.935478)
		(width 0.127)
		(layer "In3.Cu")
		(net "IRQ_OOB_MGMT_RISER_ALERT_N")
	)
	(segment
		(start 50.319178 2.935478)
		(end 50.319432 2.935732)
		(width 0.127)
		(layer "In3.Cu")
		(net "IRQ_OOB_MGMT_RISER_ALERT_N")
	)
	(segment
		(start 28.086812 5.08)
		(end 30.537912 2.6289)
		(width 0.127)
		(layer "In3.Cu")
		(net "IRQ_OOB_MGMT_RISER_ALERT_N")
	)
	(segment
		(start 128.9304 -13.72616)
		(end 128.8288 -13.62456)
		(width 0.1016)
		(layer "F.Cu")
		(net "FM_SLT_CFG1")
	)
	(segment
		(start 125.8824 -5.3086)
		(end 124.587 -4.0132)
		(width 0.1016)
		(layer "F.Cu")
		(net "FM_SLT_CFG1")
	)
	(segment
		(start 124.587 -3.24104)
		(end 124.52096 -3.175)
		(width 0.1016)
		(layer "F.Cu")
		(net "FM_SLT_CFG1")
	)
	(segment
		(start 125.8824 -5.4864)
		(end 125.8824 -5.3086)
		(width 0.1016)
		(layer "F.Cu")
		(net "FM_SLT_CFG1")
	)
	(segment
		(start 128.9558 -13.72616)
		(end 128.9304 -13.72616)
		(width 0.1016)
		(layer "F.Cu")
		(net "FM_SLT_CFG1")
	)
	(segment
		(start 22.0218 5.8547)
		(end 22.6187 6.4516)
		(width 0.1016)
		(layer "F.Cu")
		(net "FM_SLT_CFG1")
	)
	(segment
		(start 21.9964 5.8547)
		(end 22.0218 5.8547)
		(width 0.1016)
		(layer "F.Cu")
		(net "FM_SLT_CFG1")
	)
	(segment
		(start 21.9964 5.8547)
		(end 21.9964 5.0165)
		(width 0.1016)
		(layer "F.Cu")
		(net "FM_SLT_CFG1")
	)
	(segment
		(start 21.9964 5.0165)
		(end 22.1869 4.826)
		(width 0.1016)
		(layer "F.Cu")
		(net "FM_SLT_CFG1")
	)
	(segment
		(start 128.8288 -13.62456)
		(end 127.6858 -13.62456)
		(width 0.1016)
		(layer "F.Cu")
		(net "FM_SLT_CFG1")
	)
	(segment
		(start 124.587 -4.0132)
		(end 124.587 -3.24104)
		(width 0.1016)
		(layer "F.Cu")
		(net "FM_SLT_CFG1")
	)
	(via
		(at 22.6187 6.4516)
		(size 0.508)
		(drill 0.254)
		(layers "F.Cu" "B.Cu")
		(net "FM_SLT_CFG1")
	)
	(via
		(at 125.8824 -5.4864)
		(size 0.508)
		(drill 0.254)
		(layers "F.Cu" "B.Cu")
		(net "FM_SLT_CFG1")
	)
	(via
		(at 129.864104 -14.065758)
		(size 0.7112)
		(drill 0.3556)
		(layers "F.Cu" "B.Cu")
		(net "FM_SLT_CFG1")
	)
	(via
		(at 128.9558 -13.72616)
		(size 0.508)
		(drill 0.254)
		(layers "F.Cu" "B.Cu")
		(net "FM_SLT_CFG1")
	)
	(segment
		(start 22.4028 7.5565)
		(end 22.9235 7.0358)
		(width 0.1016)
		(layer "B.Cu")
		(net "FM_SLT_CFG1")
	)
	(segment
		(start 128.9558 -13.72616)
		(end 129.04216 -13.72616)
		(width 0.1016)
		(layer "B.Cu")
		(net "FM_SLT_CFG1")
	)
	(segment
		(start 22.4028 8.16864)
		(end 22.4028 7.5565)
		(width 0.1016)
		(layer "B.Cu")
		(net "FM_SLT_CFG1")
	)
	(segment
		(start 129.04216 -13.72616)
		(end 129.381758 -14.065758)
		(width 0.1016)
		(layer "B.Cu")
		(net "FM_SLT_CFG1")
	)
	(segment
		(start 129.381758 -14.065758)
		(end 129.864104 -14.065758)
		(width 0.1016)
		(layer "B.Cu")
		(net "FM_SLT_CFG1")
	)
	(segment
		(start 22.9235 7.0358)
		(end 22.9235 6.7564)
		(width 0.1016)
		(layer "B.Cu")
		(net "FM_SLT_CFG1")
	)
	(segment
		(start 21.97989 8.59155)
		(end 22.4028 8.16864)
		(width 0.1016)
		(layer "B.Cu")
		(net "FM_SLT_CFG1")
	)
	(segment
		(start 21.97989 12.514072)
		(end 21.97989 8.59155)
		(width 0.1016)
		(layer "B.Cu")
		(net "FM_SLT_CFG1")
	)
	(segment
		(start 22.9235 6.7564)
		(end 22.6187 6.4516)
		(width 0.1016)
		(layer "B.Cu")
		(net "FM_SLT_CFG1")
	)
	(segment
		(start 128.9558 -13.72616)
		(end 125.8824 -10.65276)
		(width 0.127)
		(layer "In2.Cu")
		(net "FM_SLT_CFG1")
	)
	(segment
		(start 125.8824 -10.65276)
		(end 125.8824 -5.4864)
		(width 0.127)
		(layer "In2.Cu")
		(net "FM_SLT_CFG1")
	)
	(segment
		(start 125.8824 -5.4864)
		(end 125.708918 -5.4864)
		(width 0.127)
		(layer "In3.Cu")
		(net "FM_SLT_CFG1")
	)
	(segment
		(start 22.674072 6.4516)
		(end 22.6187 6.4516)
		(width 0.127)
		(layer "In3.Cu")
		(net "FM_SLT_CFG1")
	)
	(segment
		(start 48.472344 -0.137922)
		(end 47.85741 -0.137922)
		(width 0.127)
		(layer "In3.Cu")
		(net "FM_SLT_CFG1")
	)
	(segment
		(start 104.8893 -0.127)
		(end 48.483266 -0.127)
		(width 0.127)
		(layer "In3.Cu")
		(net "FM_SLT_CFG1")
	)
	(segment
		(start 125.708918 -5.4864)
		(end 125.162818 -4.9403)
		(width 0.127)
		(layer "In3.Cu")
		(net "FM_SLT_CFG1")
	)
	(segment
		(start 106.059478 1.043178)
		(end 104.8893 -0.127)
		(width 0.127)
		(layer "In3.Cu")
		(net "FM_SLT_CFG1")
	)
	(segment
		(start 37.010594 -1.6637)
		(end 34.363406 -1.6637)
		(width 0.127)
		(layer "In3.Cu")
		(net "FM_SLT_CFG1")
	)
	(segment
		(start 24.634444 4.7498)
		(end 24.558244 4.826)
		(width 0.127)
		(layer "In3.Cu")
		(net "FM_SLT_CFG1")
	)
	(segment
		(start 24.558244 4.826)
		(end 24.299418 4.826)
		(width 0.127)
		(layer "In3.Cu")
		(net "FM_SLT_CFG1")
	)
	(segment
		(start 42.7863 -1.0795)
		(end 40.7162 0.9906)
		(width 0.127)
		(layer "In3.Cu")
		(net "FM_SLT_CFG1")
	)
	(segment
		(start 24.299418 4.826)
		(end 23.245572 5.8801)
		(width 0.127)
		(layer "In3.Cu")
		(net "FM_SLT_CFG1")
	)
	(segment
		(start 34.363406 -1.6637)
		(end 27.949906 4.7498)
		(width 0.127)
		(layer "In3.Cu")
		(net "FM_SLT_CFG1")
	)
	(segment
		(start 48.483266 -0.127)
		(end 48.472344 -0.137922)
		(width 0.127)
		(layer "In3.Cu")
		(net "FM_SLT_CFG1")
	)
	(segment
		(start 27.949906 4.7498)
		(end 24.634444 4.7498)
		(width 0.127)
		(layer "In3.Cu")
		(net "FM_SLT_CFG1")
	)
	(segment
		(start 46.915832 -1.0795)
		(end 42.7863 -1.0795)
		(width 0.127)
		(layer "In3.Cu")
		(net "FM_SLT_CFG1")
	)
	(segment
		(start 125.162818 -4.9403)
		(end 125.095 -4.9403)
		(width 0.127)
		(layer "In3.Cu")
		(net "FM_SLT_CFG1")
	)
	(segment
		(start 125.095 -4.9403)
		(end 119.111522 1.043178)
		(width 0.127)
		(layer "In3.Cu")
		(net "FM_SLT_CFG1")
	)
	(segment
		(start 40.7162 0.9906)
		(end 39.664894 0.9906)
		(width 0.127)
		(layer "In3.Cu")
		(net "FM_SLT_CFG1")
	)
	(segment
		(start 39.664894 0.9906)
		(end 37.010594 -1.6637)
		(width 0.127)
		(layer "In3.Cu")
		(net "FM_SLT_CFG1")
	)
	(segment
		(start 119.111522 1.043178)
		(end 106.059478 1.043178)
		(width 0.127)
		(layer "In3.Cu")
		(net "FM_SLT_CFG1")
	)
	(segment
		(start 23.245572 5.8801)
		(end 22.674072 6.4516)
		(width 0.127)
		(layer "In3.Cu")
		(net "FM_SLT_CFG1")
	)
	(segment
		(start 47.85741 -0.137922)
		(end 46.915832 -1.0795)
		(width 0.127)
		(layer "In3.Cu")
		(net "FM_SLT_CFG1")
	)
	(segment
		(start 22.86 5.4864)
		(end 22.8727 5.4737)
		(width 0.1016)
		(layer "F.Cu")
		(net "FM_SLT_CFG0")
	)
	(segment
		(start 22.032468 9.649968)
		(end 22.77999 10.39749)
		(width 0.1016)
		(layer "F.Cu")
		(net "FM_SLT_CFG0")
	)
	(segment
		(start 124.9172 -5.4102)
		(end 123.87072 -4.36372)
		(width 0.1016)
		(layer "F.Cu")
		(net "FM_SLT_CFG0")
	)
	(segment
		(start 23.0759 5.4737)
		(end 24.2443 4.3053)
		(width 0.1016)
		(layer "F.Cu")
		(net "FM_SLT_CFG0")
	)
	(segment
		(start 126.3904 -13.3604)
		(end 126.3904 -13.2334)
		(width 0.1016)
		(layer "F.Cu")
		(net "FM_SLT_CFG0")
	)
	(segment
		(start 24.257 4.1656)
		(end 24.2443 4.1783)
		(width 0.1016)
		(layer "F.Cu")
		(net "FM_SLT_CFG0")
	)
	(segment
		(start 23.0759 6.7945)
		(end 22.032468 7.837932)
		(width 0.1016)
		(layer "F.Cu")
		(net "FM_SLT_CFG0")
	)
	(segment
		(start 22.77999 10.39749)
		(end 22.77999 12.133072)
		(width 0.1016)
		(layer "F.Cu")
		(net "FM_SLT_CFG0")
	)
	(segment
		(start 22.032468 7.837932)
		(end 22.032468 9.649968)
		(width 0.1016)
		(layer "F.Cu")
		(net "FM_SLT_CFG0")
	)
	(segment
		(start 22.86 5.4864)
		(end 23.0759 5.7023)
		(width 0.1016)
		(layer "F.Cu")
		(net "FM_SLT_CFG0")
	)
	(segment
		(start 124.968 -5.4102)
		(end 124.9172 -5.4102)
		(width 0.1016)
		(layer "F.Cu")
		(net "FM_SLT_CFG0")
	)
	(segment
		(start 25.2476 4.1656)
		(end 24.257 4.1656)
		(width 0.1016)
		(layer "F.Cu")
		(net "FM_SLT_CFG0")
	)
	(segment
		(start 24.2443 4.3053)
		(end 24.2443 4.1783)
		(width 0.1016)
		(layer "F.Cu")
		(net "FM_SLT_CFG0")
	)
	(segment
		(start 22.8727 5.4737)
		(end 23.0759 5.4737)
		(width 0.1016)
		(layer "F.Cu")
		(net "FM_SLT_CFG0")
	)
	(segment
		(start 123.87072 -4.36372)
		(end 123.87072 -3.175)
		(width 0.1016)
		(layer "F.Cu")
		(net "FM_SLT_CFG0")
	)
	(segment
		(start 23.0759 5.7023)
		(end 23.0759 6.7945)
		(width 0.1016)
		(layer "F.Cu")
		(net "FM_SLT_CFG0")
	)
	(segment
		(start 126.3904 -13.2334)
		(end 126.64948 -12.97432)
		(width 0.1016)
		(layer "F.Cu")
		(net "FM_SLT_CFG0")
	)
	(segment
		(start 126.64948 -12.97432)
		(end 127.6858 -12.97432)
		(width 0.1016)
		(layer "F.Cu")
		(net "FM_SLT_CFG0")
	)
	(via
		(at 126.3904 -13.3604)
		(size 0.508)
		(drill 0.254)
		(layers "F.Cu" "B.Cu")
		(net "FM_SLT_CFG0")
	)
	(via
		(at 22.86 5.4864)
		(size 0.508)
		(drill 0.254)
		(layers "F.Cu" "B.Cu")
		(net "FM_SLT_CFG0")
	)
	(via
		(at 23.81631 5.355336)
		(size 0.7112)
		(drill 0.3556)
		(layers "F.Cu" "B.Cu")
		(net "FM_SLT_CFG0")
	)
	(via
		(at 124.968 -5.4102)
		(size 0.508)
		(drill 0.254)
		(layers "F.Cu" "B.Cu")
		(net "FM_SLT_CFG0")
	)
	(segment
		(start 22.9108 5.4356)
		(end 23.736046 5.4356)
		(width 0.1016)
		(layer "B.Cu")
		(net "FM_SLT_CFG0")
	)
	(segment
		(start 22.86 5.4864)
		(end 22.9108 5.4356)
		(width 0.1016)
		(layer "B.Cu")
		(net "FM_SLT_CFG0")
	)
	(segment
		(start 23.736046 5.4356)
		(end 23.81631 5.355336)
		(width 0.1016)
		(layer "B.Cu")
		(net "FM_SLT_CFG0")
	)
	(segment
		(start 126.3904 -12.100306)
		(end 126.3904 -13.3604)
		(width 0.127)
		(layer "In2.Cu")
		(net "FM_SLT_CFG0")
	)
	(segment
		(start 124.968 -5.4102)
		(end 124.968 -10.677906)
		(width 0.127)
		(layer "In2.Cu")
		(net "FM_SLT_CFG0")
	)
	(segment
		(start 124.968 -10.677906)
		(end 126.3904 -12.100306)
		(width 0.127)
		(layer "In2.Cu")
		(net "FM_SLT_CFG0")
	)
	(segment
		(start 123.8758 -4.6228)
		(end 123.414282 -4.6228)
		(width 0.127)
		(layer "In3.Cu")
		(net "FM_SLT_CFG0")
	)
	(segment
		(start 24.421338 4.4958)
		(end 23.8506 4.4958)
		(width 0.127)
		(layer "In3.Cu")
		(net "FM_SLT_CFG0")
	)
	(segment
		(start 23.8506 4.4958)
		(end 22.86 5.4864)
		(width 0.127)
		(layer "In3.Cu")
		(net "FM_SLT_CFG0")
	)
	(segment
		(start 37.5793 -1.5621)
		(end 37.1475 -1.9939)
		(width 0.127)
		(layer "In3.Cu")
		(net "FM_SLT_CFG0")
	)
	(segment
		(start 123.414282 -4.6228)
		(end 118.346982 0.4445)
		(width 0.127)
		(layer "In3.Cu")
		(net "FM_SLT_CFG0")
	)
	(segment
		(start 27.813 4.4196)
		(end 24.497538 4.4196)
		(width 0.127)
		(layer "In3.Cu")
		(net "FM_SLT_CFG0")
	)
	(segment
		(start 118.346982 0.4445)
		(end 105.9434 0.4445)
		(width 0.127)
		(layer "In3.Cu")
		(net "FM_SLT_CFG0")
	)
	(segment
		(start 37.1475 -1.9939)
		(end 34.2265 -1.9939)
		(width 0.127)
		(layer "In3.Cu")
		(net "FM_SLT_CFG0")
	)
	(segment
		(start 124.6632 -5.4102)
		(end 123.8758 -4.6228)
		(width 0.127)
		(layer "In3.Cu")
		(net "FM_SLT_CFG0")
	)
	(segment
		(start 124.968 -5.4102)
		(end 124.6632 -5.4102)
		(width 0.127)
		(layer "In3.Cu")
		(net "FM_SLT_CFG0")
	)
	(segment
		(start 46.900338 -1.5621)
		(end 37.5793 -1.5621)
		(width 0.127)
		(layer "In3.Cu")
		(net "FM_SLT_CFG0")
	)
	(segment
		(start 105.9434 0.4445)
		(end 105.030778 -0.468122)
		(width 0.127)
		(layer "In3.Cu")
		(net "FM_SLT_CFG0")
	)
	(segment
		(start 34.2265 -1.9939)
		(end 27.813 4.4196)
		(width 0.127)
		(layer "In3.Cu")
		(net "FM_SLT_CFG0")
	)
	(segment
		(start 24.497538 4.4196)
		(end 24.421338 4.4958)
		(width 0.127)
		(layer "In3.Cu")
		(net "FM_SLT_CFG0")
	)
	(segment
		(start 47.994316 -0.468122)
		(end 46.900338 -1.5621)
		(width 0.127)
		(layer "In3.Cu")
		(net "FM_SLT_CFG0")
	)
	(segment
		(start 105.030778 -0.468122)
		(end 47.994316 -0.468122)
		(width 0.127)
		(layer "In3.Cu")
		(net "FM_SLT_CFG0")
	)
	(segment
		(start 67.056 -13.3604)
		(end 67.056 -15.2146)
		(width 0.1016)
		(layer "F.Cu")
		(net "FM_PWRBRK_SLOT_N")
	)
	(segment
		(start 67.056 -15.2146)
		(end 65.532 -16.7386)
		(width 0.1016)
		(layer "F.Cu")
		(net "FM_PWRBRK_SLOT_N")
	)
	(segment
		(start 62.079632 -7.250176)
		(end 62.406276 -7.250176)
		(width 0.1016)
		(layer "F.Cu")
		(net "FM_PWRBRK_SLOT_N")
	)
	(segment
		(start 66.04 -12.3444)
		(end 67.056 -13.3604)
		(width 0.1016)
		(layer "F.Cu")
		(net "FM_PWRBRK_SLOT_N")
	)
	(segment
		(start 56.5404 -1.0922)
		(end 56.8198 -1.0922)
		(width 0.1016)
		(layer "F.Cu")
		(net "FM_PWRBRK_SLOT_N")
	)
	(segment
		(start 62.406276 -7.250176)
		(end 63.9064 -8.7503)
		(width 0.1016)
		(layer "F.Cu")
		(net "FM_PWRBRK_SLOT_N")
	)
	(segment
		(start 62.079632 -6.352032)
		(end 62.079632 -7.250176)
		(width 0.1016)
		(layer "F.Cu")
		(net "FM_PWRBRK_SLOT_N")
	)
	(segment
		(start 66.04 -11.4808)
		(end 66.04 -12.3444)
		(width 0.1016)
		(layer "F.Cu")
		(net "FM_PWRBRK_SLOT_N")
	)
	(segment
		(start 63.9064 -9.3472)
		(end 66.04 -11.4808)
		(width 0.1016)
		(layer "F.Cu")
		(net "FM_PWRBRK_SLOT_N")
	)
	(segment
		(start 56.8198 -1.0922)
		(end 62.079632 -6.352032)
		(width 0.1016)
		(layer "F.Cu")
		(net "FM_PWRBRK_SLOT_N")
	)
	(segment
		(start 63.9064 -8.7503)
		(end 63.9064 -9.3472)
		(width 0.1016)
		(layer "F.Cu")
		(net "FM_PWRBRK_SLOT_N")
	)
	(via
		(at 22.464268 8.99414)
		(size 0.508)
		(drill 0.254)
		(layers "F.Cu" "B.Cu")
		(net "FM_PWRBRK_SLOT_N")
	)
	(via
		(at 57.3278 -1.651)
		(size 0.7112)
		(drill 0.3556)
		(layers "F.Cu" "B.Cu")
		(net "FM_PWRBRK_SLOT_N")
	)
	(via
		(at 56.5404 -1.0922)
		(size 0.508)
		(drill 0.254)
		(layers "F.Cu" "B.Cu")
		(net "FM_PWRBRK_SLOT_N")
	)
	(via
		(at 52.2478 5.0673)
		(size 0.508)
		(drill 0.254)
		(layers "F.Cu" "B.Cu")
		(net "FM_PWRBRK_SLOT_N")
	)
	(via
		(at 65.532 -16.7386)
		(size 0.508)
		(drill 0.254)
		(layers "F.Cu" "B.Cu")
		(net "FM_PWRBRK_SLOT_N")
	)
	(segment
		(start 65.532 -16.7386)
		(end 62.079632 -20.190968)
		(width 0.1016)
		(layer "B.Cu")
		(net "FM_PWRBRK_SLOT_N")
	)
	(segment
		(start 22.77999 10.06729)
		(end 22.77999 12.514072)
		(width 0.1016)
		(layer "B.Cu")
		(net "FM_PWRBRK_SLOT_N")
	)
	(segment
		(start 22.464268 9.751568)
		(end 22.77999 10.06729)
		(width 0.1016)
		(layer "B.Cu")
		(net "FM_PWRBRK_SLOT_N")
	)
	(segment
		(start 22.464268 8.99414)
		(end 22.464268 9.751568)
		(width 0.1016)
		(layer "B.Cu")
		(net "FM_PWRBRK_SLOT_N")
	)
	(segment
		(start 57.3278 -1.651)
		(end 56.7944 -1.1176)
		(width 0.1016)
		(layer "B.Cu")
		(net "FM_PWRBRK_SLOT_N")
	)
	(segment
		(start 56.7944 -1.1176)
		(end 56.5658 -1.1176)
		(width 0.1016)
		(layer "B.Cu")
		(net "FM_PWRBRK_SLOT_N")
	)
	(segment
		(start 56.5658 -1.1176)
		(end 56.5404 -1.0922)
		(width 0.1016)
		(layer "B.Cu")
		(net "FM_PWRBRK_SLOT_N")
	)
	(segment
		(start 62.079632 -20.190968)
		(end 62.079632 -27.570176)
		(width 0.1016)
		(layer "B.Cu")
		(net "FM_PWRBRK_SLOT_N")
	)
	(segment
		(start 56.5404 -1.0922)
		(end 56.5658 -1.0668)
		(width 0.127)
		(layer "In2.Cu")
		(net "FM_PWRBRK_SLOT_N")
	)
	(segment
		(start 56.5658 -1.0668)
		(end 56.5658 0.7493)
		(width 0.127)
		(layer "In2.Cu")
		(net "FM_PWRBRK_SLOT_N")
	)
	(segment
		(start 56.5658 0.7493)
		(end 52.2478 5.0673)
		(width 0.127)
		(layer "In2.Cu")
		(net "FM_PWRBRK_SLOT_N")
	)
	(segment
		(start 30.2768 8.7884)
		(end 28.6639 10.4013)
		(width 0.127)
		(layer "In3.Cu")
		(net "FM_PWRBRK_SLOT_N")
	)
	(segment
		(start 28.6639 10.4013)
		(end 23.5331 10.4013)
		(width 0.127)
		(layer "In3.Cu")
		(net "FM_PWRBRK_SLOT_N")
	)
	(segment
		(start 52.2478 5.0673)
		(end 52.2478 5.820918)
		(width 0.127)
		(layer "In3.Cu")
		(net "FM_PWRBRK_SLOT_N")
	)
	(segment
		(start 36.075112 6.6421)
		(end 33.928812 8.7884)
		(width 0.127)
		(layer "In3.Cu")
		(net "FM_PWRBRK_SLOT_N")
	)
	(segment
		(start 22.464268 9.332468)
		(end 22.464268 8.99414)
		(width 0.127)
		(layer "In3.Cu")
		(net "FM_PWRBRK_SLOT_N")
	)
	(segment
		(start 33.928812 8.7884)
		(end 30.2768 8.7884)
		(width 0.127)
		(layer "In3.Cu")
		(net "FM_PWRBRK_SLOT_N")
	)
	(segment
		(start 23.5331 10.4013)
		(end 22.464268 9.332468)
		(width 0.127)
		(layer "In3.Cu")
		(net "FM_PWRBRK_SLOT_N")
	)
	(segment
		(start 52.2478 5.820918)
		(end 51.426618 6.6421)
		(width 0.127)
		(layer "In3.Cu")
		(net "FM_PWRBRK_SLOT_N")
	)
	(segment
		(start 51.426618 6.6421)
		(end 36.075112 6.6421)
		(width 0.127)
		(layer "In3.Cu")
		(net "FM_PWRBRK_SLOT_N")
	)
	(segment
		(start 97.979992 10.2362)
		(end 97.979992 12.133072)
		(width 0.1016)
		(layer "F.Cu")
		(net "FM_PRSNT_2_6_N")
	)
	(segment
		(start 97.478088 6.256782)
		(end 97.478088 7.638288)
		(width 0.1016)
		(layer "F.Cu")
		(net "FM_PRSNT_2_6_N")
	)
	(segment
		(start 97.478088 7.638288)
		(end 98.03003 8.19023)
		(width 0.1016)
		(layer "F.Cu")
		(net "FM_PRSNT_2_6_N")
	)
	(segment
		(start 98.9457 5.0038)
		(end 98.174048 5.775452)
		(width 0.1016)
		(layer "F.Cu")
		(net "FM_PRSNT_2_6_N")
	)
	(segment
		(start 97.959418 5.775452)
		(end 97.478088 6.256782)
		(width 0.1016)
		(layer "F.Cu")
		(net "FM_PRSNT_2_6_N")
	)
	(segment
		(start 98.9457 4.2037)
		(end 98.6282 3.8862)
		(width 0.1016)
		(layer "F.Cu")
		(net "FM_PRSNT_2_6_N")
	)
	(segment
		(start 98.03003 10.186162)
		(end 97.979992 10.2362)
		(width 0.1016)
		(layer "F.Cu")
		(net "FM_PRSNT_2_6_N")
	)
	(segment
		(start 98.03003 8.19023)
		(end 98.03003 10.186162)
		(width 0.1016)
		(layer "F.Cu")
		(net "FM_PRSNT_2_6_N")
	)
	(segment
		(start 98.174048 5.775452)
		(end 97.959418 5.775452)
		(width 0.1016)
		(layer "F.Cu")
		(net "FM_PRSNT_2_6_N")
	)
	(segment
		(start 98.9457 5.0038)
		(end 98.9457 4.2037)
		(width 0.1016)
		(layer "F.Cu")
		(net "FM_PRSNT_2_6_N")
	)
	(via
		(at 98.6282 3.8862)
		(size 0.7112)
		(drill 0.3556)
		(layers "F.Cu" "B.Cu")
		(net "FM_PRSNT_2_6_N")
	)
	(segment
		(start 41.119552 3.8608)
		(end 41.774364 3.206242)
		(width 0.1016)
		(layer "F.Cu")
		(net "FM_PE_SLOTX24_WAKE_N")
	)
	(segment
		(start 40.016938 3.8608)
		(end 41.119552 3.8608)
		(width 0.1016)
		(layer "F.Cu")
		(net "FM_PE_SLOTX24_WAKE_N")
	)
	(segment
		(start 44.283376 1.8161)
		(end 44.717716 1.38176)
		(width 0.1016)
		(layer "F.Cu")
		(net "FM_PE_SLOTX24_WAKE_N")
	)
	(segment
		(start 44.717716 1.370584)
		(end 45.6438 0.4445)
		(width 0.1016)
		(layer "F.Cu")
		(net "FM_PE_SLOTX24_WAKE_N")
	)
	(segment
		(start 36.3982 4.6736)
		(end 36.786058 5.061458)
		(width 0.1016)
		(layer "F.Cu")
		(net "FM_PE_SLOTX24_WAKE_N")
	)
	(segment
		(start 44.717716 1.38176)
		(end 44.717716 1.370584)
		(width 0.1016)
		(layer "F.Cu")
		(net "FM_PE_SLOTX24_WAKE_N")
	)
	(segment
		(start 43.164506 1.8161)
		(end 44.283376 1.8161)
		(width 0.1016)
		(layer "F.Cu")
		(net "FM_PE_SLOTX24_WAKE_N")
	)
	(segment
		(start 36.786058 5.061458)
		(end 38.599872 5.061458)
		(width 0.1016)
		(layer "F.Cu")
		(net "FM_PE_SLOTX24_WAKE_N")
	)
	(segment
		(start 39.246556 4.631182)
		(end 40.016938 3.8608)
		(width 0.1016)
		(layer "F.Cu")
		(net "FM_PE_SLOTX24_WAKE_N")
	)
	(segment
		(start 39.245794 4.63169)
		(end 39.246556 4.631182)
		(width 0.1016)
		(layer "F.Cu")
		(net "FM_PE_SLOTX24_WAKE_N")
	)
	(segment
		(start 41.774364 3.206242)
		(end 43.164506 1.8161)
		(width 0.1016)
		(layer "F.Cu")
		(net "FM_PE_SLOTX24_WAKE_N")
	)
	(segment
		(start 39.105332 4.725162)
		(end 39.245794 4.63169)
		(width 0.1016)
		(layer "F.Cu")
		(net "FM_PE_SLOTX24_WAKE_N")
	)
	(segment
		(start 38.599872 5.061458)
		(end 39.105332 4.725162)
		(width 0.1016)
		(layer "F.Cu")
		(net "FM_PE_SLOTX24_WAKE_N")
	)
	(via
		(at 36.3982 4.6736)
		(size 0.508)
		(drill 0.254)
		(layers "F.Cu" "B.Cu")
		(net "FM_PE_SLOTX24_WAKE_N")
	)
	(via
		(at 46.687994 -0.942594)
		(size 0.7112)
		(drill 0.3556)
		(layers "F.Cu" "B.Cu")
		(net "FM_PE_SLOTX24_WAKE_N")
	)
	(via
		(at 45.6438 0.4445)
		(size 0.508)
		(drill 0.254)
		(layers "F.Cu" "B.Cu")
		(net "FM_PE_SLOTX24_WAKE_N")
	)
	(segment
		(start 41.080182 -8.665718)
		(end 45.212 -4.5339)
		(width 0.1016)
		(layer "B.Cu")
		(net "FM_PE_SLOTX24_WAKE_N")
	)
	(segment
		(start 45.1231 -13.5001)
		(end 45.1231 -14.4145)
		(width 0.1016)
		(layer "B.Cu")
		(net "FM_PE_SLOTX24_WAKE_N")
	)
	(segment
		(start 41.080182 -9.250426)
		(end 41.080182 -8.665718)
		(width 0.1016)
		(layer "B.Cu")
		(net "FM_PE_SLOTX24_WAKE_N")
	)
	(segment
		(start 41.080182 -9.250426)
		(end 41.651174 -9.250426)
		(width 0.1016)
		(layer "B.Cu")
		(net "FM_PE_SLOTX24_WAKE_N")
	)
	(segment
		(start 44.5135 -11.049)
		(end 44.0563 -11.5062)
		(width 0.1016)
		(layer "B.Cu")
		(net "FM_PE_SLOTX24_WAKE_N")
	)
	(segment
		(start 45.212 -4.5339)
		(end 46.430184 -4.5339)
		(width 0.1016)
		(layer "B.Cu")
		(net "FM_PE_SLOTX24_WAKE_N")
	)
	(segment
		(start 47.3202 -1.5748)
		(end 46.687994 -0.942594)
		(width 0.1016)
		(layer "B.Cu")
		(net "FM_PE_SLOTX24_WAKE_N")
	)
	(segment
		(start 44.0563 -12.4333)
		(end 45.1231 -13.5001)
		(width 0.1016)
		(layer "B.Cu")
		(net "FM_PE_SLOTX24_WAKE_N")
	)
	(segment
		(start 25.979882 10.735818)
		(end 25.979882 12.514072)
		(width 0.1016)
		(layer "B.Cu")
		(net "FM_PE_SLOTX24_WAKE_N")
	)
	(segment
		(start 27.1145 7.642352)
		(end 27.1145 9.6012)
		(width 0.1016)
		(layer "B.Cu")
		(net "FM_PE_SLOTX24_WAKE_N")
	)
	(segment
		(start 42.1005 -8.8011)
		(end 43.3197 -8.8011)
		(width 0.1016)
		(layer "B.Cu")
		(net "FM_PE_SLOTX24_WAKE_N")
	)
	(segment
		(start 44.2722 -9.753854)
		(end 44.5135 -9.995154)
		(width 0.1016)
		(layer "B.Cu")
		(net "FM_PE_SLOTX24_WAKE_N")
	)
	(segment
		(start 41.080182 -29.306266)
		(end 41.080182 -29.570426)
		(width 0.1016)
		(layer "B.Cu")
		(net "FM_PE_SLOTX24_WAKE_N")
	)
	(segment
		(start 46.6598 -15.9512)
		(end 46.6598 -23.726648)
		(width 0.1016)
		(layer "B.Cu")
		(net "FM_PE_SLOTX24_WAKE_N")
	)
	(segment
		(start 27.1145 9.6012)
		(end 25.979882 10.735818)
		(width 0.1016)
		(layer "B.Cu")
		(net "FM_PE_SLOTX24_WAKE_N")
	)
	(segment
		(start 47.3202 -3.643884)
		(end 47.3202 -1.5748)
		(width 0.1016)
		(layer "B.Cu")
		(net "FM_PE_SLOTX24_WAKE_N")
	)
	(segment
		(start 46.430184 -4.5339)
		(end 47.3202 -3.643884)
		(width 0.1016)
		(layer "B.Cu")
		(net "FM_PE_SLOTX24_WAKE_N")
	)
	(segment
		(start 41.651174 -9.250426)
		(end 42.1005 -8.8011)
		(width 0.1016)
		(layer "B.Cu")
		(net "FM_PE_SLOTX24_WAKE_N")
	)
	(segment
		(start 46.687994 -0.942594)
		(end 45.6438 0.1016)
		(width 0.1016)
		(layer "B.Cu")
		(net "FM_PE_SLOTX24_WAKE_N")
	)
	(segment
		(start 46.6598 -23.726648)
		(end 41.080182 -29.306266)
		(width 0.1016)
		(layer "B.Cu")
		(net "FM_PE_SLOTX24_WAKE_N")
	)
	(segment
		(start 45.6438 0.1016)
		(end 45.6438 0.4445)
		(width 0.1016)
		(layer "B.Cu")
		(net "FM_PE_SLOTX24_WAKE_N")
	)
	(segment
		(start 44.5135 -9.995154)
		(end 44.5135 -11.049)
		(width 0.1016)
		(layer "B.Cu")
		(net "FM_PE_SLOTX24_WAKE_N")
	)
	(segment
		(start 28.305252 6.4516)
		(end 27.1145 7.642352)
		(width 0.1016)
		(layer "B.Cu")
		(net "FM_PE_SLOTX24_WAKE_N")
	)
	(segment
		(start 35.648392 6.010656)
		(end 34.0233 6.4516)
		(width 0.1016)
		(layer "B.Cu")
		(net "FM_PE_SLOTX24_WAKE_N")
	)
	(segment
		(start 44.03979 -9.52119)
		(end 44.2722 -9.753854)
		(width 0.1016)
		(layer "B.Cu")
		(net "FM_PE_SLOTX24_WAKE_N")
	)
	(segment
		(start 43.3197 -8.8011)
		(end 44.03979 -9.52119)
		(width 0.1016)
		(layer "B.Cu")
		(net "FM_PE_SLOTX24_WAKE_N")
	)
	(segment
		(start 45.1231 -14.4145)
		(end 46.6598 -15.9512)
		(width 0.1016)
		(layer "B.Cu")
		(net "FM_PE_SLOTX24_WAKE_N")
	)
	(segment
		(start 36.3982 4.6736)
		(end 36.3982 5.260848)
		(width 0.1016)
		(layer "B.Cu")
		(net "FM_PE_SLOTX24_WAKE_N")
	)
	(segment
		(start 44.0563 -11.5062)
		(end 44.0563 -12.4333)
		(width 0.1016)
		(layer "B.Cu")
		(net "FM_PE_SLOTX24_WAKE_N")
	)
	(segment
		(start 34.0233 6.4516)
		(end 28.305252 6.4516)
		(width 0.1016)
		(layer "B.Cu")
		(net "FM_PE_SLOTX24_WAKE_N")
	)
	(segment
		(start 36.3982 5.260848)
		(end 35.648392 6.010656)
		(width 0.1016)
		(layer "B.Cu")
		(net "FM_PE_SLOTX24_WAKE_N")
	)
	(segment
		(start 46.219364 -4.963922)
		(end 45.979334 -4.9022)
		(width 0.127)
		(layer "F.Cu")
		(net "CLK_100M_PCH_SLOTX24_S5_DP")
	)
	(segment
		(start 29.854398 8.22071)
		(end 36.338002 7.314946)
		(width 0.127)
		(layer "F.Cu")
		(net "CLK_100M_PCH_SLOTX24_S5_DP")
	)
	(segment
		(start 44.631864 -5.902198)
		(end 44.30395 -6.096)
		(width 0.127)
		(layer "F.Cu")
		(net "CLK_100M_PCH_SLOTX24_S5_DP")
	)
	(segment
		(start 45.261784 -5.530088)
		(end 45.021754 -5.468366)
		(width 0.127)
		(layer "F.Cu")
		(net "CLK_100M_PCH_SLOTX24_S5_DP")
	)
	(segment
		(start 45.021754 -5.468366)
		(end 44.693586 -5.662168)
		(width 0.127)
		(layer "F.Cu")
		(net "CLK_100M_PCH_SLOTX24_S5_DP")
	)
	(segment
		(start 48.198024 -1.450594)
		(end 48.2346 -2.2225)
		(width 0.127)
		(layer "F.Cu")
		(net "CLK_100M_PCH_SLOTX24_S5_DP")
	)
	(segment
		(start 28.379928 12.133072)
		(end 28.379928 10.9474)
		(width 0.127)
		(layer "F.Cu")
		(net "CLK_100M_PCH_SLOTX24_S5_DP")
	)
	(segment
		(start 28.466542 10.738358)
		(end 28.503626 10.701274)
		(width 0.127)
		(layer "F.Cu")
		(net "CLK_100M_PCH_SLOTX24_S5_DP")
	)
	(segment
		(start 45.65142 -5.096002)
		(end 45.589698 -5.336032)
		(width 0.127)
		(layer "F.Cu")
		(net "CLK_100M_PCH_SLOTX24_S5_DP")
	)
	(segment
		(start 43.9674 -9.1821)
		(end 43.9674 -9.198356)
		(width 0.127)
		(layer "F.Cu")
		(net "CLK_100M_PCH_SLOTX24_S5_DP")
	)
	(segment
		(start 28.772612 9.2837)
		(end 29.191966 8.684514)
		(width 0.127)
		(layer "F.Cu")
		(net "CLK_100M_PCH_SLOTX24_S5_DP")
	)
	(segment
		(start 29.191966 8.684514)
		(end 29.854398 8.22071)
		(width 0.127)
		(layer "F.Cu")
		(net "CLK_100M_PCH_SLOTX24_S5_DP")
	)
	(segment
		(start 48.2346 -2.2225)
		(end 47.9425 -3.5306)
		(width 0.127)
		(layer "F.Cu")
		(net "CLK_100M_PCH_SLOTX24_S5_DP")
	)
	(segment
		(start 45.738796 -12.499594)
		(end 45.625512 -12.55649)
		(width 0.127)
		(layer "F.Cu")
		(net "CLK_100M_PCH_SLOTX24_S5_DP")
	)
	(segment
		(start 42.080688 4.291076)
		(end 42.96791 4.0005)
		(width 0.127)
		(layer "F.Cu")
		(net "CLK_100M_PCH_SLOTX24_S5_DP")
	)
	(segment
		(start 45.589698 -5.336032)
		(end 45.261784 -5.530088)
		(width 0.127)
		(layer "F.Cu")
		(net "CLK_100M_PCH_SLOTX24_S5_DP")
	)
	(segment
		(start 28.627324 10.40257)
		(end 28.627324 10.157206)
		(width 0.127)
		(layer "F.Cu")
		(net "CLK_100M_PCH_SLOTX24_S5_DP")
	)
	(segment
		(start 47.9425 -3.5306)
		(end 47.2694 -4.3434)
		(width 0.127)
		(layer "F.Cu")
		(net "CLK_100M_PCH_SLOTX24_S5_DP")
	)
	(segment
		(start 47.2694 -4.3434)
		(end 46.219364 -4.963922)
		(width 0.127)
		(layer "F.Cu")
		(net "CLK_100M_PCH_SLOTX24_S5_DP")
	)
	(segment
		(start 44.693586 -5.662168)
		(end 44.631864 -5.902198)
		(width 0.127)
		(layer "F.Cu")
		(net "CLK_100M_PCH_SLOTX24_S5_DP")
	)
	(segment
		(start 42.9641 -7.1247)
		(end 42.9641 -7.36727)
		(width 0.127)
		(layer "F.Cu")
		(net "CLK_100M_PCH_SLOTX24_S5_DP")
	)
	(segment
		(start 45.157136 -10.660888)
		(end 45.40758 -10.732516)
		(width 0.127)
		(layer "F.Cu")
		(net "CLK_100M_PCH_SLOTX24_S5_DP")
	)
	(segment
		(start 40.198548 4.745482)
		(end 42.080688 4.291076)
		(width 0.127)
		(layer "F.Cu")
		(net "CLK_100M_PCH_SLOTX24_S5_DP")
	)
	(segment
		(start 44.323254 -10.058146)
		(end 44.731178 -10.46607)
		(width 0.127)
		(layer "F.Cu")
		(net "CLK_100M_PCH_SLOTX24_S5_DP")
	)
	(segment
		(start 42.96791 4.0005)
		(end 44.279058 3.570986)
		(width 0.127)
		(layer "F.Cu")
		(net "CLK_100M_PCH_SLOTX24_S5_DP")
	)
	(segment
		(start 36.338002 7.314946)
		(end 40.198548 4.745482)
		(width 0.127)
		(layer "F.Cu")
		(net "CLK_100M_PCH_SLOTX24_S5_DP")
	)
	(segment
		(start 43.256708 -6.476746)
		(end 43.215052 -6.518148)
		(width 0.127)
		(layer "F.Cu")
		(net "CLK_100M_PCH_SLOTX24_S5_DP")
	)
	(segment
		(start 43.294554 -8.165846)
		(end 43.724322 -8.595614)
		(width 0.127)
		(layer "F.Cu")
		(net "CLK_100M_PCH_SLOTX24_S5_DP")
	)
	(segment
		(start 45.979334 -4.9022)
		(end 45.65142 -5.096002)
		(width 0.127)
		(layer "F.Cu")
		(net "CLK_100M_PCH_SLOTX24_S5_DP")
	)
	(segment
		(start 44.279058 3.570986)
		(end 45.185584 2.948432)
		(width 0.127)
		(layer "F.Cu")
		(net "CLK_100M_PCH_SLOTX24_S5_DP")
	)
	(segment
		(start 48.053244 -0.804926)
		(end 48.198024 -1.450594)
		(width 0.127)
		(layer "F.Cu")
		(net "CLK_100M_PCH_SLOTX24_S5_DP")
	)
	(segment
		(start 45.185584 2.948432)
		(end 45.215048 2.913126)
		(width 0.127)
		(layer "F.Cu")
		(net "CLK_100M_PCH_SLOTX24_S5_DP")
	)
	(segment
		(start 45.454824 -12.499848)
		(end 45.079412 -11.749786)
		(width 0.127)
		(layer "F.Cu")
		(net "CLK_100M_PCH_SLOTX24_S5_DP")
	)
	(segment
		(start 44.30395 -6.096)
		(end 44.17695 -6.096)
		(width 0.127)
		(layer "F.Cu")
		(net "CLK_100M_PCH_SLOTX24_S5_DP")
	)
	(segment
		(start 28.63596 10.058908)
		(end 28.772612 9.2837)
		(width 0.127)
		(layer "F.Cu")
		(net "CLK_100M_PCH_SLOTX24_S5_DP")
	)
	(segment
		(start 45.90034 -11.345418)
		(end 45.949108 -12.134596)
		(width 0.127)
		(layer "F.Cu")
		(net "CLK_100M_PCH_SLOTX24_S5_DP")
	)
	(segment
		(start 45.625512 -12.55649)
		(end 45.625258 -12.55649)
		(width 0.127)
		(layer "F.Cu")
		(net "CLK_100M_PCH_SLOTX24_S5_DP")
	)
	(segment
		(start 45.215048 2.913126)
		(end 48.053244 -0.804926)
		(width 0.127)
		(layer "F.Cu")
		(net "CLK_100M_PCH_SLOTX24_S5_DP")
	)
	(arc
		(start 45.40758 -10.732516)
		(mid 45.751365 -10.960651)
		(end 45.90034 -11.345418)
		(width 0.127)
		(layer "F.Cu")
		(net "CLK_100M_PCH_SLOTX24_S5_DP")
	)
	(arc
		(start 45.949108 -12.134596)
		(mid 45.898885 -12.348758)
		(end 45.738796 -12.499594)
		(width 0.127)
		(layer "F.Cu")
		(net "CLK_100M_PCH_SLOTX24_S5_DP")
	)
	(arc
		(start 44.17695 -6.096)
		(mid 43.679012 -6.194957)
		(end 43.256708 -6.476746)
		(width 0.127)
		(layer "F.Cu")
		(net "CLK_100M_PCH_SLOTX24_S5_DP")
	)
	(arc
		(start 42.9641 -7.36727)
		(mid 43.049891 -7.799424)
		(end 43.294554 -8.165846)
		(width 0.127)
		(layer "F.Cu")
		(net "CLK_100M_PCH_SLOTX24_S5_DP")
	)
	(arc
		(start 44.731178 -10.46607)
		(mid 44.926625 -10.601806)
		(end 45.157136 -10.660888)
		(width 0.127)
		(layer "F.Cu")
		(net "CLK_100M_PCH_SLOTX24_S5_DP")
	)
	(arc
		(start 28.627324 10.157206)
		(mid 28.629496 10.107868)
		(end 28.63596 10.058908)
		(width 0.127)
		(layer "F.Cu")
		(net "CLK_100M_PCH_SLOTX24_S5_DP")
	)
	(arc
		(start 43.215052 -6.518148)
		(mid 43.029164 -6.796438)
		(end 42.9641 -7.1247)
		(width 0.127)
		(layer "F.Cu")
		(net "CLK_100M_PCH_SLOTX24_S5_DP")
	)
	(arc
		(start 28.379928 10.9474)
		(mid 28.402433 10.834257)
		(end 28.466542 10.738358)
		(width 0.127)
		(layer "F.Cu")
		(net "CLK_100M_PCH_SLOTX24_S5_DP")
	)
	(arc
		(start 43.9674 -9.198356)
		(mid 44.059784 -9.663656)
		(end 44.323254 -10.058146)
		(width 0.127)
		(layer "F.Cu")
		(net "CLK_100M_PCH_SLOTX24_S5_DP")
	)
	(arc
		(start 43.724322 -8.595614)
		(mid 43.9042 -8.864681)
		(end 43.9674 -9.1821)
		(width 0.127)
		(layer "F.Cu")
		(net "CLK_100M_PCH_SLOTX24_S5_DP")
	)
	(arc
		(start 45.625258 -12.55649)
		(mid 45.52831 -12.563467)
		(end 45.454824 -12.499848)
		(width 0.127)
		(layer "F.Cu")
		(net "CLK_100M_PCH_SLOTX24_S5_DP")
	)
	(arc
		(start 28.503626 10.701274)
		(mid 28.595198 10.564227)
		(end 28.627324 10.40257)
		(width 0.127)
		(layer "F.Cu")
		(net "CLK_100M_PCH_SLOTX24_S5_DP")
	)
	(segment
		(start 45.392848 3.176016)
		(end 45.4533 3.103372)
		(width 0.127)
		(layer "F.Cu")
		(net "CLK_100M_PCH_SLOTX24_S5_DN")
	)
	(segment
		(start 44.415456 3.847084)
		(end 44.905168 3.510788)
		(width 0.127)
		(layer "F.Cu")
		(net "CLK_100M_PCH_SLOTX24_S5_DN")
	)
	(segment
		(start 42.164 4.5847)
		(end 43.062906 4.290314)
		(width 0.127)
		(layer "F.Cu")
		(net "CLK_100M_PCH_SLOTX24_S5_DN")
	)
	(segment
		(start 48.224186 -3.668776)
		(end 47.470314 -4.578858)
		(width 0.127)
		(layer "F.Cu")
		(net "CLK_100M_PCH_SLOTX24_S5_DN")
	)
	(segment
		(start 44.905168 3.510788)
		(end 45.392848 3.176016)
		(width 0.127)
		(layer "F.Cu")
		(net "CLK_100M_PCH_SLOTX24_S5_DN")
	)
	(segment
		(start 29.179774 12.133072)
		(end 29.179774 11.10742)
		(width 0.127)
		(layer "F.Cu")
		(net "CLK_100M_PCH_SLOTX24_S5_DN")
	)
	(segment
		(start 48.489362 -1.35636)
		(end 48.5013 -1.4097)
		(width 0.127)
		(layer "F.Cu")
		(net "CLK_100M_PCH_SLOTX24_S5_DN")
	)
	(segment
		(start 45.761656 -12.829286)
		(end 45.761402 -12.829286)
		(width 0.127)
		(layer "F.Cu")
		(net "CLK_100M_PCH_SLOTX24_S5_DN")
	)
	(segment
		(start 43.2689 -7.1247)
		(end 43.2689 -7.367524)
		(width 0.127)
		(layer "F.Cu")
		(net "CLK_100M_PCH_SLOTX24_S5_DN")
	)
	(segment
		(start 45.206158 -10.357866)
		(end 45.4914 -10.4394)
		(width 0.127)
		(layer "F.Cu")
		(net "CLK_100M_PCH_SLOTX24_S5_DN")
	)
	(segment
		(start 44.2722 -9.1821)
		(end 44.2722 -9.19861)
		(width 0.127)
		(layer "F.Cu")
		(net "CLK_100M_PCH_SLOTX24_S5_DN")
	)
	(segment
		(start 48.350678 -0.737616)
		(end 48.350932 -0.738632)
		(width 0.127)
		(layer "F.Cu")
		(net "CLK_100M_PCH_SLOTX24_S5_DN")
	)
	(segment
		(start 28.941776 10.07999)
		(end 29.061156 9.40308)
		(width 0.127)
		(layer "F.Cu")
		(net "CLK_100M_PCH_SLOTX24_S5_DN")
	)
	(segment
		(start 29.410914 8.903462)
		(end 29.969206 8.512556)
		(width 0.127)
		(layer "F.Cu")
		(net "CLK_100M_PCH_SLOTX24_S5_DN")
	)
	(segment
		(start 43.5102 -7.9502)
		(end 43.939968 -8.379968)
		(width 0.127)
		(layer "F.Cu")
		(net "CLK_100M_PCH_SLOTX24_S5_DN")
	)
	(segment
		(start 45.875194 -12.77239)
		(end 45.761656 -12.829286)
		(width 0.127)
		(layer "F.Cu")
		(net "CLK_100M_PCH_SLOTX24_S5_DN")
	)
	(segment
		(start 46.204632 -11.326622)
		(end 46.2534 -12.1158)
		(width 0.127)
		(layer "F.Cu")
		(net "CLK_100M_PCH_SLOTX24_S5_DN")
	)
	(segment
		(start 44.5389 -9.8425)
		(end 44.946824 -10.250424)
		(width 0.127)
		(layer "F.Cu")
		(net "CLK_100M_PCH_SLOTX24_S5_DN")
	)
	(segment
		(start 48.350932 -0.738632)
		(end 48.489362 -1.356614)
		(width 0.127)
		(layer "F.Cu")
		(net "CLK_100M_PCH_SLOTX24_S5_DN")
	)
	(segment
		(start 43.062906 4.290314)
		(end 44.415456 3.847084)
		(width 0.127)
		(layer "F.Cu")
		(net "CLK_100M_PCH_SLOTX24_S5_DN")
	)
	(segment
		(start 48.489362 -1.356614)
		(end 48.489362 -1.35636)
		(width 0.127)
		(layer "F.Cu")
		(net "CLK_100M_PCH_SLOTX24_S5_DN")
	)
	(segment
		(start 43.4721 -6.6929)
		(end 43.430444 -6.734302)
		(width 0.127)
		(layer "F.Cu")
		(net "CLK_100M_PCH_SLOTX24_S5_DN")
	)
	(segment
		(start 28.932124 10.509758)
		(end 28.932124 10.190226)
		(width 0.127)
		(layer "F.Cu")
		(net "CLK_100M_PCH_SLOTX24_S5_DN")
	)
	(segment
		(start 40.3225 5.0292)
		(end 42.164 4.5847)
		(width 0.127)
		(layer "F.Cu")
		(net "CLK_100M_PCH_SLOTX24_S5_DN")
	)
	(segment
		(start 47.470314 -4.578858)
		(end 44.387516 -6.4008)
		(width 0.127)
		(layer "F.Cu")
		(net "CLK_100M_PCH_SLOTX24_S5_DN")
	)
	(segment
		(start 48.3362 -0.672846)
		(end 48.3362 -0.6731)
		(width 0.127)
		(layer "F.Cu")
		(net "CLK_100M_PCH_SLOTX24_S5_DN")
	)
	(segment
		(start 48.532288 -2.288794)
		(end 48.224186 -3.668776)
		(width 0.127)
		(layer "F.Cu")
		(net "CLK_100M_PCH_SLOTX24_S5_DN")
	)
	(segment
		(start 36.449 7.6073)
		(end 36.85921 7.33425)
		(width 0.127)
		(layer "F.Cu")
		(net "CLK_100M_PCH_SLOTX24_S5_DN")
	)
	(segment
		(start 48.540924 -2.24282)
		(end 48.532288 -2.288794)
		(width 0.127)
		(layer "F.Cu")
		(net "CLK_100M_PCH_SLOTX24_S5_DN")
	)
	(segment
		(start 29.061156 9.40308)
		(end 29.410914 8.903462)
		(width 0.127)
		(layer "F.Cu")
		(net "CLK_100M_PCH_SLOTX24_S5_DN")
	)
	(segment
		(start 48.5013 -1.4097)
		(end 48.540924 -2.24282)
		(width 0.127)
		(layer "F.Cu")
		(net "CLK_100M_PCH_SLOTX24_S5_DN")
	)
	(segment
		(start 45.70476 -12.99972)
		(end 46.080172 -13.750036)
		(width 0.127)
		(layer "F.Cu")
		(net "CLK_100M_PCH_SLOTX24_S5_DN")
	)
	(segment
		(start 36.85921 7.33425)
		(end 38.437312 6.28396)
		(width 0.127)
		(layer "F.Cu")
		(net "CLK_100M_PCH_SLOTX24_S5_DN")
	)
	(segment
		(start 38.437312 6.28396)
		(end 40.3225 5.0292)
		(width 0.127)
		(layer "F.Cu")
		(net "CLK_100M_PCH_SLOTX24_S5_DN")
	)
	(segment
		(start 29.969206 8.512556)
		(end 36.449 7.6073)
		(width 0.127)
		(layer "F.Cu")
		(net "CLK_100M_PCH_SLOTX24_S5_DN")
	)
	(segment
		(start 44.387516 -6.4008)
		(end 44.177204 -6.4008)
		(width 0.127)
		(layer "F.Cu")
		(net "CLK_100M_PCH_SLOTX24_S5_DN")
	)
	(segment
		(start 45.4533 3.103372)
		(end 48.3362 -0.672846)
		(width 0.127)
		(layer "F.Cu")
		(net "CLK_100M_PCH_SLOTX24_S5_DN")
	)
	(segment
		(start 48.3362 -0.6731)
		(end 48.350678 -0.737616)
		(width 0.127)
		(layer "F.Cu")
		(net "CLK_100M_PCH_SLOTX24_S5_DN")
	)
	(arc
		(start 29.056076 10.808716)
		(mid 28.964319 10.671581)
		(end 28.932124 10.509758)
		(width 0.127)
		(layer "F.Cu")
		(net "CLK_100M_PCH_SLOTX24_S5_DN")
	)
	(arc
		(start 45.4914 -10.4394)
		(mid 45.988998 -10.769671)
		(end 46.204632 -11.326622)
		(width 0.127)
		(layer "F.Cu")
		(net "CLK_100M_PCH_SLOTX24_S5_DN")
	)
	(arc
		(start 44.177204 -6.4008)
		(mid 43.795591 -6.476708)
		(end 43.4721 -6.6929)
		(width 0.127)
		(layer "F.Cu")
		(net "CLK_100M_PCH_SLOTX24_S5_DN")
	)
	(arc
		(start 28.932124 10.190226)
		(mid 28.934539 10.134897)
		(end 28.941776 10.07999)
		(width 0.127)
		(layer "F.Cu")
		(net "CLK_100M_PCH_SLOTX24_S5_DN")
	)
	(arc
		(start 43.939968 -8.379968)
		(mid 44.185872 -8.747989)
		(end 44.2722 -9.1821)
		(width 0.127)
		(layer "F.Cu")
		(net "CLK_100M_PCH_SLOTX24_S5_DN")
	)
	(arc
		(start 43.2689 -7.367524)
		(mid 43.331621 -7.682846)
		(end 43.5102 -7.9502)
		(width 0.127)
		(layer "F.Cu")
		(net "CLK_100M_PCH_SLOTX24_S5_DN")
	)
	(arc
		(start 44.946824 -10.250424)
		(mid 45.065807 -10.329926)
		(end 45.206158 -10.357866)
		(width 0.127)
		(layer "F.Cu")
		(net "CLK_100M_PCH_SLOTX24_S5_DN")
	)
	(arc
		(start 46.2534 -12.1158)
		(mid 46.163044 -12.500964)
		(end 45.875194 -12.77239)
		(width 0.127)
		(layer "F.Cu")
		(net "CLK_100M_PCH_SLOTX24_S5_DN")
	)
	(arc
		(start 43.430444 -6.734302)
		(mid 43.310845 -6.913433)
		(end 43.2689 -7.1247)
		(width 0.127)
		(layer "F.Cu")
		(net "CLK_100M_PCH_SLOTX24_S5_DN")
	)
	(arc
		(start 45.761402 -12.829286)
		(mid 45.697783 -12.902772)
		(end 45.70476 -12.99972)
		(width 0.127)
		(layer "F.Cu")
		(net "CLK_100M_PCH_SLOTX24_S5_DN")
	)
	(arc
		(start 44.2722 -9.19861)
		(mid 44.341515 -9.547078)
		(end 44.5389 -9.8425)
		(width 0.127)
		(layer "F.Cu")
		(net "CLK_100M_PCH_SLOTX24_S5_DN")
	)
	(arc
		(start 29.179774 11.10742)
		(mid 29.147621 10.945774)
		(end 29.056076 10.808716)
		(width 0.127)
		(layer "F.Cu")
		(net "CLK_100M_PCH_SLOTX24_S5_DN")
	)
	(segment
		(start 45.299122 -8.26135)
		(end 45.33646 -8.311388)
		(width 0.127)
		(layer "B.Cu")
		(net "CLK_100M_PCH_SLOTX24_S4_DP")
	)
	(segment
		(start 47.112682 -14.651482)
		(end 47.117254 -14.653006)
		(width 0.127)
		(layer "B.Cu")
		(net "CLK_100M_PCH_SLOTX24_S4_DP")
	)
	(segment
		(start 46.212252 -5.55498)
		(end 45.023024 -6.621526)
		(width 0.127)
		(layer "B.Cu")
		(net "CLK_100M_PCH_SLOTX24_S4_DP")
	)
	(segment
		(start 47.927768 -4.18084)
		(end 47.904908 -4.238498)
		(width 0.127)
		(layer "B.Cu")
		(net "CLK_100M_PCH_SLOTX24_S4_DP")
	)
	(segment
		(start 29.427424 10.32637)
		(end 29.427424 10.13587)
		(width 0.127)
		(layer "B.Cu")
		(net "CLK_100M_PCH_SLOTX24_S4_DP")
	)
	(segment
		(start 32.199326 8.4074)
		(end 32.350456 8.211058)
		(width 0.127)
		(layer "B.Cu")
		(net "CLK_100M_PCH_SLOTX24_S4_DP")
	)
	(segment
		(start 47.768764 -0.546354)
		(end 48.392334 -2.477008)
		(width 0.127)
		(layer "B.Cu")
		(net "CLK_100M_PCH_SLOTX24_S4_DP")
	)
	(segment
		(start 46.822106 -13.278358)
		(end 46.873414 -13.545058)
		(width 0.127)
		(layer "B.Cu")
		(net "CLK_100M_PCH_SLOTX24_S4_DP")
	)
	(segment
		(start 45.738796 -32.819594)
		(end 45.625512 -32.87649)
		(width 0.127)
		(layer "B.Cu")
		(net "CLK_100M_PCH_SLOTX24_S4_DP")
	)
	(segment
		(start 45.189648 -8.073898)
		(end 45.296074 -8.26008)
		(width 0.127)
		(layer "B.Cu")
		(net "CLK_100M_PCH_SLOTX24_S4_DP")
	)
	(segment
		(start 47.432722 -4.642866)
		(end 46.212252 -5.55498)
		(width 0.127)
		(layer "B.Cu")
		(net "CLK_100M_PCH_SLOTX24_S4_DP")
	)
	(segment
		(start 51.0032 -22.46376)
		(end 50.7365 -23.2156)
		(width 0.127)
		(layer "B.Cu")
		(net "CLK_100M_PCH_SLOTX24_S4_DP")
	)
	(segment
		(start 29.179774 12.514072)
		(end 29.179774 10.924032)
		(width 0.127)
		(layer "B.Cu")
		(net "CLK_100M_PCH_SLOTX24_S4_DP")
	)
	(segment
		(start 44.931584 -27.203146)
		(end 44.931584 -27.633676)
		(width 0.127)
		(layer "B.Cu")
		(net "CLK_100M_PCH_SLOTX24_S4_DP")
	)
	(segment
		(start 41.357296 4.397756)
		(end 43.392598 3.949954)
		(width 0.127)
		(layer "B.Cu")
		(net "CLK_100M_PCH_SLOTX24_S4_DP")
	)
	(segment
		(start 29.427424 10.13587)
		(end 29.670756 9.649206)
		(width 0.127)
		(layer "B.Cu")
		(net "CLK_100M_PCH_SLOTX24_S4_DP")
	)
	(segment
		(start 45.980096 -32.111188)
		(end 45.907198 -32.588454)
		(width 0.127)
		(layer "B.Cu")
		(net "CLK_100M_PCH_SLOTX24_S4_DP")
	)
	(segment
		(start 36.031932 7.792212)
		(end 39.11981 5.620766)
		(width 0.127)
		(layer "B.Cu")
		(net "CLK_100M_PCH_SLOTX24_S4_DP")
	)
	(segment
		(start 30.718506 8.600948)
		(end 31.096204 8.551672)
		(width 0.127)
		(layer "B.Cu")
		(net "CLK_100M_PCH_SLOTX24_S4_DP")
	)
	(segment
		(start 45.625512 -32.87649)
		(end 45.625258 -32.87649)
		(width 0.127)
		(layer "B.Cu")
		(net "CLK_100M_PCH_SLOTX24_S4_DP")
	)
	(segment
		(start 44.918122 -7.34695)
		(end 44.916598 -7.348474)
		(width 0.127)
		(layer "B.Cu")
		(net "CLK_100M_PCH_SLOTX24_S4_DP")
	)
	(segment
		(start 48.268382 -3.311906)
		(end 47.927768 -4.18084)
		(width 0.127)
		(layer "B.Cu")
		(net "CLK_100M_PCH_SLOTX24_S4_DP")
	)
	(segment
		(start 31.247334 8.355076)
		(end 31.625032 8.3058)
		(width 0.127)
		(layer "B.Cu")
		(net "CLK_100M_PCH_SLOTX24_S4_DP")
	)
	(segment
		(start 44.906438 -7.176262)
		(end 44.916598 -7.32663)
		(width 0.127)
		(layer "B.Cu")
		(net "CLK_100M_PCH_SLOTX24_S4_DP")
	)
	(segment
		(start 47.904654 -4.238498)
		(end 47.903638 -4.241038)
		(width 0.127)
		(layer "B.Cu")
		(net "CLK_100M_PCH_SLOTX24_S4_DP")
	)
	(segment
		(start 46.120558 -12.426696)
		(end 46.822106 -13.278358)
		(width 0.127)
		(layer "B.Cu")
		(net "CLK_100M_PCH_SLOTX24_S4_DP")
	)
	(segment
		(start 45.964348 -11.895328)
		(end 46.120558 -12.426696)
		(width 0.127)
		(layer "B.Cu")
		(net "CLK_100M_PCH_SLOTX24_S4_DP")
	)
	(segment
		(start 32.350456 8.211058)
		(end 32.728408 8.161528)
		(width 0.127)
		(layer "B.Cu")
		(net "CLK_100M_PCH_SLOTX24_S4_DP")
	)
	(segment
		(start 47.21606 -14.88694)
		(end 47.238412 -14.939772)
		(width 0.127)
		(layer "B.Cu")
		(net "CLK_100M_PCH_SLOTX24_S4_DP")
	)
	(segment
		(start 31.821628 8.456676)
		(end 32.199326 8.4074)
		(width 0.127)
		(layer "B.Cu")
		(net "CLK_100M_PCH_SLOTX24_S4_DP")
	)
	(segment
		(start 45.023024 -6.621526)
		(end 44.906438 -7.176262)
		(width 0.127)
		(layer "B.Cu")
		(net "CLK_100M_PCH_SLOTX24_S4_DP")
	)
	(segment
		(start 39.11981 5.620766)
		(end 41.357296 4.397756)
		(width 0.127)
		(layer "B.Cu")
		(net "CLK_100M_PCH_SLOTX24_S4_DP")
	)
	(segment
		(start 50.7365 -23.2156)
		(end 48.915574 -24.585422)
		(width 0.127)
		(layer "B.Cu")
		(net "CLK_100M_PCH_SLOTX24_S4_DP")
	)
	(segment
		(start 44.990004 3.282188)
		(end 47.768764 -0.546354)
		(width 0.127)
		(layer "B.Cu")
		(net "CLK_100M_PCH_SLOTX24_S4_DP")
	)
	(segment
		(start 47.904908 -4.238498)
		(end 47.904654 -4.238498)
		(width 0.127)
		(layer "B.Cu")
		(net "CLK_100M_PCH_SLOTX24_S4_DP")
	)
	(segment
		(start 34.69513 8.081264)
		(end 36.031932 7.792212)
		(width 0.127)
		(layer "B.Cu")
		(net "CLK_100M_PCH_SLOTX24_S4_DP")
	)
	(segment
		(start 45.92701 -9.435338)
		(end 45.964348 -11.895328)
		(width 0.127)
		(layer "B.Cu")
		(net "CLK_100M_PCH_SLOTX24_S4_DP")
	)
	(segment
		(start 44.916598 -7.32663)
		(end 44.918122 -7.344918)
		(width 0.127)
		(layer "B.Cu")
		(net "CLK_100M_PCH_SLOTX24_S4_DP")
	)
	(segment
		(start 29.670756 9.649206)
		(end 30.718506 8.600948)
		(width 0.127)
		(layer "B.Cu")
		(net "CLK_100M_PCH_SLOTX24_S4_DP")
	)
	(segment
		(start 47.861474 -4.31927)
		(end 47.815246 -4.372356)
		(width 0.127)
		(layer "B.Cu")
		(net "CLK_100M_PCH_SLOTX24_S4_DP")
	)
	(segment
		(start 31.096204 8.551672)
		(end 31.247334 8.355076)
		(width 0.127)
		(layer "B.Cu")
		(net "CLK_100M_PCH_SLOTX24_S4_DP")
	)
	(segment
		(start 51.0032 -17.5514)
		(end 51.0032 -22.46376)
		(width 0.127)
		(layer "B.Cu")
		(net "CLK_100M_PCH_SLOTX24_S4_DP")
	)
	(segment
		(start 45.276262 -26.542746)
		(end 45.154342 -26.664666)
		(width 0.127)
		(layer "B.Cu")
		(net "CLK_100M_PCH_SLOTX24_S4_DP")
	)
	(segment
		(start 47.064422 -14.537436)
		(end 47.112682 -14.651482)
		(width 0.127)
		(layer "B.Cu")
		(net "CLK_100M_PCH_SLOTX24_S4_DP")
	)
	(segment
		(start 44.918122 -7.344918)
		(end 44.918122 -7.34695)
		(width 0.127)
		(layer "B.Cu")
		(net "CLK_100M_PCH_SLOTX24_S4_DP")
	)
	(segment
		(start 46.930056 -13.838936)
		(end 47.064422 -14.537436)
		(width 0.127)
		(layer "B.Cu")
		(net "CLK_100M_PCH_SLOTX24_S4_DP")
	)
	(segment
		(start 45.058584 -28.02001)
		(end 45.478954 -28.728162)
		(width 0.127)
		(layer "B.Cu")
		(net "CLK_100M_PCH_SLOTX24_S4_DP")
	)
	(segment
		(start 47.903638 -4.241038)
		(end 47.900844 -4.248404)
		(width 0.127)
		(layer "B.Cu")
		(net "CLK_100M_PCH_SLOTX24_S4_DP")
	)
	(segment
		(start 45.454824 -32.819848)
		(end 45.079412 -32.069786)
		(width 0.127)
		(layer "B.Cu")
		(net "CLK_100M_PCH_SLOTX24_S4_DP")
	)
	(segment
		(start 45.925232 -29.573474)
		(end 45.93844 -29.920184)
		(width 0.127)
		(layer "B.Cu")
		(net "CLK_100M_PCH_SLOTX24_S4_DP")
	)
	(segment
		(start 45.488606 -28.742132)
		(end 45.834554 -29.180028)
		(width 0.127)
		(layer "B.Cu")
		(net "CLK_100M_PCH_SLOTX24_S4_DP")
	)
	(segment
		(start 45.872908 -9.023858)
		(end 45.92701 -9.435338)
		(width 0.127)
		(layer "B.Cu")
		(net "CLK_100M_PCH_SLOTX24_S4_DP")
	)
	(segment
		(start 44.916598 -7.348982)
		(end 45.012356 -7.763256)
		(width 0.127)
		(layer "B.Cu")
		(net "CLK_100M_PCH_SLOTX24_S4_DP")
	)
	(segment
		(start 47.433484 -4.642612)
		(end 47.432722 -4.642866)
		(width 0.127)
		(layer "B.Cu")
		(net "CLK_100M_PCH_SLOTX24_S4_DP")
	)
	(segment
		(start 45.33646 -8.311388)
		(end 45.374814 -8.362442)
		(width 0.127)
		(layer "B.Cu")
		(net "CLK_100M_PCH_SLOTX24_S4_DP")
	)
	(segment
		(start 32.728408 8.161528)
		(end 32.92475 8.312658)
		(width 0.127)
		(layer "B.Cu")
		(net "CLK_100M_PCH_SLOTX24_S4_DP")
	)
	(segment
		(start 45.93844 -29.920184)
		(end 45.956728 -31.658814)
		(width 0.127)
		(layer "B.Cu")
		(net "CLK_100M_PCH_SLOTX24_S4_DP")
	)
	(segment
		(start 45.298106 -8.260334)
		(end 45.299122 -8.26135)
		(width 0.127)
		(layer "B.Cu")
		(net "CLK_100M_PCH_SLOTX24_S4_DP")
	)
	(segment
		(start 31.625032 8.3058)
		(end 31.821628 8.456676)
		(width 0.127)
		(layer "B.Cu")
		(net "CLK_100M_PCH_SLOTX24_S4_DP")
	)
	(segment
		(start 47.899574 -4.251198)
		(end 47.861474 -4.31927)
		(width 0.127)
		(layer "B.Cu")
		(net "CLK_100M_PCH_SLOTX24_S4_DP")
	)
	(segment
		(start 43.392598 3.949954)
		(end 44.990004 3.282188)
		(width 0.127)
		(layer "B.Cu")
		(net "CLK_100M_PCH_SLOTX24_S4_DP")
	)
	(segment
		(start 48.94326 -15.6718)
		(end 49.1236 -15.6718)
		(width 0.127)
		(layer "B.Cu")
		(net "CLK_100M_PCH_SLOTX24_S4_DP")
	)
	(segment
		(start 44.916598 -7.348474)
		(end 44.916598 -7.348982)
		(width 0.127)
		(layer "B.Cu")
		(net "CLK_100M_PCH_SLOTX24_S4_DP")
	)
	(segment
		(start 32.92475 8.312658)
		(end 34.69513 8.081264)
		(width 0.127)
		(layer "B.Cu")
		(net "CLK_100M_PCH_SLOTX24_S4_DP")
	)
	(segment
		(start 45.296074 -8.26008)
		(end 45.29709 -8.261096)
		(width 0.127)
		(layer "B.Cu")
		(net "CLK_100M_PCH_SLOTX24_S4_DP")
	)
	(segment
		(start 45.374814 -8.362442)
		(end 45.872908 -9.023858)
		(width 0.127)
		(layer "B.Cu")
		(net "CLK_100M_PCH_SLOTX24_S4_DP")
	)
	(segment
		(start 47.117254 -14.653006)
		(end 47.21606 -14.88694)
		(width 0.127)
		(layer "B.Cu")
		(net "CLK_100M_PCH_SLOTX24_S4_DP")
	)
	(segment
		(start 47.4345 -4.641596)
		(end 47.433484 -4.642612)
		(width 0.127)
		(layer "B.Cu")
		(net "CLK_100M_PCH_SLOTX24_S4_DP")
	)
	(segment
		(start 45.012356 -7.763256)
		(end 45.189648 -8.073898)
		(width 0.127)
		(layer "B.Cu")
		(net "CLK_100M_PCH_SLOTX24_S4_DP")
	)
	(segment
		(start 47.815246 -4.372356)
		(end 47.4345 -4.641596)
		(width 0.127)
		(layer "B.Cu")
		(net "CLK_100M_PCH_SLOTX24_S4_DP")
	)
	(segment
		(start 45.834554 -29.180028)
		(end 45.925232 -29.573474)
		(width 0.127)
		(layer "B.Cu")
		(net "CLK_100M_PCH_SLOTX24_S4_DP")
	)
	(segment
		(start 48.392334 -2.477008)
		(end 48.268382 -3.311906)
		(width 0.127)
		(layer "B.Cu")
		(net "CLK_100M_PCH_SLOTX24_S4_DP")
	)
	(segment
		(start 46.873414 -13.545058)
		(end 46.930056 -13.838936)
		(width 0.127)
		(layer "B.Cu")
		(net "CLK_100M_PCH_SLOTX24_S4_DP")
	)
	(segment
		(start 45.29709 -8.261096)
		(end 45.298106 -8.260334)
		(width 0.127)
		(layer "B.Cu")
		(net "CLK_100M_PCH_SLOTX24_S4_DP")
	)
	(segment
		(start 47.900844 -4.248404)
		(end 47.899574 -4.251198)
		(width 0.127)
		(layer "B.Cu")
		(net "CLK_100M_PCH_SLOTX24_S4_DP")
	)
	(segment
		(start 48.915574 -24.585422)
		(end 45.276262 -26.542746)
		(width 0.127)
		(layer "B.Cu")
		(net "CLK_100M_PCH_SLOTX24_S4_DP")
	)
	(arc
		(start 45.625258 -32.87649)
		(mid 45.52831 -32.883467)
		(end 45.454824 -32.819848)
		(width 0.127)
		(layer "B.Cu")
		(net "CLK_100M_PCH_SLOTX24_S4_DP")
	)
	(arc
		(start 29.179774 10.924032)
		(mid 29.211927 10.762386)
		(end 29.303472 10.625328)
		(width 0.127)
		(layer "B.Cu")
		(net "CLK_100M_PCH_SLOTX24_S4_DP")
	)
	(arc
		(start 49.1236 -15.6718)
		(mid 50.452678 -16.222322)
		(end 51.0032 -17.5514)
		(width 0.127)
		(layer "B.Cu")
		(net "CLK_100M_PCH_SLOTX24_S4_DP")
	)
	(arc
		(start 47.281338 -14.983714)
		(mid 48.04385 -15.493085)
		(end 48.94326 -15.6718)
		(width 0.127)
		(layer "B.Cu")
		(net "CLK_100M_PCH_SLOTX24_S4_DP")
	)
	(arc
		(start 45.154342 -26.664666)
		(mid 44.989479 -26.91178)
		(end 44.931584 -27.203146)
		(width 0.127)
		(layer "B.Cu")
		(net "CLK_100M_PCH_SLOTX24_S4_DP")
	)
	(arc
		(start 45.907198 -32.588454)
		(mid 45.851104 -32.724496)
		(end 45.738796 -32.819594)
		(width 0.127)
		(layer "B.Cu")
		(net "CLK_100M_PCH_SLOTX24_S4_DP")
	)
	(arc
		(start 47.238412 -14.939772)
		(mid 47.259731 -14.961883)
		(end 47.281338 -14.983714)
		(width 0.127)
		(layer "B.Cu")
		(net "CLK_100M_PCH_SLOTX24_S4_DP")
	)
	(arc
		(start 29.303472 10.625328)
		(mid 29.395229 10.488193)
		(end 29.427424 10.32637)
		(width 0.127)
		(layer "B.Cu")
		(net "CLK_100M_PCH_SLOTX24_S4_DP")
	)
	(arc
		(start 44.931584 -27.633676)
		(mid 44.973953 -27.833788)
		(end 45.058584 -28.02001)
		(width 0.127)
		(layer "B.Cu")
		(net "CLK_100M_PCH_SLOTX24_S4_DP")
	)
	(arc
		(start 45.478954 -28.728162)
		(mid 45.483549 -28.735307)
		(end 45.488606 -28.742132)
		(width 0.127)
		(layer "B.Cu")
		(net "CLK_100M_PCH_SLOTX24_S4_DP")
	)
	(arc
		(start 45.956728 -31.658814)
		(mid 45.991444 -31.883811)
		(end 45.980096 -32.111188)
		(width 0.127)
		(layer "B.Cu")
		(net "CLK_100M_PCH_SLOTX24_S4_DP")
	)
	(segment
		(start 45.70476 -33.31972)
		(end 46.080172 -34.070036)
		(width 0.127)
		(layer "B.Cu")
		(net "CLK_100M_PCH_SLOTX24_S4_DN")
	)
	(segment
		(start 45.2247 -7.325868)
		(end 45.2247 -7.3279)
		(width 0.127)
		(layer "B.Cu")
		(net "CLK_100M_PCH_SLOTX24_S4_DN")
	)
	(segment
		(start 34.7472 8.382)
		(end 36.1569 8.0772)
		(width 0.127)
		(layer "B.Cu")
		(net "CLK_100M_PCH_SLOTX24_S4_DN")
	)
	(segment
		(start 48.170592 -4.391152)
		(end 48.170338 -4.391914)
		(width 0.127)
		(layer "B.Cu")
		(net "CLK_100M_PCH_SLOTX24_S4_DN")
	)
	(segment
		(start 47.351696 -14.416024)
		(end 47.40021 -14.530324)
		(width 0.127)
		(layer "B.Cu")
		(net "CLK_100M_PCH_SLOTX24_S4_DN")
	)
	(segment
		(start 45.542708 -8.077962)
		(end 45.543216 -8.078724)
		(width 0.127)
		(layer "B.Cu")
		(net "CLK_100M_PCH_SLOTX24_S4_DN")
	)
	(segment
		(start 51.308 -22.516338)
		(end 50.993294 -23.404068)
		(width 0.127)
		(layer "B.Cu")
		(net "CLK_100M_PCH_SLOTX24_S4_DN")
	)
	(segment
		(start 46.24324 -29.9085)
		(end 46.24324 -29.912818)
		(width 0.127)
		(layer "B.Cu")
		(net "CLK_100M_PCH_SLOTX24_S4_DN")
	)
	(segment
		(start 50.993294 -23.404068)
		(end 49.08042 -24.842978)
		(width 0.127)
		(layer "B.Cu")
		(net "CLK_100M_PCH_SLOTX24_S4_DN")
	)
	(segment
		(start 48.111918 -4.496054)
		(end 48.020986 -4.600194)
		(width 0.127)
		(layer "B.Cu")
		(net "CLK_100M_PCH_SLOTX24_S4_DN")
	)
	(segment
		(start 45.761656 -33.149286)
		(end 45.761402 -33.149286)
		(width 0.127)
		(layer "B.Cu")
		(net "CLK_100M_PCH_SLOTX24_S4_DN")
	)
	(segment
		(start 29.855922 10.806176)
		(end 29.855668 10.805922)
		(width 0.127)
		(layer "B.Cu")
		(net "CLK_100M_PCH_SLOTX24_S4_DN")
	)
	(segment
		(start 43.4848 4.2418)
		(end 45.1866 3.5306)
		(width 0.127)
		(layer "B.Cu")
		(net "CLK_100M_PCH_SLOTX24_S4_DN")
	)
	(segment
		(start 48.211486 -4.2926)
		(end 48.184816 -4.35991)
		(width 0.127)
		(layer "B.Cu")
		(net "CLK_100M_PCH_SLOTX24_S4_DN")
	)
	(segment
		(start 46.26864 -11.8491)
		(end 46.39564 -12.2809)
		(width 0.127)
		(layer "B.Cu")
		(net "CLK_100M_PCH_SLOTX24_S4_DN")
	)
	(segment
		(start 45.875194 -33.09239)
		(end 45.761656 -33.149286)
		(width 0.127)
		(layer "B.Cu")
		(net "CLK_100M_PCH_SLOTX24_S4_DN")
	)
	(segment
		(start 46.11624 -29.0449)
		(end 46.228762 -29.533088)
		(width 0.127)
		(layer "B.Cu")
		(net "CLK_100M_PCH_SLOTX24_S4_DN")
	)
	(segment
		(start 46.24324 -29.912818)
		(end 46.261274 -31.62046)
		(width 0.127)
		(layer "B.Cu")
		(net "CLK_100M_PCH_SLOTX24_S4_DN")
	)
	(segment
		(start 48.173386 -4.388866)
		(end 48.171354 -4.389628)
		(width 0.127)
		(layer "B.Cu")
		(net "CLK_100M_PCH_SLOTX24_S4_DN")
	)
	(segment
		(start 48.020986 -4.600194)
		(end 47.6123 -4.8895)
		(width 0.127)
		(layer "B.Cu")
		(net "CLK_100M_PCH_SLOTX24_S4_DN")
	)
	(segment
		(start 45.236384 -27.2034)
		(end 45.236384 -27.616912)
		(width 0.127)
		(layer "B.Cu")
		(net "CLK_100M_PCH_SLOTX24_S4_DN")
	)
	(segment
		(start 45.222414 -7.326122)
		(end 45.2247 -7.325868)
		(width 0.127)
		(layer "B.Cu")
		(net "CLK_100M_PCH_SLOTX24_S4_DN")
	)
	(segment
		(start 29.921454 9.8298)
		(end 30.861 8.89)
		(width 0.127)
		(layer "B.Cu")
		(net "CLK_100M_PCH_SLOTX24_S4_DN")
	)
	(segment
		(start 45.73524 -28.5623)
		(end 46.11624 -29.0449)
		(width 0.127)
		(layer "B.Cu")
		(net "CLK_100M_PCH_SLOTX24_S4_DN")
	)
	(segment
		(start 48.184816 -4.35991)
		(end 48.184562 -4.360672)
		(width 0.127)
		(layer "B.Cu")
		(net "CLK_100M_PCH_SLOTX24_S4_DN")
	)
	(segment
		(start 29.732224 10.507472)
		(end 29.732224 10.335006)
		(width 0.127)
		(layer "B.Cu")
		(net "CLK_100M_PCH_SLOTX24_S4_DN")
	)
	(segment
		(start 48.0441 -0.4064)
		(end 48.7045 -2.4511)
		(width 0.127)
		(layer "B.Cu")
		(net "CLK_100M_PCH_SLOTX24_S4_DN")
	)
	(segment
		(start 29.979874 12.514072)
		(end 29.979874 11.10488)
		(width 0.127)
		(layer "B.Cu")
		(net "CLK_100M_PCH_SLOTX24_S4_DN")
	)
	(segment
		(start 41.4655 4.6863)
		(end 43.4848 4.2418)
		(width 0.127)
		(layer "B.Cu")
		(net "CLK_100M_PCH_SLOTX24_S4_DN")
	)
	(segment
		(start 45.222414 -7.32409)
		(end 45.222414 -7.326122)
		(width 0.127)
		(layer "B.Cu")
		(net "CLK_100M_PCH_SLOTX24_S4_DN")
	)
	(segment
		(start 45.1866 3.5306)
		(end 48.0441 -0.4064)
		(width 0.127)
		(layer "B.Cu")
		(net "CLK_100M_PCH_SLOTX24_S4_DN")
	)
	(segment
		(start 46.281594 -32.157162)
		(end 46.208696 -32.634682)
		(width 0.127)
		(layer "B.Cu")
		(net "CLK_100M_PCH_SLOTX24_S4_DN")
	)
	(segment
		(start 46.164754 -8.904732)
		(end 46.231556 -9.412986)
		(width 0.127)
		(layer "B.Cu")
		(net "CLK_100M_PCH_SLOTX24_S4_DN")
	)
	(segment
		(start 47.398178 -14.534388)
		(end 47.496984 -14.768068)
		(width 0.127)
		(layer "B.Cu")
		(net "CLK_100M_PCH_SLOTX24_S4_DN")
	)
	(segment
		(start 48.7045 -2.4511)
		(end 48.5648 -3.3909)
		(width 0.127)
		(layer "B.Cu")
		(net "CLK_100M_PCH_SLOTX24_S4_DN")
	)
	(segment
		(start 30.861 8.89)
		(end 34.7472 8.382)
		(width 0.127)
		(layer "B.Cu")
		(net "CLK_100M_PCH_SLOTX24_S4_DN")
	)
	(segment
		(start 45.299376 -7.650988)
		(end 45.541692 -8.075168)
		(width 0.127)
		(layer "B.Cu")
		(net "CLK_100M_PCH_SLOTX24_S4_DN")
	)
	(segment
		(start 48.170338 -4.391914)
		(end 48.111918 -4.496054)
		(width 0.127)
		(layer "B.Cu")
		(net "CLK_100M_PCH_SLOTX24_S4_DN")
	)
	(segment
		(start 49.08042 -24.842978)
		(end 45.460412 -26.789888)
		(width 0.127)
		(layer "B.Cu")
		(net "CLK_100M_PCH_SLOTX24_S4_DN")
	)
	(segment
		(start 45.213524 -7.197344)
		(end 45.222414 -7.32409)
		(width 0.127)
		(layer "B.Cu")
		(net "CLK_100M_PCH_SLOTX24_S4_DN")
	)
	(segment
		(start 47.40021 -14.530324)
		(end 47.398178 -14.534388)
		(width 0.127)
		(layer "B.Cu")
		(net "CLK_100M_PCH_SLOTX24_S4_DN")
	)
	(segment
		(start 36.1569 8.0772)
		(end 39.2811 5.8801)
		(width 0.127)
		(layer "B.Cu")
		(net "CLK_100M_PCH_SLOTX24_S4_DN")
	)
	(segment
		(start 29.732224 10.208006)
		(end 29.921454 9.8298)
		(width 0.127)
		(layer "B.Cu")
		(net "CLK_100M_PCH_SLOTX24_S4_DN")
	)
	(segment
		(start 45.3009 -6.7818)
		(end 45.213524 -7.197344)
		(width 0.127)
		(layer "B.Cu")
		(net "CLK_100M_PCH_SLOTX24_S4_DN")
	)
	(segment
		(start 46.4058 -5.7912)
		(end 45.3009 -6.7818)
		(width 0.127)
		(layer "B.Cu")
		(net "CLK_100M_PCH_SLOTX24_S4_DN")
	)
	(segment
		(start 45.2247 -7.3279)
		(end 45.299376 -7.650988)
		(width 0.127)
		(layer "B.Cu")
		(net "CLK_100M_PCH_SLOTX24_S4_DN")
	)
	(segment
		(start 39.2811 5.8801)
		(end 41.4655 4.6863)
		(width 0.127)
		(layer "B.Cu")
		(net "CLK_100M_PCH_SLOTX24_S4_DN")
	)
	(segment
		(start 45.618654 -8.179308)
		(end 46.164754 -8.904732)
		(width 0.127)
		(layer "B.Cu")
		(net "CLK_100M_PCH_SLOTX24_S4_DN")
	)
	(segment
		(start 48.184562 -4.360672)
		(end 48.173386 -4.388866)
		(width 0.127)
		(layer "B.Cu")
		(net "CLK_100M_PCH_SLOTX24_S4_DN")
	)
	(segment
		(start 48.171354 -4.389628)
		(end 48.170592 -4.391152)
		(width 0.127)
		(layer "B.Cu")
		(net "CLK_100M_PCH_SLOTX24_S4_DN")
	)
	(segment
		(start 45.460412 -26.789888)
		(end 45.370496 -26.880058)
		(width 0.127)
		(layer "B.Cu")
		(net "CLK_100M_PCH_SLOTX24_S4_DN")
	)
	(segment
		(start 29.732224 10.32637)
		(end 29.732224 10.208006)
		(width 0.127)
		(layer "B.Cu")
		(net "CLK_100M_PCH_SLOTX24_S4_DN")
	)
	(segment
		(start 47.17288 -13.4874)
		(end 47.229522 -13.781278)
		(width 0.127)
		(layer "B.Cu")
		(net "CLK_100M_PCH_SLOTX24_S4_DN")
	)
	(segment
		(start 45.320712 -27.864308)
		(end 45.73524 -28.5623)
		(width 0.127)
		(layer "B.Cu")
		(net "CLK_100M_PCH_SLOTX24_S4_DN")
	)
	(segment
		(start 48.943006 -15.367)
		(end 49.1236 -15.367)
		(width 0.127)
		(layer "B.Cu")
		(net "CLK_100M_PCH_SLOTX24_S4_DN")
	)
	(segment
		(start 46.228762 -29.533088)
		(end 46.24324 -29.9085)
		(width 0.127)
		(layer "B.Cu")
		(net "CLK_100M_PCH_SLOTX24_S4_DN")
	)
	(segment
		(start 47.229522 -13.781278)
		(end 47.351696 -14.416024)
		(width 0.127)
		(layer "B.Cu")
		(net "CLK_100M_PCH_SLOTX24_S4_DN")
	)
	(segment
		(start 45.541692 -8.075168)
		(end 45.542708 -8.076184)
		(width 0.127)
		(layer "B.Cu")
		(net "CLK_100M_PCH_SLOTX24_S4_DN")
	)
	(segment
		(start 47.6123 -4.8895)
		(end 46.4058 -5.7912)
		(width 0.127)
		(layer "B.Cu")
		(net "CLK_100M_PCH_SLOTX24_S4_DN")
	)
	(segment
		(start 45.542708 -8.076184)
		(end 45.541692 -8.076946)
		(width 0.127)
		(layer "B.Cu")
		(net "CLK_100M_PCH_SLOTX24_S4_DN")
	)
	(segment
		(start 45.543216 -8.078724)
		(end 45.618654 -8.179308)
		(width 0.127)
		(layer "B.Cu")
		(net "CLK_100M_PCH_SLOTX24_S4_DN")
	)
	(segment
		(start 46.231556 -9.412986)
		(end 46.26864 -11.8491)
		(width 0.127)
		(layer "B.Cu")
		(net "CLK_100M_PCH_SLOTX24_S4_DN")
	)
	(segment
		(start 47.10684 -13.1445)
		(end 47.17288 -13.4874)
		(width 0.127)
		(layer "B.Cu")
		(net "CLK_100M_PCH_SLOTX24_S4_DN")
	)
	(segment
		(start 45.541692 -8.076946)
		(end 45.542708 -8.077962)
		(width 0.127)
		(layer "B.Cu")
		(net "CLK_100M_PCH_SLOTX24_S4_DN")
	)
	(segment
		(start 48.5648 -3.3909)
		(end 48.211486 -4.2926)
		(width 0.127)
		(layer "B.Cu")
		(net "CLK_100M_PCH_SLOTX24_S4_DN")
	)
	(segment
		(start 51.308 -17.5514)
		(end 51.308 -22.516338)
		(width 0.127)
		(layer "B.Cu")
		(net "CLK_100M_PCH_SLOTX24_S4_DN")
	)
	(segment
		(start 46.39564 -12.2809)
		(end 47.10684 -13.1445)
		(width 0.127)
		(layer "B.Cu")
		(net "CLK_100M_PCH_SLOTX24_S4_DN")
	)
	(arc
		(start 47.496984 -14.768068)
		(mid 48.160425 -15.211365)
		(end 48.943006 -15.367)
		(width 0.127)
		(layer "B.Cu")
		(net "CLK_100M_PCH_SLOTX24_S4_DN")
	)
	(arc
		(start 45.236384 -27.616912)
		(mid 45.265663 -27.745004)
		(end 45.320712 -27.864308)
		(width 0.127)
		(layer "B.Cu")
		(net "CLK_100M_PCH_SLOTX24_S4_DN")
	)
	(arc
		(start 45.761402 -33.149286)
		(mid 45.697783 -33.222772)
		(end 45.70476 -33.31972)
		(width 0.127)
		(layer "B.Cu")
		(net "CLK_100M_PCH_SLOTX24_S4_DN")
	)
	(arc
		(start 46.261274 -31.62046)
		(mid 46.296866 -31.887846)
		(end 46.281594 -32.157162)
		(width 0.127)
		(layer "B.Cu")
		(net "CLK_100M_PCH_SLOTX24_S4_DN")
	)
	(arc
		(start 49.1236 -15.367)
		(mid 50.668204 -16.006796)
		(end 51.308 -17.5514)
		(width 0.127)
		(layer "B.Cu")
		(net "CLK_100M_PCH_SLOTX24_S4_DN")
	)
	(arc
		(start 45.370496 -26.880058)
		(mid 45.271288 -27.028394)
		(end 45.236384 -27.2034)
		(width 0.127)
		(layer "B.Cu")
		(net "CLK_100M_PCH_SLOTX24_S4_DN")
	)
	(arc
		(start 29.855668 10.805922)
		(mid 29.764282 10.668964)
		(end 29.732224 10.507472)
		(width 0.127)
		(layer "B.Cu")
		(net "CLK_100M_PCH_SLOTX24_S4_DN")
	)
	(arc
		(start 29.732224 10.335006)
		(mid 29.732237 10.330688)
		(end 29.732224 10.32637)
		(width 0.127)
		(layer "B.Cu")
		(net "CLK_100M_PCH_SLOTX24_S4_DN")
	)
	(arc
		(start 29.979874 11.10488)
		(mid 29.947618 10.94319)
		(end 29.855922 10.806176)
		(width 0.127)
		(layer "B.Cu")
		(net "CLK_100M_PCH_SLOTX24_S4_DN")
	)
	(arc
		(start 46.208696 -32.634682)
		(mid 46.097634 -32.90411)
		(end 45.875194 -33.09239)
		(width 0.127)
		(layer "B.Cu")
		(net "CLK_100M_PCH_SLOTX24_S4_DN")
	)
	(segment
		(start 119.7864 -22.4028)
		(end 119.7864 -21.6154)
		(width 0.1016)
		(layer "F.Cu")
		(net "SMDAT_USB_HUB_R")
	)
	(segment
		(start 121.7041 -23.3934)
		(end 121.450354 -23.139654)
		(width 0.1016)
		(layer "F.Cu")
		(net "SMDAT_USB_HUB_R")
	)
	(segment
		(start 122.9614 -23.5458)
		(end 123.774454 -24.358854)
		(width 0.1016)
		(layer "F.Cu")
		(net "SMDAT_USB_HUB_R")
	)
	(segment
		(start 121.450354 -23.13051)
		(end 121.07799 -22.758146)
		(width 0.1016)
		(layer "F.Cu")
		(net "SMDAT_USB_HUB_R")
	)
	(segment
		(start 119.7864 -21.6154)
		(end 119.888 -21.5138)
		(width 0.1016)
		(layer "F.Cu")
		(net "SMDAT_USB_HUB_R")
	)
	(segment
		(start 121.8565 -23.5458)
		(end 122.9614 -23.5458)
		(width 0.1016)
		(layer "F.Cu")
		(net "SMDAT_USB_HUB_R")
	)
	(segment
		(start 119.938546 -22.554946)
		(end 119.7864 -22.4028)
		(width 0.1016)
		(layer "F.Cu")
		(net "SMDAT_USB_HUB_R")
	)
	(segment
		(start 121.450354 -23.139654)
		(end 121.450354 -23.13051)
		(width 0.1016)
		(layer "F.Cu")
		(net "SMDAT_USB_HUB_R")
	)
	(segment
		(start 121.07799 -22.758146)
		(end 120.881394 -22.758146)
		(width 0.1016)
		(layer "F.Cu")
		(net "SMDAT_USB_HUB_R")
	)
	(segment
		(start 121.7041 -23.3934)
		(end 121.8565 -23.5458)
		(width 0.1016)
		(layer "F.Cu")
		(net "SMDAT_USB_HUB_R")
	)
	(segment
		(start 120.881394 -22.758146)
		(end 120.678194 -22.554946)
		(width 0.1016)
		(layer "F.Cu")
		(net "SMDAT_USB_HUB_R")
	)
	(segment
		(start 120.678194 -22.554946)
		(end 119.938546 -22.554946)
		(width 0.1016)
		(layer "F.Cu")
		(net "SMDAT_USB_HUB_R")
	)
	(segment
		(start 123.774454 -24.358854)
		(end 123.774454 -25.27173)
		(width 0.1016)
		(layer "F.Cu")
		(net "SMDAT_USB_HUB_R")
	)
	(via
		(at 118.7196 -19.8501)
		(size 0.7112)
		(drill 0.3556)
		(layers "F.Cu" "B.Cu")
		(net "SMDAT_USB_HUB_R")
	)
	(via
		(at 119.888 -21.5138)
		(size 0.508)
		(drill 0.254)
		(layers "F.Cu" "B.Cu")
		(net "SMDAT_USB_HUB_R")
	)
	(segment
		(start 122.48134 -15.60068)
		(end 121.73712 -15.60068)
		(width 0.1016)
		(layer "B.Cu")
		(net "SMDAT_USB_HUB_R")
	)
	(segment
		(start 118.8212 -19.9517)
		(end 118.7196 -19.8501)
		(width 0.1016)
		(layer "B.Cu")
		(net "SMDAT_USB_HUB_R")
	)
	(segment
		(start 121.73712 -15.60068)
		(end 118.6434 -18.6944)
		(width 0.1016)
		(layer "B.Cu")
		(net "SMDAT_USB_HUB_R")
	)
	(segment
		(start 118.6434 -18.7833)
		(end 118.6307 -18.796)
		(width 0.1016)
		(layer "B.Cu")
		(net "SMDAT_USB_HUB_R")
	)
	(segment
		(start 119.888 -21.5138)
		(end 119.888 -21.463)
		(width 0.1016)
		(layer "B.Cu")
		(net "SMDAT_USB_HUB_R")
	)
	(segment
		(start 119.888 -21.463)
		(end 118.8212 -20.3962)
		(width 0.1016)
		(layer "B.Cu")
		(net "SMDAT_USB_HUB_R")
	)
	(segment
		(start 119.6594 -21.7424)
		(end 119.888 -21.5138)
		(width 0.1016)
		(layer "B.Cu")
		(net "SMDAT_USB_HUB_R")
	)
	(segment
		(start 118.6434 -18.6944)
		(end 118.6434 -18.7833)
		(width 0.1016)
		(layer "B.Cu")
		(net "SMDAT_USB_HUB_R")
	)
	(segment
		(start 118.6307 -18.796)
		(end 118.6307 -19.7612)
		(width 0.1016)
		(layer "B.Cu")
		(net "SMDAT_USB_HUB_R")
	)
	(segment
		(start 119.6594 -22.3393)
		(end 119.6594 -21.7424)
		(width 0.1016)
		(layer "B.Cu")
		(net "SMDAT_USB_HUB_R")
	)
	(segment
		(start 118.6307 -19.7612)
		(end 118.7196 -19.8501)
		(width 0.1016)
		(layer "B.Cu")
		(net "SMDAT_USB_HUB_R")
	)
	(segment
		(start 118.8212 -20.3962)
		(end 118.8212 -19.9517)
		(width 0.1016)
		(layer "B.Cu")
		(net "SMDAT_USB_HUB_R")
	)
	(segment
		(start 130.3274 2.7178)
		(end 130.1369 2.5273)
		(width 0.1016)
		(layer "F.Cu")
		(net "SMDAT_PCH_DEVICE")
	)
	(segment
		(start 130.1496 0.9271)
		(end 130.1496 1.9685)
		(width 0.1016)
		(layer "F.Cu")
		(net "SMDAT_PCH_DEVICE")
	)
	(segment
		(start 130.1369 2.5273)
		(end 130.1369 1.9812)
		(width 0.1016)
		(layer "F.Cu")
		(net "SMDAT_PCH_DEVICE")
	)
	(segment
		(start 130.3274 2.8448)
		(end 130.3274 2.7178)
		(width 0.1016)
		(layer "F.Cu")
		(net "SMDAT_PCH_DEVICE")
	)
	(segment
		(start 130.1496 1.9685)
		(end 130.1369 1.9812)
		(width 0.1016)
		(layer "F.Cu")
		(net "SMDAT_PCH_DEVICE")
	)
	(via
		(at 130.3274 2.8448)
		(size 0.508)
		(drill 0.254)
		(layers "F.Cu" "B.Cu")
		(net "SMDAT_PCH_DEVICE")
	)
	(via
		(at 130.0353 1.8415)
		(size 0.7112)
		(drill 0.3556)
		(layers "F.Cu" "B.Cu")
		(net "SMDAT_PCH_DEVICE")
	)
	(via
		(at 129.083562 -26.313892)
		(size 0.508)
		(drill 0.254)
		(layers "F.Cu" "B.Cu")
		(net "SMDAT_PCH_DEVICE")
	)
	(segment
		(start 129.286 -25.6921)
		(end 129.032 -25.4381)
		(width 0.1016)
		(layer "B.Cu")
		(net "SMDAT_PCH_DEVICE")
	)
	(segment
		(start 127.77216 -2.50444)
		(end 128.0668 -2.2098)
		(width 0.1016)
		(layer "B.Cu")
		(net "SMDAT_PCH_DEVICE")
	)
	(segment
		(start 129.083562 -26.313638)
		(end 129.286 -26.1112)
		(width 0.1016)
		(layer "B.Cu")
		(net "SMDAT_PCH_DEVICE")
	)
	(segment
		(start 127.799084 -1.27)
		(end 127.773684 -1.27)
		(width 0.1016)
		(layer "B.Cu")
		(net "SMDAT_PCH_DEVICE")
	)
	(segment
		(start 127.773684 -1.27)
		(end 127.2032 -0.699516)
		(width 0.1016)
		(layer "B.Cu")
		(net "SMDAT_PCH_DEVICE")
	)
	(segment
		(start 129.8829 1.9177)
		(end 129.9591 1.8415)
		(width 0.1016)
		(layer "B.Cu")
		(net "SMDAT_PCH_DEVICE")
	)
	(segment
		(start 130.0353 1.8415)
		(end 130.0353 1.8923)
		(width 0.1016)
		(layer "B.Cu")
		(net "SMDAT_PCH_DEVICE")
	)
	(segment
		(start 127.2032 1.1811)
		(end 127.9398 1.9177)
		(width 0.1016)
		(layer "B.Cu")
		(net "SMDAT_PCH_DEVICE")
	)
	(segment
		(start 127.9398 1.9177)
		(end 129.8829 1.9177)
		(width 0.1016)
		(layer "B.Cu")
		(net "SMDAT_PCH_DEVICE")
	)
	(segment
		(start 128.0668 -2.2098)
		(end 128.0668 -1.537716)
		(width 0.1016)
		(layer "B.Cu")
		(net "SMDAT_PCH_DEVICE")
	)
	(segment
		(start 129.083562 -26.313892)
		(end 129.083562 -26.313638)
		(width 0.1016)
		(layer "B.Cu")
		(net "SMDAT_PCH_DEVICE")
	)
	(segment
		(start 127.2032 -0.699516)
		(end 127.2032 1.1811)
		(width 0.1016)
		(layer "B.Cu")
		(net "SMDAT_PCH_DEVICE")
	)
	(segment
		(start 130.3274 2.1844)
		(end 130.3274 2.8448)
		(width 0.1016)
		(layer "B.Cu")
		(net "SMDAT_PCH_DEVICE")
	)
	(segment
		(start 129.286 -26.1112)
		(end 129.286 -25.6921)
		(width 0.1016)
		(layer "B.Cu")
		(net "SMDAT_PCH_DEVICE")
	)
	(segment
		(start 129.9591 1.8415)
		(end 130.0353 1.8415)
		(width 0.1016)
		(layer "B.Cu")
		(net "SMDAT_PCH_DEVICE")
	)
	(segment
		(start 127.77216 -3.175)
		(end 127.77216 -2.50444)
		(width 0.1016)
		(layer "B.Cu")
		(net "SMDAT_PCH_DEVICE")
	)
	(segment
		(start 128.0668 -1.537716)
		(end 127.799084 -1.27)
		(width 0.1016)
		(layer "B.Cu")
		(net "SMDAT_PCH_DEVICE")
	)
	(segment
		(start 130.0353 1.8923)
		(end 130.3274 2.1844)
		(width 0.1016)
		(layer "B.Cu")
		(net "SMDAT_PCH_DEVICE")
	)
	(segment
		(start 129.083562 -26.313892)
		(end 129.083562 -25.203404)
		(width 0.127)
		(layer "In2.Cu")
		(net "SMDAT_PCH_DEVICE")
	)
	(segment
		(start 130.3274 2.013966)
		(end 130.3274 2.8448)
		(width 0.127)
		(layer "In2.Cu")
		(net "SMDAT_PCH_DEVICE")
	)
	(segment
		(start 129.7178 1.404366)
		(end 130.3274 2.013966)
		(width 0.127)
		(layer "In2.Cu")
		(net "SMDAT_PCH_DEVICE")
	)
	(segment
		(start 129.7178 -10.319766)
		(end 129.7178 1.404366)
		(width 0.127)
		(layer "In2.Cu")
		(net "SMDAT_PCH_DEVICE")
	)
	(segment
		(start 130.6703 -23.616666)
		(end 130.6703 -11.272266)
		(width 0.127)
		(layer "In2.Cu")
		(net "SMDAT_PCH_DEVICE")
	)
	(segment
		(start 129.083562 -25.203404)
		(end 130.6703 -23.616666)
		(width 0.127)
		(layer "In2.Cu")
		(net "SMDAT_PCH_DEVICE")
	)
	(segment
		(start 130.6703 -11.272266)
		(end 129.7178 -10.319766)
		(width 0.127)
		(layer "In2.Cu")
		(net "SMDAT_PCH_DEVICE")
	)
	(segment
		(start 123.5583 -23.5458)
		(end 122.8471 -22.8346)
		(width 0.1016)
		(layer "F.Cu")
		(net "SMCLK_USB_HUB_R")
	)
	(segment
		(start 121.278142 -22.275546)
		(end 121.73585 -22.733)
		(width 0.1016)
		(layer "F.Cu")
		(net "SMCLK_USB_HUB_R")
	)
	(segment
		(start 124.774706 -23.911306)
		(end 124.4092 -23.5458)
		(width 0.1016)
		(layer "F.Cu")
		(net "SMCLK_USB_HUB_R")
	)
	(segment
		(start 121.73585 -22.733)
		(end 122.7455 -22.733)
		(width 0.1016)
		(layer "F.Cu")
		(net "SMCLK_USB_HUB_R")
	)
	(segment
		(start 124.774706 -25.27173)
		(end 124.774706 -23.911306)
		(width 0.1016)
		(layer "F.Cu")
		(net "SMCLK_USB_HUB_R")
	)
	(segment
		(start 122.7455 -22.733)
		(end 122.8471 -22.8346)
		(width 0.1016)
		(layer "F.Cu")
		(net "SMCLK_USB_HUB_R")
	)
	(segment
		(start 124.4092 -23.5458)
		(end 123.5583 -23.5458)
		(width 0.1016)
		(layer "F.Cu")
		(net "SMCLK_USB_HUB_R")
	)
	(segment
		(start 121.081546 -22.275546)
		(end 121.278142 -22.275546)
		(width 0.1016)
		(layer "F.Cu")
		(net "SMCLK_USB_HUB_R")
	)
	(segment
		(start 120.777 -21.4884)
		(end 120.777 -21.971)
		(width 0.1016)
		(layer "F.Cu")
		(net "SMCLK_USB_HUB_R")
	)
	(segment
		(start 120.777 -21.971)
		(end 121.081546 -22.275546)
		(width 0.1016)
		(layer "F.Cu")
		(net "SMCLK_USB_HUB_R")
	)
	(via
		(at 119.9642 -20.32)
		(size 0.7112)
		(drill 0.3556)
		(layers "F.Cu" "B.Cu")
		(net "SMCLK_USB_HUB_R")
	)
	(via
		(at 120.777 -21.4884)
		(size 0.508)
		(drill 0.254)
		(layers "F.Cu" "B.Cu")
		(net "SMCLK_USB_HUB_R")
	)
	(segment
		(start 119.6467 -18.373852)
		(end 119.6467 -18.796)
		(width 0.1016)
		(layer "B.Cu")
		(net "SMCLK_USB_HUB_R")
	)
	(segment
		(start 120.8278 -21.5392)
		(end 120.777 -21.4884)
		(width 0.1016)
		(layer "B.Cu")
		(net "SMCLK_USB_HUB_R")
	)
	(segment
		(start 120.777 -21.336)
		(end 119.9642 -20.5232)
		(width 0.1016)
		(layer "B.Cu")
		(net "SMCLK_USB_HUB_R")
	)
	(segment
		(start 119.6467 -20.0025)
		(end 119.9642 -20.32)
		(width 0.1016)
		(layer "B.Cu")
		(net "SMCLK_USB_HUB_R")
	)
	(segment
		(start 122.48134 -16.25092)
		(end 121.769632 -16.25092)
		(width 0.1016)
		(layer "B.Cu")
		(net "SMCLK_USB_HUB_R")
	)
	(segment
		(start 119.9642 -20.5232)
		(end 119.9642 -20.32)
		(width 0.1016)
		(layer "B.Cu")
		(net "SMCLK_USB_HUB_R")
	)
	(segment
		(start 119.6467 -18.796)
		(end 119.6467 -20.0025)
		(width 0.1016)
		(layer "B.Cu")
		(net "SMCLK_USB_HUB_R")
	)
	(segment
		(start 120.8278 -22.4155)
		(end 120.8278 -21.5392)
		(width 0.1016)
		(layer "B.Cu")
		(net "SMCLK_USB_HUB_R")
	)
	(segment
		(start 121.769632 -16.25092)
		(end 119.6467 -18.373852)
		(width 0.1016)
		(layer "B.Cu")
		(net "SMCLK_USB_HUB_R")
	)
	(segment
		(start 120.777 -21.4884)
		(end 120.777 -21.336)
		(width 0.1016)
		(layer "B.Cu")
		(net "SMCLK_USB_HUB_R")
	)
	(segment
		(start 129.1082 0.9271)
		(end 129.1082 1.9177)
		(width 0.1016)
		(layer "F.Cu")
		(net "SMCLK_PCH_DEVICE")
	)
	(segment
		(start 129.4638 2.667)
		(end 129.0701 2.2733)
		(width 0.1016)
		(layer "F.Cu")
		(net "SMCLK_PCH_DEVICE")
	)
	(segment
		(start 129.1082 1.9177)
		(end 129.0701 1.9558)
		(width 0.1016)
		(layer "F.Cu")
		(net "SMCLK_PCH_DEVICE")
	)
	(segment
		(start 129.4638 2.7178)
		(end 129.4638 2.667)
		(width 0.1016)
		(layer "F.Cu")
		(net "SMCLK_PCH_DEVICE")
	)
	(segment
		(start 129.0701 2.2733)
		(end 129.0701 1.9558)
		(width 0.1016)
		(layer "F.Cu")
		(net "SMCLK_PCH_DEVICE")
	)
	(via
		(at 129.4638 2.7178)
		(size 0.508)
		(drill 0.254)
		(layers "F.Cu" "B.Cu")
		(net "SMCLK_PCH_DEVICE")
	)
	(via
		(at 129.947162 -26.314654)
		(size 0.508)
		(drill 0.254)
		(layers "F.Cu" "B.Cu")
		(net "SMCLK_PCH_DEVICE")
	)
	(via
		(at 127.4953 2.5273)
		(size 0.7112)
		(drill 0.3556)
		(layers "F.Cu" "B.Cu")
		(net "SMCLK_PCH_DEVICE")
	)
	(segment
		(start 129.9464 -26.2636)
		(end 129.921 -26.2382)
		(width 0.1016)
		(layer "B.Cu")
		(net "SMCLK_PCH_DEVICE")
	)
	(segment
		(start 127.12192 -3.175)
		(end 127.12192 -2.455672)
		(width 0.1016)
		(layer "B.Cu")
		(net "SMCLK_PCH_DEVICE")
	)
	(segment
		(start 126.7206 -2.054352)
		(end 126.7206 1.381252)
		(width 0.1016)
		(layer "B.Cu")
		(net "SMCLK_PCH_DEVICE")
	)
	(segment
		(start 129.4638 2.7178)
		(end 127.6858 2.7178)
		(width 0.1016)
		(layer "B.Cu")
		(net "SMCLK_PCH_DEVICE")
	)
	(segment
		(start 127.12192 -2.455672)
		(end 126.7206 -2.054352)
		(width 0.1016)
		(layer "B.Cu")
		(net "SMCLK_PCH_DEVICE")
	)
	(segment
		(start 129.9464 -26.314654)
		(end 129.9464 -26.2636)
		(width 0.1016)
		(layer "B.Cu")
		(net "SMCLK_PCH_DEVICE")
	)
	(segment
		(start 130.0988 -25.4762)
		(end 130.0988 -25.4381)
		(width 0.1016)
		(layer "B.Cu")
		(net "SMCLK_PCH_DEVICE")
	)
	(segment
		(start 129.947162 -26.314654)
		(end 129.9464 -26.314654)
		(width 0.1016)
		(layer "B.Cu")
		(net "SMCLK_PCH_DEVICE")
	)
	(segment
		(start 129.921 -25.654)
		(end 130.0988 -25.4762)
		(width 0.1016)
		(layer "B.Cu")
		(net "SMCLK_PCH_DEVICE")
	)
	(segment
		(start 129.921 -26.2382)
		(end 129.921 -25.654)
		(width 0.1016)
		(layer "B.Cu")
		(net "SMCLK_PCH_DEVICE")
	)
	(segment
		(start 127.6858 2.7178)
		(end 127.4953 2.5273)
		(width 0.1016)
		(layer "B.Cu")
		(net "SMCLK_PCH_DEVICE")
	)
	(segment
		(start 127.0254 1.686052)
		(end 127.0254 2.0574)
		(width 0.1016)
		(layer "B.Cu")
		(net "SMCLK_PCH_DEVICE")
	)
	(segment
		(start 126.7206 1.381252)
		(end 127.0254 1.686052)
		(width 0.1016)
		(layer "B.Cu")
		(net "SMCLK_PCH_DEVICE")
	)
	(segment
		(start 127.0254 2.0574)
		(end 127.4953 2.5273)
		(width 0.1016)
		(layer "B.Cu")
		(net "SMCLK_PCH_DEVICE")
	)
	(segment
		(start 130.0988 3.3528)
		(end 130.537966 3.3528)
		(width 0.127)
		(layer "In2.Cu")
		(net "SMCLK_PCH_DEVICE")
	)
	(segment
		(start 130.8354 3.055366)
		(end 130.8354 1.8034)
		(width 0.127)
		(layer "In2.Cu")
		(net "SMCLK_PCH_DEVICE")
	)
	(segment
		(start 129.6924 -26.059892)
		(end 129.947162 -26.314654)
		(width 0.127)
		(layer "In2.Cu")
		(net "SMCLK_PCH_DEVICE")
	)
	(segment
		(start 130.537966 3.3528)
		(end 130.8354 3.055366)
		(width 0.127)
		(layer "In2.Cu")
		(net "SMCLK_PCH_DEVICE")
	)
	(segment
		(start 129.6924 -25.313386)
		(end 129.6924 -26.059892)
		(width 0.127)
		(layer "In2.Cu")
		(net "SMCLK_PCH_DEVICE")
	)
	(segment
		(start 130.2258 1.1938)
		(end 130.2258 -10.1092)
		(width 0.127)
		(layer "In2.Cu")
		(net "SMCLK_PCH_DEVICE")
	)
	(segment
		(start 131.234942 -23.770844)
		(end 129.6924 -25.313386)
		(width 0.127)
		(layer "In2.Cu")
		(net "SMCLK_PCH_DEVICE")
	)
	(segment
		(start 129.4638 2.7178)
		(end 130.0988 3.3528)
		(width 0.127)
		(layer "In2.Cu")
		(net "SMCLK_PCH_DEVICE")
	)
	(segment
		(start 130.8354 1.8034)
		(end 130.2258 1.1938)
		(width 0.127)
		(layer "In2.Cu")
		(net "SMCLK_PCH_DEVICE")
	)
	(segment
		(start 130.2258 -10.1092)
		(end 131.234942 -11.118342)
		(width 0.127)
		(layer "In2.Cu")
		(net "SMCLK_PCH_DEVICE")
	)
	(segment
		(start 131.234942 -11.118342)
		(end 131.234942 -23.770844)
		(width 0.127)
		(layer "In2.Cu")
		(net "SMCLK_PCH_DEVICE")
	)
	(segment
		(start 53.541676 -21.0312)
		(end 53.7464 -21.235924)
		(width 0.1016)
		(layer "F.Cu")
		(net "SMB_PCIE_SLOT3_ALERT_N")
	)
	(segment
		(start 52.5526 -21.0312)
		(end 53.541676 -21.0312)
		(width 0.1016)
		(layer "F.Cu")
		(net "SMB_PCIE_SLOT3_ALERT_N")
	)
	(segment
		(start 53.7464 -21.235924)
		(end 53.7464 -21.7551)
		(width 0.1016)
		(layer "F.Cu")
		(net "SMB_PCIE_SLOT3_ALERT_N")
	)
	(via
		(at 116.1415 -5.2578)
		(size 0.508)
		(drill 0.254)
		(layers "F.Cu" "B.Cu")
		(net "SMB_PCIE_SLOT3_ALERT_N")
	)
	(via
		(at 124.117608 -5.765292)
		(size 0.508)
		(drill 0.254)
		(layers "F.Cu" "B.Cu")
		(net "SMB_PCIE_SLOT3_ALERT_N")
	)
	(via
		(at 110.4519 -17.8181)
		(size 0.7112)
		(drill 0.3556)
		(layers "F.Cu" "B.Cu")
		(net "SMB_PCIE_SLOT3_ALERT_N")
	)
	(via
		(at 111.1377 -19.098514)
		(size 0.508)
		(drill 0.254)
		(layers "F.Cu" "B.Cu")
		(net "SMB_PCIE_SLOT3_ALERT_N")
	)
	(via
		(at 52.5526 -21.0312)
		(size 0.508)
		(drill 0.254)
		(layers "F.Cu" "B.Cu")
		(net "SMB_PCIE_SLOT3_ALERT_N")
	)
	(segment
		(start 115.54968 -3.98018)
		(end 115.9764 -4.4069)
		(width 0.1016)
		(layer "B.Cu")
		(net "SMB_PCIE_SLOT3_ALERT_N")
	)
	(segment
		(start 111.54918 -3.53568)
		(end 113.4491 -5.4356)
		(width 0.1016)
		(layer "B.Cu")
		(net "SMB_PCIE_SLOT3_ALERT_N")
	)
	(segment
		(start 111.252 -3.2385)
		(end 111.252 -3.253232)
		(width 0.1016)
		(layer "B.Cu")
		(net "SMB_PCIE_SLOT3_ALERT_N")
	)
	(segment
		(start 110.4519 -17.032224)
		(end 112.142524 -15.3416)
		(width 0.1016)
		(layer "B.Cu")
		(net "SMB_PCIE_SLOT3_ALERT_N")
	)
	(segment
		(start 110.4519 -18.412714)
		(end 111.1377 -19.098514)
		(width 0.1016)
		(layer "B.Cu")
		(net "SMB_PCIE_SLOT3_ALERT_N")
	)
	(segment
		(start 115.9764 -5.0927)
		(end 116.1415 -5.2578)
		(width 0.1016)
		(layer "B.Cu")
		(net "SMB_PCIE_SLOT3_ALERT_N")
	)
	(segment
		(start 128.4224 -8.8138)
		(end 128.4224 -8.0264)
		(width 0.1016)
		(layer "B.Cu")
		(net "SMB_PCIE_SLOT3_ALERT_N")
	)
	(segment
		(start 115.9764 -4.4069)
		(end 115.9764 -5.0927)
		(width 0.1016)
		(layer "B.Cu")
		(net "SMB_PCIE_SLOT3_ALERT_N")
	)
	(segment
		(start 108.93806 -0.92456)
		(end 111.252 -3.2385)
		(width 0.1016)
		(layer "B.Cu")
		(net "SMB_PCIE_SLOT3_ALERT_N")
	)
	(segment
		(start 116.1415 -5.90804)
		(end 116.1415 -5.2578)
		(width 0.1016)
		(layer "B.Cu")
		(net "SMB_PCIE_SLOT3_ALERT_N")
	)
	(segment
		(start 126.4158 -6.0198)
		(end 124.4854 -6.0198)
		(width 0.1016)
		(layer "B.Cu")
		(net "SMB_PCIE_SLOT3_ALERT_N")
	)
	(segment
		(start 114.0587 -15.3416)
		(end 117.578632 -11.821668)
		(width 0.1016)
		(layer "B.Cu")
		(net "SMB_PCIE_SLOT3_ALERT_N")
	)
	(segment
		(start 111.534448 -3.53568)
		(end 111.54918 -3.53568)
		(width 0.1016)
		(layer "B.Cu")
		(net "SMB_PCIE_SLOT3_ALERT_N")
	)
	(segment
		(start 124.4854 -6.0198)
		(end 124.230892 -5.765292)
		(width 0.1016)
		(layer "B.Cu")
		(net "SMB_PCIE_SLOT3_ALERT_N")
	)
	(segment
		(start 113.4491 -5.4356)
		(end 114.09426 -5.4356)
		(width 0.1016)
		(layer "B.Cu")
		(net "SMB_PCIE_SLOT3_ALERT_N")
	)
	(segment
		(start 128.4224 -8.0264)
		(end 126.4158 -6.0198)
		(width 0.1016)
		(layer "B.Cu")
		(net "SMB_PCIE_SLOT3_ALERT_N")
	)
	(segment
		(start 124.230892 -5.765292)
		(end 124.117608 -5.765292)
		(width 0.1016)
		(layer "B.Cu")
		(net "SMB_PCIE_SLOT3_ALERT_N")
	)
	(segment
		(start 110.4519 -17.8181)
		(end 110.4519 -18.412714)
		(width 0.1016)
		(layer "B.Cu")
		(net "SMB_PCIE_SLOT3_ALERT_N")
	)
	(segment
		(start 112.142524 -15.3416)
		(end 114.0587 -15.3416)
		(width 0.1016)
		(layer "B.Cu")
		(net "SMB_PCIE_SLOT3_ALERT_N")
	)
	(segment
		(start 111.252 -3.253232)
		(end 111.534448 -3.53568)
		(width 0.1016)
		(layer "B.Cu")
		(net "SMB_PCIE_SLOT3_ALERT_N")
	)
	(segment
		(start 106.8578 -0.92456)
		(end 108.93806 -0.92456)
		(width 0.1016)
		(layer "B.Cu")
		(net "SMB_PCIE_SLOT3_ALERT_N")
	)
	(segment
		(start 117.578632 -11.821668)
		(end 117.578632 -7.345172)
		(width 0.1016)
		(layer "B.Cu")
		(net "SMB_PCIE_SLOT3_ALERT_N")
	)
	(segment
		(start 117.578632 -7.345172)
		(end 116.1415 -5.90804)
		(width 0.1016)
		(layer "B.Cu")
		(net "SMB_PCIE_SLOT3_ALERT_N")
	)
	(segment
		(start 110.4519 -17.8181)
		(end 110.4519 -17.032224)
		(width 0.1016)
		(layer "B.Cu")
		(net "SMB_PCIE_SLOT3_ALERT_N")
	)
	(segment
		(start 114.09426 -5.4356)
		(end 115.54968 -3.98018)
		(width 0.1016)
		(layer "B.Cu")
		(net "SMB_PCIE_SLOT3_ALERT_N")
	)
	(segment
		(start 52.5526 -21.0312)
		(end 52.6034 -20.9804)
		(width 0.127)
		(layer "In3.Cu")
		(net "SMB_PCIE_SLOT3_ALERT_N")
	)
	(segment
		(start 56.1594 -19.939)
		(end 58.1279 -17.9705)
		(width 0.127)
		(layer "In3.Cu")
		(net "SMB_PCIE_SLOT3_ALERT_N")
	)
	(segment
		(start 122.0978 -6.0452)
		(end 123.8377 -6.0452)
		(width 0.127)
		(layer "In3.Cu")
		(net "SMB_PCIE_SLOT3_ALERT_N")
	)
	(segment
		(start 118.1735 -5.2832)
		(end 118.4656 -5.2832)
		(width 0.127)
		(layer "In3.Cu")
		(net "SMB_PCIE_SLOT3_ALERT_N")
	)
	(segment
		(start 116.1415 -4.7625)
		(end 116.58092 -4.32308)
		(width 0.127)
		(layer "In3.Cu")
		(net "SMB_PCIE_SLOT3_ALERT_N")
	)
	(segment
		(start 99.219766 -18.796)
		(end 110.835186 -18.796)
		(width 0.127)
		(layer "In3.Cu")
		(net "SMB_PCIE_SLOT3_ALERT_N")
	)
	(segment
		(start 52.6034 -20.9804)
		(end 53.680106 -20.9804)
		(width 0.127)
		(layer "In3.Cu")
		(net "SMB_PCIE_SLOT3_ALERT_N")
	)
	(segment
		(start 53.680106 -20.9804)
		(end 54.721506 -19.939)
		(width 0.127)
		(layer "In3.Cu")
		(net "SMB_PCIE_SLOT3_ALERT_N")
	)
	(segment
		(start 110.835186 -18.796)
		(end 111.1377 -19.098514)
		(width 0.127)
		(layer "In3.Cu")
		(net "SMB_PCIE_SLOT3_ALERT_N")
	)
	(segment
		(start 98.394266 -17.9705)
		(end 99.219766 -18.796)
		(width 0.127)
		(layer "In3.Cu")
		(net "SMB_PCIE_SLOT3_ALERT_N")
	)
	(segment
		(start 118.4656 -5.2832)
		(end 118.5926 -5.4102)
		(width 0.127)
		(layer "In3.Cu")
		(net "SMB_PCIE_SLOT3_ALERT_N")
	)
	(segment
		(start 116.1415 -5.2578)
		(end 116.1415 -4.7625)
		(width 0.127)
		(layer "In3.Cu")
		(net "SMB_PCIE_SLOT3_ALERT_N")
	)
	(segment
		(start 58.1279 -17.9705)
		(end 98.394266 -17.9705)
		(width 0.127)
		(layer "In3.Cu")
		(net "SMB_PCIE_SLOT3_ALERT_N")
	)
	(segment
		(start 117.21338 -4.32308)
		(end 118.1735 -5.2832)
		(width 0.127)
		(layer "In3.Cu")
		(net "SMB_PCIE_SLOT3_ALERT_N")
	)
	(segment
		(start 123.8377 -6.0452)
		(end 124.117608 -5.765292)
		(width 0.127)
		(layer "In3.Cu")
		(net "SMB_PCIE_SLOT3_ALERT_N")
	)
	(segment
		(start 116.58092 -4.32308)
		(end 117.21338 -4.32308)
		(width 0.127)
		(layer "In3.Cu")
		(net "SMB_PCIE_SLOT3_ALERT_N")
	)
	(segment
		(start 121.4628 -5.4102)
		(end 122.0978 -6.0452)
		(width 0.127)
		(layer "In3.Cu")
		(net "SMB_PCIE_SLOT3_ALERT_N")
	)
	(segment
		(start 54.721506 -19.939)
		(end 56.1594 -19.939)
		(width 0.127)
		(layer "In3.Cu")
		(net "SMB_PCIE_SLOT3_ALERT_N")
	)
	(segment
		(start 118.5926 -5.4102)
		(end 121.4628 -5.4102)
		(width 0.127)
		(layer "In3.Cu")
		(net "SMB_PCIE_SLOT3_ALERT_N")
	)
	(segment
		(start 54.8386 -15.9004)
		(end 53.9877 -15.9004)
		(width 0.1016)
		(layer "F.Cu")
		(net "SMB_PCIE_SLOT2_ALERT_N")
	)
	(via
		(at 111.529622 -18.328894)
		(size 0.508)
		(drill 0.254)
		(layers "F.Cu" "B.Cu")
		(net "SMB_PCIE_SLOT2_ALERT_N")
	)
	(via
		(at 54.8386 -15.9004)
		(size 0.508)
		(drill 0.254)
		(layers "F.Cu" "B.Cu")
		(net "SMB_PCIE_SLOT2_ALERT_N")
	)
	(via
		(at 123.19 -7.1374)
		(size 0.508)
		(drill 0.254)
		(layers "F.Cu" "B.Cu")
		(net "SMB_PCIE_SLOT2_ALERT_N")
	)
	(via
		(at 117.46484 -13.24356)
		(size 0.7112)
		(drill 0.3556)
		(layers "F.Cu" "B.Cu")
		(net "SMB_PCIE_SLOT2_ALERT_N")
	)
	(via
		(at 116.9162 -4.8514)
		(size 0.508)
		(drill 0.254)
		(layers "F.Cu" "B.Cu")
		(net "SMB_PCIE_SLOT2_ALERT_N")
	)
	(segment
		(start 111.5568 -3.12674)
		(end 111.66094 -3.23088)
		(width 0.1016)
		(layer "B.Cu")
		(net "SMB_PCIE_SLOT2_ALERT_N")
	)
	(segment
		(start 111.5568 -3.112008)
		(end 111.5568 -3.12674)
		(width 0.1016)
		(layer "B.Cu")
		(net "SMB_PCIE_SLOT2_ALERT_N")
	)
	(segment
		(start 109.064552 -0.61976)
		(end 111.5568 -3.112008)
		(width 0.1016)
		(layer "B.Cu")
		(net "SMB_PCIE_SLOT2_ALERT_N")
	)
	(segment
		(start 116.60124 -3.95224)
		(end 116.60124 -4.53644)
		(width 0.1016)
		(layer "B.Cu")
		(net "SMB_PCIE_SLOT2_ALERT_N")
	)
	(segment
		(start 107.39882 1.02616)
		(end 109.04474 -0.61976)
		(width 0.1016)
		(layer "B.Cu")
		(net "SMB_PCIE_SLOT2_ALERT_N")
	)
	(segment
		(start 112.269016 -15.6464)
		(end 111.501936 -16.41348)
		(width 0.1016)
		(layer "B.Cu")
		(net "SMB_PCIE_SLOT2_ALERT_N")
	)
	(segment
		(start 116.97716 -6.08076)
		(end 117.883432 -6.987032)
		(width 0.1016)
		(layer "B.Cu")
		(net "SMB_PCIE_SLOT2_ALERT_N")
	)
	(segment
		(start 117.883432 -12.824968)
		(end 117.46484 -13.24356)
		(width 0.1016)
		(layer "B.Cu")
		(net "SMB_PCIE_SLOT2_ALERT_N")
	)
	(segment
		(start 123.5202 -7.4676)
		(end 125.815344 -7.4676)
		(width 0.1016)
		(layer "B.Cu")
		(net "SMB_PCIE_SLOT2_ALERT_N")
	)
	(segment
		(start 123.19 -7.1374)
		(end 123.5202 -7.4676)
		(width 0.1016)
		(layer "B.Cu")
		(net "SMB_PCIE_SLOT2_ALERT_N")
	)
	(segment
		(start 114.0587 -3.23088)
		(end 114.73434 -2.55524)
		(width 0.1016)
		(layer "B.Cu")
		(net "SMB_PCIE_SLOT2_ALERT_N")
	)
	(segment
		(start 115.062 -15.6464)
		(end 112.269016 -15.6464)
		(width 0.1016)
		(layer "B.Cu")
		(net "SMB_PCIE_SLOT2_ALERT_N")
	)
	(segment
		(start 117.883432 -6.987032)
		(end 117.883432 -12.824968)
		(width 0.1016)
		(layer "B.Cu")
		(net "SMB_PCIE_SLOT2_ALERT_N")
	)
	(segment
		(start 116.05768 -2.79908)
		(end 116.05768 -3.40868)
		(width 0.1016)
		(layer "B.Cu")
		(net "SMB_PCIE_SLOT2_ALERT_N")
	)
	(segment
		(start 115.81384 -2.55524)
		(end 116.05768 -2.79908)
		(width 0.1016)
		(layer "B.Cu")
		(net "SMB_PCIE_SLOT2_ALERT_N")
	)
	(segment
		(start 116.9162 -4.8514)
		(end 116.9162 -5.0038)
		(width 0.1016)
		(layer "B.Cu")
		(net "SMB_PCIE_SLOT2_ALERT_N")
	)
	(segment
		(start 116.9162 -5.0038)
		(end 116.97716 -5.06476)
		(width 0.1016)
		(layer "B.Cu")
		(net "SMB_PCIE_SLOT2_ALERT_N")
	)
	(segment
		(start 116.05768 -3.40868)
		(end 116.60124 -3.95224)
		(width 0.1016)
		(layer "B.Cu")
		(net "SMB_PCIE_SLOT2_ALERT_N")
	)
	(segment
		(start 109.04474 -0.61976)
		(end 109.064552 -0.61976)
		(width 0.1016)
		(layer "B.Cu")
		(net "SMB_PCIE_SLOT2_ALERT_N")
	)
	(segment
		(start 116.60124 -4.53644)
		(end 116.9162 -4.8514)
		(width 0.1016)
		(layer "B.Cu")
		(net "SMB_PCIE_SLOT2_ALERT_N")
	)
	(segment
		(start 111.501936 -16.41348)
		(end 111.501936 -18.301208)
		(width 0.1016)
		(layer "B.Cu")
		(net "SMB_PCIE_SLOT2_ALERT_N")
	)
	(segment
		(start 111.501936 -18.301208)
		(end 111.529622 -18.328894)
		(width 0.1016)
		(layer "B.Cu")
		(net "SMB_PCIE_SLOT2_ALERT_N")
	)
	(segment
		(start 117.46484 -13.24356)
		(end 115.062 -15.6464)
		(width 0.1016)
		(layer "B.Cu")
		(net "SMB_PCIE_SLOT2_ALERT_N")
	)
	(segment
		(start 116.97716 -5.06476)
		(end 116.97716 -6.08076)
		(width 0.1016)
		(layer "B.Cu")
		(net "SMB_PCIE_SLOT2_ALERT_N")
	)
	(segment
		(start 114.73434 -2.55524)
		(end 115.81384 -2.55524)
		(width 0.1016)
		(layer "B.Cu")
		(net "SMB_PCIE_SLOT2_ALERT_N")
	)
	(segment
		(start 106.8578 1.02616)
		(end 107.39882 1.02616)
		(width 0.1016)
		(layer "B.Cu")
		(net "SMB_PCIE_SLOT2_ALERT_N")
	)
	(segment
		(start 125.815344 -7.4676)
		(end 126.47168 -8.123936)
		(width 0.1016)
		(layer "B.Cu")
		(net "SMB_PCIE_SLOT2_ALERT_N")
	)
	(segment
		(start 126.47168 -8.123936)
		(end 126.47168 -8.8138)
		(width 0.1016)
		(layer "B.Cu")
		(net "SMB_PCIE_SLOT2_ALERT_N")
	)
	(segment
		(start 111.66094 -3.23088)
		(end 114.0587 -3.23088)
		(width 0.1016)
		(layer "B.Cu")
		(net "SMB_PCIE_SLOT2_ALERT_N")
	)
	(segment
		(start 111.529622 -18.328894)
		(end 109.952028 -16.7513)
		(width 0.127)
		(layer "In3.Cu")
		(net "SMB_PCIE_SLOT2_ALERT_N")
	)
	(segment
		(start 118.729252 -5.740654)
		(end 118.729506 -5.7404)
		(width 0.127)
		(layer "In3.Cu")
		(net "SMB_PCIE_SLOT2_ALERT_N")
	)
	(segment
		(start 118.328694 -5.6134)
		(end 118.455948 -5.740654)
		(width 0.127)
		(layer "In3.Cu")
		(net "SMB_PCIE_SLOT2_ALERT_N")
	)
	(segment
		(start 121.2596 -5.7404)
		(end 122.6566 -7.1374)
		(width 0.127)
		(layer "In3.Cu")
		(net "SMB_PCIE_SLOT2_ALERT_N")
	)
	(segment
		(start 97.823782 -16.7513)
		(end 97.696782 -16.8783)
		(width 0.127)
		(layer "In3.Cu")
		(net "SMB_PCIE_SLOT2_ALERT_N")
	)
	(segment
		(start 116.9162 -4.8514)
		(end 116.9797 -4.9149)
		(width 0.127)
		(layer "In3.Cu")
		(net "SMB_PCIE_SLOT2_ALERT_N")
	)
	(segment
		(start 109.952028 -16.7513)
		(end 97.823782 -16.7513)
		(width 0.127)
		(layer "In3.Cu")
		(net "SMB_PCIE_SLOT2_ALERT_N")
	)
	(segment
		(start 67.3735 -16.8783)
		(end 66.7385 -16.2433)
		(width 0.127)
		(layer "In3.Cu")
		(net "SMB_PCIE_SLOT2_ALERT_N")
	)
	(segment
		(start 97.696782 -16.8783)
		(end 67.3735 -16.8783)
		(width 0.127)
		(layer "In3.Cu")
		(net "SMB_PCIE_SLOT2_ALERT_N")
	)
	(segment
		(start 118.729506 -5.7404)
		(end 121.2596 -5.7404)
		(width 0.127)
		(layer "In3.Cu")
		(net "SMB_PCIE_SLOT2_ALERT_N")
	)
	(segment
		(start 116.9797 -4.9149)
		(end 117.2083 -4.9149)
		(width 0.127)
		(layer "In3.Cu")
		(net "SMB_PCIE_SLOT2_ALERT_N")
	)
	(segment
		(start 55.1815 -16.2433)
		(end 54.8386 -15.9004)
		(width 0.127)
		(layer "In3.Cu")
		(net "SMB_PCIE_SLOT2_ALERT_N")
	)
	(segment
		(start 117.9068 -5.6134)
		(end 118.328694 -5.6134)
		(width 0.127)
		(layer "In3.Cu")
		(net "SMB_PCIE_SLOT2_ALERT_N")
	)
	(segment
		(start 118.455948 -5.740654)
		(end 118.729252 -5.740654)
		(width 0.127)
		(layer "In3.Cu")
		(net "SMB_PCIE_SLOT2_ALERT_N")
	)
	(segment
		(start 117.2083 -4.9149)
		(end 117.9068 -5.6134)
		(width 0.127)
		(layer "In3.Cu")
		(net "SMB_PCIE_SLOT2_ALERT_N")
	)
	(segment
		(start 66.7385 -16.2433)
		(end 55.1815 -16.2433)
		(width 0.127)
		(layer "In3.Cu")
		(net "SMB_PCIE_SLOT2_ALERT_N")
	)
	(segment
		(start 122.6566 -7.1374)
		(end 123.19 -7.1374)
		(width 0.127)
		(layer "In3.Cu")
		(net "SMB_PCIE_SLOT2_ALERT_N")
	)
	(segment
		(start 25.979882 12.133072)
		(end 25.979882 10.646918)
		(width 0.1016)
		(layer "F.Cu")
		(net "SMB_PCH_ALERT_R_N")
	)
	(segment
		(start 38.187884 4.756658)
		(end 38.207188 4.737354)
		(width 0.1016)
		(layer "F.Cu")
		(net "SMB_PCH_ALERT_R_N")
	)
	(segment
		(start 25.979882 10.646918)
		(end 27.2034 9.4234)
		(width 0.1016)
		(layer "F.Cu")
		(net "SMB_PCH_ALERT_R_N")
	)
	(segment
		(start 36.208716 4.2164)
		(end 36.642548 4.2164)
		(width 0.1016)
		(layer "F.Cu")
		(net "SMB_PCH_ALERT_R_N")
	)
	(segment
		(start 41.0083 3.5306)
		(end 42.799 1.7399)
		(width 0.1016)
		(layer "F.Cu")
		(net "SMB_PCH_ALERT_R_N")
	)
	(segment
		(start 39.915846 3.5306)
		(end 41.0083 3.5306)
		(width 0.1016)
		(layer "F.Cu")
		(net "SMB_PCH_ALERT_R_N")
	)
	(segment
		(start 35.240468 5.184648)
		(end 36.208716 4.2164)
		(width 0.1016)
		(layer "F.Cu")
		(net "SMB_PCH_ALERT_R_N")
	)
	(segment
		(start 37.182806 4.756658)
		(end 38.187884 4.756658)
		(width 0.1016)
		(layer "F.Cu")
		(net "SMB_PCH_ALERT_R_N")
	)
	(segment
		(start 36.642548 4.2164)
		(end 37.182806 4.756658)
		(width 0.1016)
		(layer "F.Cu")
		(net "SMB_PCH_ALERT_R_N")
	)
	(segment
		(start 38.536372 4.737354)
		(end 39.052246 4.393946)
		(width 0.1016)
		(layer "F.Cu")
		(net "SMB_PCH_ALERT_R_N")
	)
	(segment
		(start 39.661846 3.7846)
		(end 39.915846 3.5306)
		(width 0.1016)
		(layer "F.Cu")
		(net "SMB_PCH_ALERT_R_N")
	)
	(segment
		(start 27.2034 9.4234)
		(end 27.2034 8.954008)
		(width 0.1016)
		(layer "F.Cu")
		(net "SMB_PCH_ALERT_R_N")
	)
	(segment
		(start 42.799 -0.23876)
		(end 43.37558 -0.81534)
		(width 0.1016)
		(layer "F.Cu")
		(net "SMB_PCH_ALERT_R_N")
	)
	(segment
		(start 27.2034 8.954008)
		(end 29.261308 6.8961)
		(width 0.1016)
		(layer "F.Cu")
		(net "SMB_PCH_ALERT_R_N")
	)
	(segment
		(start 29.261308 6.8961)
		(end 33.529016 6.8961)
		(width 0.1016)
		(layer "F.Cu")
		(net "SMB_PCH_ALERT_R_N")
	)
	(segment
		(start 38.207188 4.737354)
		(end 38.536372 4.737354)
		(width 0.1016)
		(layer "F.Cu")
		(net "SMB_PCH_ALERT_R_N")
	)
	(segment
		(start 33.529016 6.8961)
		(end 35.240468 5.184648)
		(width 0.1016)
		(layer "F.Cu")
		(net "SMB_PCH_ALERT_R_N")
	)
	(segment
		(start 39.052246 4.393946)
		(end 39.661846 3.7846)
		(width 0.1016)
		(layer "F.Cu")
		(net "SMB_PCH_ALERT_R_N")
	)
	(segment
		(start 42.799 1.7399)
		(end 42.799 -0.23876)
		(width 0.1016)
		(layer "F.Cu")
		(net "SMB_PCH_ALERT_R_N")
	)
	(segment
		(start 43.37558 -0.81534)
		(end 43.688 -0.81534)
		(width 0.1016)
		(layer "F.Cu")
		(net "SMB_PCH_ALERT_R_N")
	)
	(via
		(at 35.240468 5.184648)
		(size 0.7112)
		(drill 0.3556)
		(layers "F.Cu" "B.Cu")
		(net "SMB_PCH_ALERT_R_N")
	)
	(segment
		(start 40.97274 0.48514)
		(end 41.8084 0.48514)
		(width 0.1016)
		(layer "F.Cu")
		(net "SMB_PCH_ALERT")
	)
	(segment
		(start 40.958008 0.470408)
		(end 40.97274 0.48514)
		(width 0.1016)
		(layer "F.Cu")
		(net "SMB_PCH_ALERT")
	)
	(segment
		(start 41.8084 -0.1651)
		(end 41.0972 -0.1651)
		(width 0.1016)
		(layer "F.Cu")
		(net "SMB_PCH_ALERT")
	)
	(segment
		(start 39.0652 1.9177)
		(end 40.1447 0.8382)
		(width 0.1016)
		(layer "F.Cu")
		(net "SMB_PCH_ALERT")
	)
	(segment
		(start 40.817292 0.470408)
		(end 40.958008 0.470408)
		(width 0.1016)
		(layer "F.Cu")
		(net "SMB_PCH_ALERT")
	)
	(segment
		(start 38.6842 1.9177)
		(end 39.0652 1.9177)
		(width 0.1016)
		(layer "F.Cu")
		(net "SMB_PCH_ALERT")
	)
	(segment
		(start 40.6781 0.6096)
		(end 40.817292 0.470408)
		(width 0.1016)
		(layer "F.Cu")
		(net "SMB_PCH_ALERT")
	)
	(segment
		(start 40.1447 0.6858)
		(end 40.2209 0.6096)
		(width 0.1016)
		(layer "F.Cu")
		(net "SMB_PCH_ALERT")
	)
	(segment
		(start 41.0972 -0.1651)
		(end 40.958008 -0.025908)
		(width 0.1016)
		(layer "F.Cu")
		(net "SMB_PCH_ALERT")
	)
	(segment
		(start 40.1447 0.8382)
		(end 40.1447 0.6858)
		(width 0.1016)
		(layer "F.Cu")
		(net "SMB_PCH_ALERT")
	)
	(segment
		(start 40.2209 0.6096)
		(end 40.6781 0.6096)
		(width 0.1016)
		(layer "F.Cu")
		(net "SMB_PCH_ALERT")
	)
	(segment
		(start 40.958008 -0.025908)
		(end 40.958008 0.470408)
		(width 0.1016)
		(layer "F.Cu")
		(net "SMB_PCH_ALERT")
	)
	(via
		(at 40.2209 0.6096)
		(size 0.7112)
		(drill 0.3556)
		(layers "F.Cu" "B.Cu")
		(net "SMB_PCH_ALERT")
	)
	(segment
		(start 28.829 -21.3106)
		(end 28.829 -20.1168)
		(width 0.1016)
		(layer "F.Cu")
		(net "SMB_BMC_DEVICE_ALERT_N")
	)
	(segment
		(start 27.335988 -19.812)
		(end 26.7462 -19.222212)
		(width 0.1016)
		(layer "F.Cu")
		(net "SMB_BMC_DEVICE_ALERT_N")
	)
	(segment
		(start 26.7462 -19.222212)
		(end 26.7462 -18.923)
		(width 0.1016)
		(layer "F.Cu")
		(net "SMB_BMC_DEVICE_ALERT_N")
	)
	(segment
		(start 26.7462 -18.923)
		(end 26.6954 -18.8722)
		(width 0.1016)
		(layer "F.Cu")
		(net "SMB_BMC_DEVICE_ALERT_N")
	)
	(segment
		(start 26.6954 -18.8722)
		(end 26.6954 -17.4879)
		(width 0.1016)
		(layer "F.Cu")
		(net "SMB_BMC_DEVICE_ALERT_N")
	)
	(segment
		(start 119.2276 -21.491448)
		(end 119.713248 -21.0058)
		(width 0.1016)
		(layer "F.Cu")
		(net "SMB_BMC_DEVICE_ALERT_N")
	)
	(segment
		(start 119.2276 -21.516848)
		(end 119.2276 -21.491448)
		(width 0.1016)
		(layer "F.Cu")
		(net "SMB_BMC_DEVICE_ALERT_N")
	)
	(segment
		(start 121.332752 -21.0058)
		(end 121.878852 -21.5519)
		(width 0.1016)
		(layer "F.Cu")
		(net "SMB_BMC_DEVICE_ALERT_N")
	)
	(segment
		(start 28.5242 -19.812)
		(end 27.335988 -19.812)
		(width 0.1016)
		(layer "F.Cu")
		(net "SMB_BMC_DEVICE_ALERT_N")
	)
	(segment
		(start 28.0924 -22.0472)
		(end 28.829 -21.3106)
		(width 0.1016)
		(layer "F.Cu")
		(net "SMB_BMC_DEVICE_ALERT_N")
	)
	(segment
		(start 118.900448 -21.844)
		(end 119.2276 -21.516848)
		(width 0.1016)
		(layer "F.Cu")
		(net "SMB_BMC_DEVICE_ALERT_N")
	)
	(segment
		(start 116.5098 -21.844)
		(end 118.900448 -21.844)
		(width 0.1016)
		(layer "F.Cu")
		(net "SMB_BMC_DEVICE_ALERT_N")
	)
	(segment
		(start 116.3066 -21.6408)
		(end 116.5098 -21.844)
		(width 0.1016)
		(layer "F.Cu")
		(net "SMB_BMC_DEVICE_ALERT_N")
	)
	(segment
		(start 26.6954 -17.4879)
		(end 26.2509 -17.0434)
		(width 0.1016)
		(layer "F.Cu")
		(net "SMB_BMC_DEVICE_ALERT_N")
	)
	(segment
		(start 121.878852 -21.5519)
		(end 123.3424 -21.5519)
		(width 0.1016)
		(layer "F.Cu")
		(net "SMB_BMC_DEVICE_ALERT_N")
	)
	(segment
		(start 28.829 -20.1168)
		(end 28.5242 -19.812)
		(width 0.1016)
		(layer "F.Cu")
		(net "SMB_BMC_DEVICE_ALERT_N")
	)
	(segment
		(start 119.713248 -21.0058)
		(end 121.332752 -21.0058)
		(width 0.1016)
		(layer "F.Cu")
		(net "SMB_BMC_DEVICE_ALERT_N")
	)
	(via
		(at 28.0924 -22.0472)
		(size 0.508)
		(drill 0.254)
		(layers "F.Cu" "B.Cu")
		(net "SMB_BMC_DEVICE_ALERT_N")
	)
	(via
		(at 115.3414 -18.7706)
		(size 0.7112)
		(drill 0.3556)
		(layers "F.Cu" "B.Cu")
		(net "SMB_BMC_DEVICE_ALERT_N")
	)
	(via
		(at 116.3066 -21.6408)
		(size 0.508)
		(drill 0.254)
		(layers "F.Cu" "B.Cu")
		(net "SMB_BMC_DEVICE_ALERT_N")
	)
	(segment
		(start 118.351046 -10.310114)
		(end 118.3513 -10.310368)
		(width 0.1016)
		(layer "B.Cu")
		(net "SMB_BMC_DEVICE_ALERT_N")
	)
	(segment
		(start 115.3414 -16.3449)
		(end 115.3414 -18.7706)
		(width 0.1016)
		(layer "B.Cu")
		(net "SMB_BMC_DEVICE_ALERT_N")
	)
	(segment
		(start 27.2923 -22.0472)
		(end 27.1653 -22.1742)
		(width 0.1016)
		(layer "B.Cu")
		(net "SMB_BMC_DEVICE_ALERT_N")
	)
	(segment
		(start 116.066316 -21.6408)
		(end 116.3066 -21.6408)
		(width 0.1016)
		(layer "B.Cu")
		(net "SMB_BMC_DEVICE_ALERT_N")
	)
	(segment
		(start 117.7925 -2.80162)
		(end 115.37188 -0.381)
		(width 0.1016)
		(layer "B.Cu")
		(net "SMB_BMC_DEVICE_ALERT_N")
	)
	(segment
		(start 115.3414 -20.915884)
		(end 116.066316 -21.6408)
		(width 0.1016)
		(layer "B.Cu")
		(net "SMB_BMC_DEVICE_ALERT_N")
	)
	(segment
		(start 27.2923 -21.0312)
		(end 27.2923 -22.0472)
		(width 0.1016)
		(layer "B.Cu")
		(net "SMB_BMC_DEVICE_ALERT_N")
	)
	(segment
		(start 113.60404 -0.92456)
		(end 112.4966 -0.92456)
		(width 0.1016)
		(layer "B.Cu")
		(net "SMB_BMC_DEVICE_ALERT_N")
	)
	(segment
		(start 114.1476 -0.381)
		(end 113.60404 -0.92456)
		(width 0.1016)
		(layer "B.Cu")
		(net "SMB_BMC_DEVICE_ALERT_N")
	)
	(segment
		(start 118.3513 -10.310368)
		(end 118.3513 -13.335)
		(width 0.1016)
		(layer "B.Cu")
		(net "SMB_BMC_DEVICE_ALERT_N")
	)
	(segment
		(start 118.351046 -9.510014)
		(end 118.351046 -10.310114)
		(width 0.1016)
		(layer "B.Cu")
		(net "SMB_BMC_DEVICE_ALERT_N")
	)
	(segment
		(start 118.3513 -13.335)
		(end 115.3414 -16.3449)
		(width 0.1016)
		(layer "B.Cu")
		(net "SMB_BMC_DEVICE_ALERT_N")
	)
	(segment
		(start 118.3513 -9.50976)
		(end 118.351046 -9.510014)
		(width 0.1016)
		(layer "B.Cu")
		(net "SMB_BMC_DEVICE_ALERT_N")
	)
	(segment
		(start 118.3513 -3.36042)
		(end 118.3513 -9.50976)
		(width 0.1016)
		(layer "B.Cu")
		(net "SMB_BMC_DEVICE_ALERT_N")
	)
	(segment
		(start 27.9654 -22.1742)
		(end 28.0924 -22.0472)
		(width 0.1016)
		(layer "B.Cu")
		(net "SMB_BMC_DEVICE_ALERT_N")
	)
	(segment
		(start 115.3414 -18.7706)
		(end 115.3414 -20.915884)
		(width 0.1016)
		(layer "B.Cu")
		(net "SMB_BMC_DEVICE_ALERT_N")
	)
	(segment
		(start 117.7925 -2.80162)
		(end 118.3513 -3.36042)
		(width 0.1016)
		(layer "B.Cu")
		(net "SMB_BMC_DEVICE_ALERT_N")
	)
	(segment
		(start 115.37188 -0.381)
		(end 114.1476 -0.381)
		(width 0.1016)
		(layer "B.Cu")
		(net "SMB_BMC_DEVICE_ALERT_N")
	)
	(segment
		(start 27.1653 -22.1742)
		(end 27.9654 -22.1742)
		(width 0.1016)
		(layer "B.Cu")
		(net "SMB_BMC_DEVICE_ALERT_N")
	)
	(segment
		(start 41.768268 -25.4)
		(end 52.854098 -25.4)
		(width 0.127)
		(layer "In3.Cu")
		(net "SMB_BMC_DEVICE_ALERT_N")
	)
	(segment
		(start 30.385766 -19.7104)
		(end 36.078668 -19.7104)
		(width 0.127)
		(layer "In3.Cu")
		(net "SMB_BMC_DEVICE_ALERT_N")
	)
	(segment
		(start 52.854098 -25.4)
		(end 57.768998 -20.4851)
		(width 0.127)
		(layer "In3.Cu")
		(net "SMB_BMC_DEVICE_ALERT_N")
	)
	(segment
		(start 110.307374 -20.4851)
		(end 111.463074 -21.6408)
		(width 0.127)
		(layer "In3.Cu")
		(net "SMB_BMC_DEVICE_ALERT_N")
	)
	(segment
		(start 28.0924 -22.0472)
		(end 28.0924 -22.003766)
		(width 0.127)
		(layer "In3.Cu")
		(net "SMB_BMC_DEVICE_ALERT_N")
	)
	(segment
		(start 36.078668 -19.7104)
		(end 41.768268 -25.4)
		(width 0.127)
		(layer "In3.Cu")
		(net "SMB_BMC_DEVICE_ALERT_N")
	)
	(segment
		(start 111.463074 -21.6408)
		(end 116.3066 -21.6408)
		(width 0.127)
		(layer "In3.Cu")
		(net "SMB_BMC_DEVICE_ALERT_N")
	)
	(segment
		(start 57.768998 -20.4851)
		(end 110.307374 -20.4851)
		(width 0.127)
		(layer "In3.Cu")
		(net "SMB_BMC_DEVICE_ALERT_N")
	)
	(segment
		(start 28.0924 -22.003766)
		(end 30.385766 -19.7104)
		(width 0.127)
		(layer "In3.Cu")
		(net "SMB_BMC_DEVICE_ALERT_N")
	)
	(segment
		(start 24.659336 -27.250136)
		(end 24.8158 -27.4066)
		(width 0.1016)
		(layer "F.Cu")
		(net "SMB_VMONITOR_SLOT3_ALERT_N")
	)
	(segment
		(start 23.801324 -27.250136)
		(end 24.659336 -27.250136)
		(width 0.1016)
		(layer "F.Cu")
		(net "SMB_VMONITOR_SLOT3_ALERT_N")
	)
	(via
		(at 25.4 -20.8534)
		(size 0.7112)
		(drill 0.3556)
		(layers "F.Cu" "B.Cu")
		(net "SMB_VMONITOR_SLOT3_ALERT_N")
	)
	(via
		(at 24.8158 -27.4066)
		(size 0.508)
		(drill 0.254)
		(layers "F.Cu" "B.Cu")
		(net "SMB_VMONITOR_SLOT3_ALERT_N")
	)
	(via
		(at 24.529034 -21.766784)
		(size 0.508)
		(drill 0.254)
		(layers "F.Cu" "B.Cu")
		(net "SMB_VMONITOR_SLOT3_ALERT_N")
	)
	(segment
		(start 24.8793 -21.3741)
		(end 24.8793 -21.3487)
		(width 0.1016)
		(layer "B.Cu")
		(net "SMB_VMONITOR_SLOT3_ALERT_N")
	)
	(segment
		(start 25.4 -20.8534)
		(end 26.2255 -20.8534)
		(width 0.1016)
		(layer "B.Cu")
		(net "SMB_VMONITOR_SLOT3_ALERT_N")
	)
	(segment
		(start 24.529034 -21.766784)
		(end 24.529034 -21.724366)
		(width 0.1016)
		(layer "B.Cu")
		(net "SMB_VMONITOR_SLOT3_ALERT_N")
	)
	(segment
		(start 25.3746 -20.8534)
		(end 25.4 -20.8534)
		(width 0.1016)
		(layer "B.Cu")
		(net "SMB_VMONITOR_SLOT3_ALERT_N")
	)
	(segment
		(start 24.529034 -21.724366)
		(end 24.8793 -21.3741)
		(width 0.1016)
		(layer "B.Cu")
		(net "SMB_VMONITOR_SLOT3_ALERT_N")
	)
	(segment
		(start 26.2255 -20.8534)
		(end 26.4033 -21.0312)
		(width 0.1016)
		(layer "B.Cu")
		(net "SMB_VMONITOR_SLOT3_ALERT_N")
	)
	(segment
		(start 24.8793 -21.3487)
		(end 25.3746 -20.8534)
		(width 0.1016)
		(layer "B.Cu")
		(net "SMB_VMONITOR_SLOT3_ALERT_N")
	)
	(segment
		(start 25.0063 -22.24405)
		(end 24.529034 -21.766784)
		(width 0.127)
		(layer "In2.Cu")
		(net "SMB_VMONITOR_SLOT3_ALERT_N")
	)
	(segment
		(start 25.0063 -27.2161)
		(end 25.0063 -22.24405)
		(width 0.127)
		(layer "In2.Cu")
		(net "SMB_VMONITOR_SLOT3_ALERT_N")
	)
	(segment
		(start 24.8158 -27.4066)
		(end 25.0063 -27.2161)
		(width 0.127)
		(layer "In2.Cu")
		(net "SMB_VMONITOR_SLOT3_ALERT_N")
	)
	(segment
		(start 25.3619 -16.2941)
		(end 25.0825 -16.0147)
		(width 0.1016)
		(layer "F.Cu")
		(net "SMB_VMONITOR_SLOT2_ALERT_N")
	)
	(segment
		(start 22.0472 -17.018)
		(end 21.814536 -17.250664)
		(width 0.1016)
		(layer "F.Cu")
		(net "SMB_VMONITOR_SLOT2_ALERT_N")
	)
	(segment
		(start 24.0792 -17.018)
		(end 22.0472 -17.018)
		(width 0.1016)
		(layer "F.Cu")
		(net "SMB_VMONITOR_SLOT2_ALERT_N")
	)
	(segment
		(start 25.0825 -16.0147)
		(end 24.0792 -17.018)
		(width 0.1016)
		(layer "F.Cu")
		(net "SMB_VMONITOR_SLOT2_ALERT_N")
	)
	(segment
		(start 25.3619 -17.0434)
		(end 25.3619 -16.2941)
		(width 0.1016)
		(layer "F.Cu")
		(net "SMB_VMONITOR_SLOT2_ALERT_N")
	)
	(segment
		(start 21.814536 -17.250664)
		(end 21.814536 -17.727676)
		(width 0.1016)
		(layer "F.Cu")
		(net "SMB_VMONITOR_SLOT2_ALERT_N")
	)
	(via
		(at 25.0825 -16.0147)
		(size 0.7112)
		(drill 0.3556)
		(layers "F.Cu" "B.Cu")
		(net "SMB_VMONITOR_SLOT2_ALERT_N")
	)
	(via
		(at 25.3492 -22.2758)
		(size 0.7112)
		(drill 0.3556)
		(layers "F.Cu" "B.Cu")
		(net "SMB_VMONITOR_ATX_ALERT_N")
	)
	(segment
		(start 23.801324 -23.651464)
		(end 24.456136 -23.651464)
		(width 0.1016)
		(layer "B.Cu")
		(net "SMB_VMONITOR_ATX_ALERT_N")
	)
	(segment
		(start 24.456136 -23.651464)
		(end 24.6888 -23.4188)
		(width 0.1016)
		(layer "B.Cu")
		(net "SMB_VMONITOR_ATX_ALERT_N")
	)
	(segment
		(start 24.6888 -23.4188)
		(end 24.6888 -22.9362)
		(width 0.1016)
		(layer "B.Cu")
		(net "SMB_VMONITOR_ATX_ALERT_N")
	)
	(segment
		(start 26.2763 -22.1742)
		(end 25.4508 -22.1742)
		(width 0.1016)
		(layer "B.Cu")
		(net "SMB_VMONITOR_ATX_ALERT_N")
	)
	(segment
		(start 24.6888 -22.9362)
		(end 25.3492 -22.2758)
		(width 0.1016)
		(layer "B.Cu")
		(net "SMB_VMONITOR_ATX_ALERT_N")
	)
	(segment
		(start 25.4508 -22.1742)
		(end 25.3492 -22.2758)
		(width 0.1016)
		(layer "B.Cu")
		(net "SMB_VMONITOR_ATX_ALERT_N")
	)
	(segment
		(start 44.9834 2.0447)
		(end 44.9834 1.8288)
		(width 0.1016)
		(layer "F.Cu")
		(net "SMB_PCH_ALERT_N")
	)
	(segment
		(start 44.9834 1.8288)
		(end 46.101 0.7112)
		(width 0.1016)
		(layer "F.Cu")
		(net "SMB_PCH_ALERT_N")
	)
	(segment
		(start 45.7962 -0.1651)
		(end 43.688 -0.1651)
		(width 0.1016)
		(layer "F.Cu")
		(net "SMB_PCH_ALERT_N")
	)
	(segment
		(start 46.101 0.1397)
		(end 45.7962 -0.1651)
		(width 0.1016)
		(layer "F.Cu")
		(net "SMB_PCH_ALERT_N")
	)
	(segment
		(start 46.101 0.7112)
		(end 46.101 0.1397)
		(width 0.1016)
		(layer "F.Cu")
		(net "SMB_PCH_ALERT_N")
	)
	(via
		(at 44.9834 2.0447)
		(size 0.508)
		(drill 0.254)
		(layers "F.Cu" "B.Cu")
		(net "SMB_PCH_ALERT_N")
	)
	(via
		(at 125.9586 -0.5461)
		(size 0.7112)
		(drill 0.3556)
		(layers "F.Cu" "B.Cu")
		(net "SMB_PCH_ALERT_N")
	)
	(via
		(at 122.936 0.381)
		(size 0.508)
		(drill 0.254)
		(layers "F.Cu" "B.Cu")
		(net "SMB_PCH_ALERT_N")
	)
	(segment
		(start 124.3838 -0.5461)
		(end 123.8631 -0.5461)
		(width 0.1016)
		(layer "B.Cu")
		(net "SMB_PCH_ALERT_N")
	)
	(segment
		(start 123.8631 -0.5461)
		(end 122.936 0.381)
		(width 0.1016)
		(layer "B.Cu")
		(net "SMB_PCH_ALERT_N")
	)
	(segment
		(start 126.238 -0.8255)
		(end 126.238 -2.254504)
		(width 0.1016)
		(layer "B.Cu")
		(net "SMB_PCH_ALERT_N")
	)
	(segment
		(start 126.238 -2.254504)
		(end 126.47168 -2.488184)
		(width 0.1016)
		(layer "B.Cu")
		(net "SMB_PCH_ALERT_N")
	)
	(segment
		(start 126.47168 -2.488184)
		(end 126.47168 -3.175)
		(width 0.1016)
		(layer "B.Cu")
		(net "SMB_PCH_ALERT_N")
	)
	(segment
		(start 125.9586 -0.5461)
		(end 125.9332 -0.5207)
		(width 0.1016)
		(layer "B.Cu")
		(net "SMB_PCH_ALERT_N")
	)
	(segment
		(start 125.9586 -0.5461)
		(end 126.238 -0.8255)
		(width 0.1016)
		(layer "B.Cu")
		(net "SMB_PCH_ALERT_N")
	)
	(segment
		(start 124.9299 -0.5461)
		(end 124.3838 -0.5461)
		(width 0.1016)
		(layer "B.Cu")
		(net "SMB_PCH_ALERT_N")
	)
	(segment
		(start 124.9553 -0.5207)
		(end 124.9299 -0.5461)
		(width 0.1016)
		(layer "B.Cu")
		(net "SMB_PCH_ALERT_N")
	)
	(segment
		(start 125.9332 -0.5207)
		(end 124.9553 -0.5207)
		(width 0.1016)
		(layer "B.Cu")
		(net "SMB_PCH_ALERT_N")
	)
	(segment
		(start 98.845624 2.600452)
		(end 99.61753 3.372358)
		(width 0.127)
		(layer "In3.Cu")
		(net "SMB_PCH_ALERT_N")
	)
	(segment
		(start 120.6754 2.6416)
		(end 122.936 0.381)
		(width 0.127)
		(layer "In3.Cu")
		(net "SMB_PCH_ALERT_N")
	)
	(segment
		(start 44.9834 2.0447)
		(end 44.9834 2.380996)
		(width 0.127)
		(layer "In3.Cu")
		(net "SMB_PCH_ALERT_N")
	)
	(segment
		(start 99.61753 3.372358)
		(end 111.080042 3.372358)
		(width 0.127)
		(layer "In3.Cu")
		(net "SMB_PCH_ALERT_N")
	)
	(segment
		(start 111.8108 2.6416)
		(end 120.6754 2.6416)
		(width 0.127)
		(layer "In3.Cu")
		(net "SMB_PCH_ALERT_N")
	)
	(segment
		(start 111.080042 3.372358)
		(end 111.8108 2.6416)
		(width 0.127)
		(layer "In3.Cu")
		(net "SMB_PCH_ALERT_N")
	)
	(segment
		(start 45.202856 2.600452)
		(end 98.845624 2.600452)
		(width 0.127)
		(layer "In3.Cu")
		(net "SMB_PCH_ALERT_N")
	)
	(segment
		(start 44.9834 2.380996)
		(end 45.202856 2.600452)
		(width 0.127)
		(layer "In3.Cu")
		(net "SMB_PCH_ALERT_N")
	)
	(via
		(at 125.0442 -19.3675)
		(size 0.7112)
		(drill 0.3556)
		(layers "F.Cu" "B.Cu")
		(net "SMDAT_USB_HUB")
	)
	(via
		(at 129.035302 -23.746968)
		(size 0.508)
		(drill 0.254)
		(layers "F.Cu" "B.Cu")
		(net "SMDAT_USB_HUB")
	)
	(via
		(at 119.2784 -24.003)
		(size 0.508)
		(drill 0.254)
		(layers "F.Cu" "B.Cu")
		(net "SMDAT_USB_HUB")
	)
	(via
		(at 124.740924 -18.416524)
		(size 0.508)
		(drill 0.254)
		(layers "F.Cu" "B.Cu")
		(net "SMDAT_USB_HUB")
	)
	(segment
		(start 129.032 -24.5491)
		(end 129.032 -23.75027)
		(width 0.1016)
		(layer "B.Cu")
		(net "SMDAT_USB_HUB")
	)
	(segment
		(start 124.740924 -18.416524)
		(end 124.8664 -18.291048)
		(width 0.1016)
		(layer "B.Cu")
		(net "SMDAT_USB_HUB")
	)
	(segment
		(start 119.6594 -23.2283)
		(end 119.6594 -23.622)
		(width 0.1016)
		(layer "B.Cu")
		(net "SMDAT_USB_HUB")
	)
	(segment
		(start 129.2352 -23.54707)
		(end 129.035302 -23.746968)
		(width 0.1016)
		(layer "B.Cu")
		(net "SMDAT_USB_HUB")
	)
	(segment
		(start 125.865636 -15.60068)
		(end 126.59106 -15.60068)
		(width 0.1016)
		(layer "B.Cu")
		(net "SMDAT_USB_HUB")
	)
	(segment
		(start 125.0442 -18.7198)
		(end 124.740924 -18.416524)
		(width 0.1016)
		(layer "B.Cu")
		(net "SMDAT_USB_HUB")
	)
	(segment
		(start 124.8664 -18.291048)
		(end 124.8664 -16.599916)
		(width 0.1016)
		(layer "B.Cu")
		(net "SMDAT_USB_HUB")
	)
	(segment
		(start 119.6594 -23.622)
		(end 119.2784 -24.003)
		(width 0.1016)
		(layer "B.Cu")
		(net "SMDAT_USB_HUB")
	)
	(segment
		(start 129.2352 -22.8473)
		(end 129.2352 -23.54707)
		(width 0.1016)
		(layer "B.Cu")
		(net "SMDAT_USB_HUB")
	)
	(segment
		(start 129.032 -23.75027)
		(end 129.035302 -23.746968)
		(width 0.1016)
		(layer "B.Cu")
		(net "SMDAT_USB_HUB")
	)
	(segment
		(start 125.0442 -19.3675)
		(end 125.0442 -18.7198)
		(width 0.1016)
		(layer "B.Cu")
		(net "SMDAT_USB_HUB")
	)
	(segment
		(start 124.8664 -16.599916)
		(end 125.865636 -15.60068)
		(width 0.1016)
		(layer "B.Cu")
		(net "SMDAT_USB_HUB")
	)
	(segment
		(start 126.713234 -22.606)
		(end 127.894334 -22.606)
		(width 0.127)
		(layer "In2.Cu")
		(net "SMDAT_USB_HUB")
	)
	(segment
		(start 127.894334 -22.606)
		(end 129.035302 -23.746968)
		(width 0.127)
		(layer "In2.Cu")
		(net "SMDAT_USB_HUB")
	)
	(segment
		(start 124.9426 -18.6182)
		(end 124.9426 -20.835366)
		(width 0.127)
		(layer "In2.Cu")
		(net "SMDAT_USB_HUB")
	)
	(segment
		(start 124.9426 -20.835366)
		(end 126.713234 -22.606)
		(width 0.127)
		(layer "In2.Cu")
		(net "SMDAT_USB_HUB")
	)
	(segment
		(start 124.740924 -18.416524)
		(end 124.9426 -18.6182)
		(width 0.127)
		(layer "In2.Cu")
		(net "SMDAT_USB_HUB")
	)
	(segment
		(start 123.242832 -21.2725)
		(end 126.560834 -21.2725)
		(width 0.127)
		(layer "In3.Cu")
		(net "SMDAT_USB_HUB")
	)
	(segment
		(start 119.9134 -23.4188)
		(end 121.096532 -23.4188)
		(width 0.127)
		(layer "In3.Cu")
		(net "SMDAT_USB_HUB")
	)
	(segment
		(start 126.560834 -21.2725)
		(end 129.035302 -23.746968)
		(width 0.127)
		(layer "In3.Cu")
		(net "SMDAT_USB_HUB")
	)
	(segment
		(start 119.2784 -24.003)
		(end 119.3292 -24.003)
		(width 0.127)
		(layer "In3.Cu")
		(net "SMDAT_USB_HUB")
	)
	(segment
		(start 121.096532 -23.4188)
		(end 123.242832 -21.2725)
		(width 0.127)
		(layer "In3.Cu")
		(net "SMDAT_USB_HUB")
	)
	(segment
		(start 119.3292 -24.003)
		(end 119.9134 -23.4188)
		(width 0.127)
		(layer "In3.Cu")
		(net "SMDAT_USB_HUB")
	)
	(segment
		(start 38.080442 -31.706058)
		(end 38.080442 -34.070036)
		(width 0.1016)
		(layer "F.Cu")
		(net "SMDAT_PCH_SLOT3_R")
	)
	(segment
		(start 35.1536 -24.5872)
		(end 37.2872 -26.7208)
		(width 0.1016)
		(layer "F.Cu")
		(net "SMDAT_PCH_SLOT3_R")
	)
	(segment
		(start 38.2905 -31.496)
		(end 38.080442 -31.706058)
		(width 0.1016)
		(layer "F.Cu")
		(net "SMDAT_PCH_SLOT3_R")
	)
	(segment
		(start 33.44164 -24.53132)
		(end 33.49752 -24.5872)
		(width 0.1016)
		(layer "F.Cu")
		(net "SMDAT_PCH_SLOT3_R")
	)
	(segment
		(start 37.2872 -26.7208)
		(end 37.2872 -27.813)
		(width 0.1016)
		(layer "F.Cu")
		(net "SMDAT_PCH_SLOT3_R")
	)
	(segment
		(start 38.2905 -28.8163)
		(end 38.2905 -31.496)
		(width 0.1016)
		(layer "F.Cu")
		(net "SMDAT_PCH_SLOT3_R")
	)
	(segment
		(start 37.2872 -27.813)
		(end 38.2905 -28.8163)
		(width 0.1016)
		(layer "F.Cu")
		(net "SMDAT_PCH_SLOT3_R")
	)
	(segment
		(start 33.49752 -24.5872)
		(end 35.1536 -24.5872)
		(width 0.1016)
		(layer "F.Cu")
		(net "SMDAT_PCH_SLOT3_R")
	)
	(segment
		(start 31.2928 -21.6916)
		(end 32.004 -21.6916)
		(width 0.1016)
		(layer "F.Cu")
		(net "SMDAT_PCH_SLOT3")
	)
	(segment
		(start 33.44164 -23.12924)
		(end 33.44164 -23.64232)
		(width 0.1016)
		(layer "F.Cu")
		(net "SMDAT_PCH_SLOT3")
	)
	(segment
		(start 32.004 -21.6916)
		(end 33.44164 -23.12924)
		(width 0.1016)
		(layer "F.Cu")
		(net "SMDAT_PCH_SLOT3")
	)
	(via
		(at 31.2928 -21.6916)
		(size 0.508)
		(drill 0.254)
		(layers "F.Cu" "B.Cu")
		(net "SMDAT_PCH_SLOT3")
	)
	(via
		(at 129.210054 -12.014708)
		(size 0.508)
		(drill 0.254)
		(layers "F.Cu" "B.Cu")
		(net "SMDAT_PCH_SLOT3")
	)
	(via
		(at 130.6068 -12.8524)
		(size 0.7112)
		(drill 0.3556)
		(layers "F.Cu" "B.Cu")
		(net "SMDAT_PCH_SLOT3")
	)
	(segment
		(start 129.07264 -8.8138)
		(end 129.07264 -10.25906)
		(width 0.1016)
		(layer "B.Cu")
		(net "SMDAT_PCH_SLOT3")
	)
	(segment
		(start 129.1844 -10.7315)
		(end 128.8923 -10.4394)
		(width 0.1016)
		(layer "B.Cu")
		(net "SMDAT_PCH_SLOT3")
	)
	(segment
		(start 129.210054 -12.014708)
		(end 129.210054 -12.001754)
		(width 0.1016)
		(layer "B.Cu")
		(net "SMDAT_PCH_SLOT3")
	)
	(segment
		(start 129.1844 -11.9761)
		(end 129.1844 -10.7315)
		(width 0.1016)
		(layer "B.Cu")
		(net "SMDAT_PCH_SLOT3")
	)
	(segment
		(start 130.302 -12.8524)
		(end 129.464308 -12.014708)
		(width 0.1016)
		(layer "B.Cu")
		(net "SMDAT_PCH_SLOT3")
	)
	(segment
		(start 129.210054 -12.001754)
		(end 129.1844 -11.9761)
		(width 0.1016)
		(layer "B.Cu")
		(net "SMDAT_PCH_SLOT3")
	)
	(segment
		(start 129.07264 -10.25906)
		(end 128.8923 -10.4394)
		(width 0.1016)
		(layer "B.Cu")
		(net "SMDAT_PCH_SLOT3")
	)
	(segment
		(start 129.464308 -12.014708)
		(end 129.210054 -12.014708)
		(width 0.1016)
		(layer "B.Cu")
		(net "SMDAT_PCH_SLOT3")
	)
	(segment
		(start 130.6068 -12.8524)
		(end 130.302 -12.8524)
		(width 0.1016)
		(layer "B.Cu")
		(net "SMDAT_PCH_SLOT3")
	)
	(segment
		(start 57.979564 -20.9931)
		(end 53.064664 -25.908)
		(width 0.127)
		(layer "In3.Cu")
		(net "SMDAT_PCH_SLOT3")
	)
	(segment
		(start 121.982992 -19.791172)
		(end 121.982992 -21.095208)
		(width 0.127)
		(layer "In3.Cu")
		(net "SMDAT_PCH_SLOT3")
	)
	(segment
		(start 111.506508 -22.4028)
		(end 110.096808 -20.9931)
		(width 0.127)
		(layer "In3.Cu")
		(net "SMDAT_PCH_SLOT3")
	)
	(segment
		(start 36.2458 -25.908)
		(end 31.8262 -21.4884)
		(width 0.127)
		(layer "In3.Cu")
		(net "SMDAT_PCH_SLOT3")
	)
	(segment
		(start 129.875534 -12.5095)
		(end 130.344418 -12.5095)
		(width 0.127)
		(layer "In3.Cu")
		(net "SMDAT_PCH_SLOT3")
	)
	(segment
		(start 130.344418 -12.5095)
		(end 130.6195 -12.784582)
		(width 0.127)
		(layer "In3.Cu")
		(net "SMDAT_PCH_SLOT3")
	)
	(segment
		(start 129.210054 -12.014708)
		(end 129.380742 -12.014708)
		(width 0.127)
		(layer "In3.Cu")
		(net "SMDAT_PCH_SLOT3")
	)
	(segment
		(start 31.8262 -21.4884)
		(end 31.496 -21.4884)
		(width 0.127)
		(layer "In3.Cu")
		(net "SMDAT_PCH_SLOT3")
	)
	(segment
		(start 124.667264 -17.1069)
		(end 121.982992 -19.791172)
		(width 0.127)
		(layer "In3.Cu")
		(net "SMDAT_PCH_SLOT3")
	)
	(segment
		(start 130.6195 -15.5829)
		(end 129.0955 -17.1069)
		(width 0.127)
		(layer "In3.Cu")
		(net "SMDAT_PCH_SLOT3")
	)
	(segment
		(start 110.096808 -20.9931)
		(end 57.979564 -20.9931)
		(width 0.127)
		(layer "In3.Cu")
		(net "SMDAT_PCH_SLOT3")
	)
	(segment
		(start 31.496 -21.4884)
		(end 31.2928 -21.6916)
		(width 0.127)
		(layer "In3.Cu")
		(net "SMDAT_PCH_SLOT3")
	)
	(segment
		(start 129.0955 -17.1069)
		(end 124.667264 -17.1069)
		(width 0.127)
		(layer "In3.Cu")
		(net "SMDAT_PCH_SLOT3")
	)
	(segment
		(start 120.6754 -22.4028)
		(end 111.506508 -22.4028)
		(width 0.127)
		(layer "In3.Cu")
		(net "SMDAT_PCH_SLOT3")
	)
	(segment
		(start 121.982992 -21.095208)
		(end 120.6754 -22.4028)
		(width 0.127)
		(layer "In3.Cu")
		(net "SMDAT_PCH_SLOT3")
	)
	(segment
		(start 129.380742 -12.014708)
		(end 129.875534 -12.5095)
		(width 0.127)
		(layer "In3.Cu")
		(net "SMDAT_PCH_SLOT3")
	)
	(segment
		(start 130.6195 -12.784582)
		(end 130.6195 -15.5829)
		(width 0.127)
		(layer "In3.Cu")
		(net "SMDAT_PCH_SLOT3")
	)
	(segment
		(start 53.064664 -25.908)
		(end 36.2458 -25.908)
		(width 0.127)
		(layer "In3.Cu")
		(net "SMDAT_PCH_SLOT3")
	)
	(via
		(at 44.1706 -3.683)
		(size 0.7112)
		(drill 0.3556)
		(layers "F.Cu" "B.Cu")
		(net "SMDAT_PCH_SLOT2_R")
	)
	(segment
		(start 38.2778 -13.552678)
		(end 38.080442 -13.750036)
		(width 0.1016)
		(layer "B.Cu")
		(net "SMDAT_PCH_SLOT2_R")
	)
	(segment
		(start 41.2877 -5.7277)
		(end 40.161972 -5.7277)
		(width 0.1016)
		(layer "B.Cu")
		(net "SMDAT_PCH_SLOT2_R")
	)
	(segment
		(start 44.069 -2.4638)
		(end 44.069 -3.5814)
		(width 0.1016)
		(layer "B.Cu")
		(net "SMDAT_PCH_SLOT2_R")
	)
	(segment
		(start 39.2938 -7.9248)
		(end 38.2778 -8.9408)
		(width 0.1016)
		(layer "B.Cu")
		(net "SMDAT_PCH_SLOT2_R")
	)
	(segment
		(start 43.8404 -4.3688)
		(end 42.6466 -4.3688)
		(width 0.1016)
		(layer "B.Cu")
		(net "SMDAT_PCH_SLOT2_R")
	)
	(segment
		(start 44.1706 -4.0386)
		(end 43.8404 -4.3688)
		(width 0.1016)
		(layer "B.Cu")
		(net "SMDAT_PCH_SLOT2_R")
	)
	(segment
		(start 42.6466 -4.3688)
		(end 41.2877 -5.7277)
		(width 0.1016)
		(layer "B.Cu")
		(net "SMDAT_PCH_SLOT2_R")
	)
	(segment
		(start 44.069 -3.5814)
		(end 44.1706 -3.683)
		(width 0.1016)
		(layer "B.Cu")
		(net "SMDAT_PCH_SLOT2_R")
	)
	(segment
		(start 43.9674 -2.3622)
		(end 44.069 -2.4638)
		(width 0.1016)
		(layer "B.Cu")
		(net "SMDAT_PCH_SLOT2_R")
	)
	(segment
		(start 38.2778 -8.9408)
		(end 38.2778 -13.552678)
		(width 0.1016)
		(layer "B.Cu")
		(net "SMDAT_PCH_SLOT2_R")
	)
	(segment
		(start 40.161972 -5.7277)
		(end 39.2938 -6.595872)
		(width 0.1016)
		(layer "B.Cu")
		(net "SMDAT_PCH_SLOT2_R")
	)
	(segment
		(start 39.2938 -6.595872)
		(end 39.2938 -7.9248)
		(width 0.1016)
		(layer "B.Cu")
		(net "SMDAT_PCH_SLOT2_R")
	)
	(segment
		(start 44.1706 -3.683)
		(end 44.1706 -4.0386)
		(width 0.1016)
		(layer "B.Cu")
		(net "SMDAT_PCH_SLOT2_R")
	)
	(via
		(at 119.7864 -4.0894)
		(size 0.508)
		(drill 0.254)
		(layers "F.Cu" "B.Cu")
		(net "SMDAT_PCH_SLOT2")
	)
	(via
		(at 46.4566 -3.8608)
		(size 0.508)
		(drill 0.254)
		(layers "F.Cu" "B.Cu")
		(net "SMDAT_PCH_SLOT2")
	)
	(via
		(at 122.174 -6.0071)
		(size 0.7112)
		(drill 0.3556)
		(layers "F.Cu" "B.Cu")
		(net "SMDAT_PCH_SLOT2")
	)
	(segment
		(start 121.36628 -4.37388)
		(end 121.0818 -4.0894)
		(width 0.1016)
		(layer "B.Cu")
		(net "SMDAT_PCH_SLOT2")
	)
	(segment
		(start 46.3423 -3.7465)
		(end 46.4566 -3.8608)
		(width 0.1016)
		(layer "B.Cu")
		(net "SMDAT_PCH_SLOT2")
	)
	(segment
		(start 46.3423 -3.4036)
		(end 46.3423 -3.7465)
		(width 0.1016)
		(layer "B.Cu")
		(net "SMDAT_PCH_SLOT2")
	)
	(segment
		(start 123.8758 -6.985)
		(end 126.015496 -6.985)
		(width 0.1016)
		(layer "B.Cu")
		(net "SMDAT_PCH_SLOT2")
	)
	(segment
		(start 126.015496 -6.985)
		(end 127.12192 -8.091424)
		(width 0.1016)
		(layer "B.Cu")
		(net "SMDAT_PCH_SLOT2")
	)
	(segment
		(start 123.29795 -6.40715)
		(end 123.8758 -6.985)
		(width 0.1016)
		(layer "B.Cu")
		(net "SMDAT_PCH_SLOT2")
	)
	(segment
		(start 44.8564 -2.3622)
		(end 45.3009 -2.3622)
		(width 0.1016)
		(layer "B.Cu")
		(net "SMDAT_PCH_SLOT2")
	)
	(segment
		(start 121.36628 -4.68122)
		(end 121.36628 -4.37388)
		(width 0.1016)
		(layer "B.Cu")
		(net "SMDAT_PCH_SLOT2")
	)
	(segment
		(start 121.0818 -4.0894)
		(end 119.7864 -4.0894)
		(width 0.1016)
		(layer "B.Cu")
		(net "SMDAT_PCH_SLOT2")
	)
	(segment
		(start 121.36628 -5.19938)
		(end 122.174 -6.0071)
		(width 0.1016)
		(layer "B.Cu")
		(net "SMDAT_PCH_SLOT2")
	)
	(segment
		(start 45.3009 -2.3622)
		(end 46.3423 -3.4036)
		(width 0.1016)
		(layer "B.Cu")
		(net "SMDAT_PCH_SLOT2")
	)
	(segment
		(start 127.12192 -8.091424)
		(end 127.12192 -8.8138)
		(width 0.1016)
		(layer "B.Cu")
		(net "SMDAT_PCH_SLOT2")
	)
	(segment
		(start 122.57405 -6.40715)
		(end 123.29795 -6.40715)
		(width 0.1016)
		(layer "B.Cu")
		(net "SMDAT_PCH_SLOT2")
	)
	(segment
		(start 121.36628 -4.68122)
		(end 121.36628 -5.19938)
		(width 0.1016)
		(layer "B.Cu")
		(net "SMDAT_PCH_SLOT2")
	)
	(segment
		(start 122.174 -6.0071)
		(end 122.57405 -6.40715)
		(width 0.1016)
		(layer "B.Cu")
		(net "SMDAT_PCH_SLOT2")
	)
	(segment
		(start 48.0568 -3.6449)
		(end 48.5394 -3.1623)
		(width 0.127)
		(layer "In3.Cu")
		(net "SMDAT_PCH_SLOT2")
	)
	(segment
		(start 48.5394 -3.1623)
		(end 55.2958 -3.1623)
		(width 0.127)
		(layer "In3.Cu")
		(net "SMDAT_PCH_SLOT2")
	)
	(segment
		(start 46.6725 -3.6449)
		(end 48.0568 -3.6449)
		(width 0.127)
		(layer "In3.Cu")
		(net "SMDAT_PCH_SLOT2")
	)
	(segment
		(start 119.3419 -3.6449)
		(end 119.7864 -4.0894)
		(width 0.127)
		(layer "In3.Cu")
		(net "SMDAT_PCH_SLOT2")
	)
	(segment
		(start 55.7784 -3.6449)
		(end 119.3419 -3.6449)
		(width 0.127)
		(layer "In3.Cu")
		(net "SMDAT_PCH_SLOT2")
	)
	(segment
		(start 46.4566 -3.8608)
		(end 46.6725 -3.6449)
		(width 0.127)
		(layer "In3.Cu")
		(net "SMDAT_PCH_SLOT2")
	)
	(segment
		(start 55.2958 -3.1623)
		(end 55.7784 -3.6449)
		(width 0.127)
		(layer "In3.Cu")
		(net "SMDAT_PCH_SLOT2")
	)
	(via
		(at 37.4269 -0.508)
		(size 0.508)
		(drill 0.254)
		(layers "F.Cu" "B.Cu")
		(net "SMDAT_PCH_R")
	)
	(via
		(at 43.3832 2.7432)
		(size 0.508)
		(drill 0.254)
		(layers "F.Cu" "B.Cu")
		(net "SMDAT_PCH_R")
	)
	(via
		(at 122.7836 -1.5621)
		(size 0.7112)
		(drill 0.3556)
		(layers "F.Cu" "B.Cu")
		(net "SMDAT_PCH_R")
	)
	(via
		(at 121.9454 -1.0668)
		(size 0.508)
		(drill 0.254)
		(layers "F.Cu" "B.Cu")
		(net "SMDAT_PCH_R")
	)
	(segment
		(start 125.1712 -3.175)
		(end 125.1712 -2.4892)
		(width 0.1016)
		(layer "B.Cu")
		(net "SMDAT_PCH_R")
	)
	(segment
		(start 122.2883 -1.0668)
		(end 122.7836 -1.5621)
		(width 0.1016)
		(layer "B.Cu")
		(net "SMDAT_PCH_R")
	)
	(segment
		(start 121.9454 -1.0668)
		(end 122.2883 -1.0668)
		(width 0.1016)
		(layer "B.Cu")
		(net "SMDAT_PCH_R")
	)
	(segment
		(start 37.6809 0.4699)
		(end 37.6809 0.866648)
		(width 0.1016)
		(layer "B.Cu")
		(net "SMDAT_PCH_R")
	)
	(segment
		(start 37.5158 0.3048)
		(end 37.6809 0.4699)
		(width 0.1016)
		(layer "B.Cu")
		(net "SMDAT_PCH_R")
	)
	(segment
		(start 122.9487 -1.7272)
		(end 122.7836 -1.5621)
		(width 0.1016)
		(layer "B.Cu")
		(net "SMDAT_PCH_R")
	)
	(segment
		(start 125.1712 -2.4892)
		(end 124.4092 -1.7272)
		(width 0.1016)
		(layer "B.Cu")
		(net "SMDAT_PCH_R")
	)
	(segment
		(start 37.6809 0.866648)
		(end 37.8206 1.006348)
		(width 0.1016)
		(layer "B.Cu")
		(net "SMDAT_PCH_R")
	)
	(segment
		(start 37.4269 0.2159)
		(end 37.5158 0.3048)
		(width 0.1016)
		(layer "B.Cu")
		(net "SMDAT_PCH_R")
	)
	(segment
		(start 37.8206 2.0447)
		(end 36.64458 3.22072)
		(width 0.1016)
		(layer "B.Cu")
		(net "SMDAT_PCH_R")
	)
	(segment
		(start 37.4269 -0.508)
		(end 37.4269 0.2159)
		(width 0.1016)
		(layer "B.Cu")
		(net "SMDAT_PCH_R")
	)
	(segment
		(start 37.8206 1.006348)
		(end 37.8206 2.0447)
		(width 0.1016)
		(layer "B.Cu")
		(net "SMDAT_PCH_R")
	)
	(segment
		(start 43.1038 3.0226)
		(end 43.3832 2.7432)
		(width 0.1016)
		(layer "B.Cu")
		(net "SMDAT_PCH_R")
	)
	(segment
		(start 124.4092 -1.7272)
		(end 122.9487 -1.7272)
		(width 0.1016)
		(layer "B.Cu")
		(net "SMDAT_PCH_R")
	)
	(segment
		(start 36.64458 3.22072)
		(end 35.09264 3.22072)
		(width 0.1016)
		(layer "B.Cu")
		(net "SMDAT_PCH_R")
	)
	(segment
		(start 42.164 3.0226)
		(end 43.1038 3.0226)
		(width 0.1016)
		(layer "B.Cu")
		(net "SMDAT_PCH_R")
	)
	(segment
		(start 40.309292 3.1496)
		(end 37.4777 0.318008)
		(width 0.127)
		(layer "In3.Cu")
		(net "SMDAT_PCH_R")
	)
	(segment
		(start 43.3832 2.7432)
		(end 42.424604 1.784604)
		(width 0.127)
		(layer "In3.Cu")
		(net "SMDAT_PCH_R")
	)
	(segment
		(start 37.4777 0.318008)
		(end 37.4777 -0.4572)
		(width 0.127)
		(layer "In3.Cu")
		(net "SMDAT_PCH_R")
	)
	(segment
		(start 42.424604 1.784604)
		(end 42.424604 0.886968)
		(width 0.127)
		(layer "In3.Cu")
		(net "SMDAT_PCH_R")
	)
	(segment
		(start 110.65891 2.356358)
		(end 111.389922 1.625346)
		(width 0.127)
		(layer "In3.Cu")
		(net "SMDAT_PCH_R")
	)
	(segment
		(start 101.581458 2.356358)
		(end 110.65891 2.356358)
		(width 0.127)
		(layer "In3.Cu")
		(net "SMDAT_PCH_R")
	)
	(segment
		(start 46.743366 -0.5334)
		(end 47.733966 0.4572)
		(width 0.127)
		(layer "In3.Cu")
		(net "SMDAT_PCH_R")
	)
	(segment
		(start 43.844972 -0.5334)
		(end 46.743366 -0.5334)
		(width 0.127)
		(layer "In3.Cu")
		(net "SMDAT_PCH_R")
	)
	(segment
		(start 47.733966 0.4572)
		(end 99.6823 0.4572)
		(width 0.127)
		(layer "In3.Cu")
		(net "SMDAT_PCH_R")
	)
	(segment
		(start 43.3832 2.7432)
		(end 42.9768 3.1496)
		(width 0.127)
		(layer "In3.Cu")
		(net "SMDAT_PCH_R")
	)
	(segment
		(start 111.389922 1.625346)
		(end 119.253254 1.625346)
		(width 0.127)
		(layer "In3.Cu")
		(net "SMDAT_PCH_R")
	)
	(segment
		(start 37.4777 -0.4572)
		(end 37.4269 -0.508)
		(width 0.127)
		(layer "In3.Cu")
		(net "SMDAT_PCH_R")
	)
	(segment
		(start 99.6823 0.4572)
		(end 101.581458 2.356358)
		(width 0.127)
		(layer "In3.Cu")
		(net "SMDAT_PCH_R")
	)
	(segment
		(start 42.9768 3.1496)
		(end 40.309292 3.1496)
		(width 0.127)
		(layer "In3.Cu")
		(net "SMDAT_PCH_R")
	)
	(segment
		(start 119.253254 1.625346)
		(end 121.9454 -1.0668)
		(width 0.127)
		(layer "In3.Cu")
		(net "SMDAT_PCH_R")
	)
	(segment
		(start 42.424604 0.886968)
		(end 43.844972 -0.5334)
		(width 0.127)
		(layer "In3.Cu")
		(net "SMDAT_PCH_R")
	)
	(segment
		(start 129.72288 -2.56032)
		(end 130.6322 -1.651)
		(width 0.1016)
		(layer "F.Cu")
		(net "SMDAT_EXP_R_PCH")
	)
	(segment
		(start 130.1496 0.0381)
		(end 130.1496 -0.2794)
		(width 0.1016)
		(layer "F.Cu")
		(net "SMDAT_EXP_R_PCH")
	)
	(segment
		(start 130.6322 -1.651)
		(end 130.81 -1.651)
		(width 0.1016)
		(layer "F.Cu")
		(net "SMDAT_EXP_R_PCH")
	)
	(segment
		(start 130.937 -1.524)
		(end 130.81 -1.651)
		(width 0.1016)
		(layer "F.Cu")
		(net "SMDAT_EXP_R_PCH")
	)
	(segment
		(start 130.937 -1.0668)
		(end 130.937 -1.524)
		(width 0.1016)
		(layer "F.Cu")
		(net "SMDAT_EXP_R_PCH")
	)
	(segment
		(start 130.1496 -0.2794)
		(end 130.937 -1.0668)
		(width 0.1016)
		(layer "F.Cu")
		(net "SMDAT_EXP_R_PCH")
	)
	(segment
		(start 129.72288 -3.175)
		(end 129.72288 -2.56032)
		(width 0.1016)
		(layer "F.Cu")
		(net "SMDAT_EXP_R_PCH")
	)
	(via
		(at 130.81 -1.651)
		(size 0.7112)
		(drill 0.3556)
		(layers "F.Cu" "B.Cu")
		(net "SMDAT_EXP_R_PCH")
	)
	(segment
		(start 36.080192 -27.088592)
		(end 36.080192 -27.570176)
		(width 0.1016)
		(layer "F.Cu")
		(net "SMDAT_BMC_SLOT3_R")
	)
	(segment
		(start 31.2928 -25.0698)
		(end 31.928054 -25.7048)
		(width 0.1016)
		(layer "F.Cu")
		(net "SMDAT_BMC_SLOT3_R")
	)
	(segment
		(start 31.2928 -24.54148)
		(end 31.2928 -25.0698)
		(width 0.1016)
		(layer "F.Cu")
		(net "SMDAT_BMC_SLOT3_R")
	)
	(segment
		(start 34.6964 -25.7048)
		(end 36.080192 -27.088592)
		(width 0.1016)
		(layer "F.Cu")
		(net "SMDAT_BMC_SLOT3_R")
	)
	(segment
		(start 31.25724 -24.50592)
		(end 31.2928 -24.54148)
		(width 0.1016)
		(layer "F.Cu")
		(net "SMDAT_BMC_SLOT3_R")
	)
	(segment
		(start 31.928054 -25.7048)
		(end 34.6964 -25.7048)
		(width 0.1016)
		(layer "F.Cu")
		(net "SMDAT_BMC_SLOT3_R")
	)
	(segment
		(start 30.9372 -15.5448)
		(end 30.9372 -15.6464)
		(width 0.1016)
		(layer "F.Cu")
		(net "SMDAT_BMC_SLOT3")
	)
	(segment
		(start 30.988 -16.129)
		(end 30.1498 -16.9672)
		(width 0.1016)
		(layer "F.Cu")
		(net "SMDAT_BMC_SLOT3")
	)
	(segment
		(start 30.1498 -16.9672)
		(end 30.1498 -22.7584)
		(width 0.1016)
		(layer "F.Cu")
		(net "SMDAT_BMC_SLOT3")
	)
	(segment
		(start 30.9372 -15.6464)
		(end 30.988 -15.6972)
		(width 0.1016)
		(layer "F.Cu")
		(net "SMDAT_BMC_SLOT3")
	)
	(segment
		(start 30.988 -15.6972)
		(end 30.988 -16.129)
		(width 0.1016)
		(layer "F.Cu")
		(net "SMDAT_BMC_SLOT3")
	)
	(segment
		(start 30.1498 -22.7584)
		(end 31.00832 -23.61692)
		(width 0.1016)
		(layer "F.Cu")
		(net "SMDAT_BMC_SLOT3")
	)
	(segment
		(start 31.00832 -23.61692)
		(end 31.25724 -23.61692)
		(width 0.1016)
		(layer "F.Cu")
		(net "SMDAT_BMC_SLOT3")
	)
	(via
		(at 102.6922 -1.1938)
		(size 0.508)
		(drill 0.254)
		(layers "F.Cu" "B.Cu")
		(net "SMDAT_BMC_SLOT3")
	)
	(via
		(at 101.9302 -0.5334)
		(size 0.7112)
		(drill 0.3556)
		(layers "F.Cu" "B.Cu")
		(net "SMDAT_BMC_SLOT3")
	)
	(via
		(at 30.9372 -15.5448)
		(size 0.508)
		(drill 0.254)
		(layers "F.Cu" "B.Cu")
		(net "SMDAT_BMC_SLOT3")
	)
	(segment
		(start 103.2637 -0.6223)
		(end 102.6922 -1.1938)
		(width 0.1016)
		(layer "B.Cu")
		(net "SMDAT_BMC_SLOT3")
	)
	(segment
		(start 105.254552 -0.8636)
		(end 104.1273 -0.8636)
		(width 0.1016)
		(layer "B.Cu")
		(net "SMDAT_BMC_SLOT3")
	)
	(segment
		(start 101.9302 -0.5334)
		(end 102.0318 -0.5334)
		(width 0.1016)
		(layer "B.Cu")
		(net "SMDAT_BMC_SLOT3")
	)
	(segment
		(start 102.0318 -0.5334)
		(end 102.6922 -1.1938)
		(width 0.1016)
		(layer "B.Cu")
		(net "SMDAT_BMC_SLOT3")
	)
	(segment
		(start 103.886 -0.6223)
		(end 103.2637 -0.6223)
		(width 0.1016)
		(layer "B.Cu")
		(net "SMDAT_BMC_SLOT3")
	)
	(segment
		(start 105.965752 -1.5748)
		(end 105.254552 -0.8636)
		(width 0.1016)
		(layer "B.Cu")
		(net "SMDAT_BMC_SLOT3")
	)
	(segment
		(start 106.8578 -1.5748)
		(end 105.965752 -1.5748)
		(width 0.1016)
		(layer "B.Cu")
		(net "SMDAT_BMC_SLOT3")
	)
	(segment
		(start 104.1273 -0.8636)
		(end 103.886 -0.6223)
		(width 0.1016)
		(layer "B.Cu")
		(net "SMDAT_BMC_SLOT3")
	)
	(segment
		(start 55.582566 -1.9558)
		(end 56.128666 -2.5019)
		(width 0.127)
		(layer "In3.Cu")
		(net "SMDAT_BMC_SLOT3")
	)
	(segment
		(start 42.537634 -3.8481)
		(end 42.537888 -3.848354)
		(width 0.127)
		(layer "In3.Cu")
		(net "SMDAT_BMC_SLOT3")
	)
	(segment
		(start 30.9372 -15.512034)
		(end 29.7434 -14.318234)
		(width 0.127)
		(layer "In3.Cu")
		(net "SMDAT_BMC_SLOT3")
	)
	(segment
		(start 33.5407 -3.8481)
		(end 42.537634 -3.8481)
		(width 0.127)
		(layer "In3.Cu")
		(net "SMDAT_BMC_SLOT3")
	)
	(segment
		(start 48.1711 -1.9558)
		(end 55.582566 -1.9558)
		(width 0.127)
		(layer "In3.Cu")
		(net "SMDAT_BMC_SLOT3")
	)
	(segment
		(start 29.7434 -7.6454)
		(end 33.5407 -3.8481)
		(width 0.127)
		(layer "In3.Cu")
		(net "SMDAT_BMC_SLOT3")
	)
	(segment
		(start 44.228766 -2.5781)
		(end 47.5488 -2.5781)
		(width 0.127)
		(layer "In3.Cu")
		(net "SMDAT_BMC_SLOT3")
	)
	(segment
		(start 102.6922 -1.391666)
		(end 102.6922 -1.1938)
		(width 0.127)
		(layer "In3.Cu")
		(net "SMDAT_BMC_SLOT3")
	)
	(segment
		(start 56.128666 -2.5019)
		(end 101.581966 -2.5019)
		(width 0.127)
		(layer "In3.Cu")
		(net "SMDAT_BMC_SLOT3")
	)
	(segment
		(start 30.9372 -15.5448)
		(end 30.9372 -15.512034)
		(width 0.127)
		(layer "In3.Cu")
		(net "SMDAT_BMC_SLOT3")
	)
	(segment
		(start 42.537888 -3.848354)
		(end 42.958512 -3.848354)
		(width 0.127)
		(layer "In3.Cu")
		(net "SMDAT_BMC_SLOT3")
	)
	(segment
		(start 29.7434 -14.318234)
		(end 29.7434 -7.6454)
		(width 0.127)
		(layer "In3.Cu")
		(net "SMDAT_BMC_SLOT3")
	)
	(segment
		(start 42.958512 -3.848354)
		(end 44.228766 -2.5781)
		(width 0.127)
		(layer "In3.Cu")
		(net "SMDAT_BMC_SLOT3")
	)
	(segment
		(start 101.581966 -2.5019)
		(end 102.6922 -1.391666)
		(width 0.127)
		(layer "In3.Cu")
		(net "SMDAT_BMC_SLOT3")
	)
	(segment
		(start 47.5488 -2.5781)
		(end 48.1711 -1.9558)
		(width 0.127)
		(layer "In3.Cu")
		(net "SMDAT_BMC_SLOT3")
	)
	(via
		(at 39.2938 -3.4798)
		(size 0.7112)
		(drill 0.3556)
		(layers "F.Cu" "B.Cu")
		(net "SMDAT_BMC_SLOT2_R")
	)
	(segment
		(start 39.2938 -3.4798)
		(end 40.874696 -3.4798)
		(width 0.1016)
		(layer "B.Cu")
		(net "SMDAT_BMC_SLOT2_R")
	)
	(segment
		(start 40.874696 -3.4798)
		(end 41.6814 -2.673096)
		(width 0.1016)
		(layer "B.Cu")
		(net "SMDAT_BMC_SLOT2_R")
	)
	(segment
		(start 41.6814 -2.673096)
		(end 41.6814 -1.9812)
		(width 0.1016)
		(layer "B.Cu")
		(net "SMDAT_BMC_SLOT2_R")
	)
	(segment
		(start 39.2938 -3.4798)
		(end 39.1414 -3.4798)
		(width 0.1016)
		(layer "B.Cu")
		(net "SMDAT_BMC_SLOT2_R")
	)
	(segment
		(start 39.1414 -3.4798)
		(end 36.080192 -6.541008)
		(width 0.1016)
		(layer "B.Cu")
		(net "SMDAT_BMC_SLOT2_R")
	)
	(segment
		(start 36.080192 -6.541008)
		(end 36.080192 -7.250176)
		(width 0.1016)
		(layer "B.Cu")
		(net "SMDAT_BMC_SLOT2_R")
	)
	(via
		(at 99.568 2.4892)
		(size 0.508)
		(drill 0.254)
		(layers "F.Cu" "B.Cu")
		(net "SMDAT_BMC_SLOT2")
	)
	(via
		(at 103.4796 2.286)
		(size 0.7112)
		(drill 0.3556)
		(layers "F.Cu" "B.Cu")
		(net "SMDAT_BMC_SLOT2")
	)
	(via
		(at 44.260516 1.192276)
		(size 0.508)
		(drill 0.254)
		(layers "F.Cu" "B.Cu")
		(net "SMDAT_BMC_SLOT2")
	)
	(segment
		(start 103.4796 2.2606)
		(end 103.4796 2.286)
		(width 0.1016)
		(layer "B.Cu")
		(net "SMDAT_BMC_SLOT2")
	)
	(segment
		(start 42.33037 -0.73787)
		(end 44.260516 1.192276)
		(width 0.1016)
		(layer "B.Cu")
		(net "SMDAT_BMC_SLOT2")
	)
	(segment
		(start 103.3145 2.4257)
		(end 102.362 2.4257)
		(width 0.1016)
		(layer "B.Cu")
		(net "SMDAT_BMC_SLOT2")
	)
	(segment
		(start 41.6814 -1.0922)
		(end 42.03573 -0.73787)
		(width 0.1016)
		(layer "B.Cu")
		(net "SMDAT_BMC_SLOT2")
	)
	(segment
		(start 103.4542 2.286)
		(end 103.3145 2.4257)
		(width 0.1016)
		(layer "B.Cu")
		(net "SMDAT_BMC_SLOT2")
	)
	(segment
		(start 102.2604 2.5273)
		(end 101.9683 2.2352)
		(width 0.1016)
		(layer "B.Cu")
		(net "SMDAT_BMC_SLOT2")
	)
	(segment
		(start 99.822 2.2352)
		(end 99.568 2.4892)
		(width 0.1016)
		(layer "B.Cu")
		(net "SMDAT_BMC_SLOT2")
	)
	(segment
		(start 103.4796 2.286)
		(end 103.4542 2.286)
		(width 0.1016)
		(layer "B.Cu")
		(net "SMDAT_BMC_SLOT2")
	)
	(segment
		(start 102.362 2.4257)
		(end 102.2604 2.5273)
		(width 0.1016)
		(layer "B.Cu")
		(net "SMDAT_BMC_SLOT2")
	)
	(segment
		(start 101.9683 2.2352)
		(end 99.822 2.2352)
		(width 0.1016)
		(layer "B.Cu")
		(net "SMDAT_BMC_SLOT2")
	)
	(segment
		(start 105.36428 0.37592)
		(end 103.4796 2.2606)
		(width 0.1016)
		(layer "B.Cu")
		(net "SMDAT_BMC_SLOT2")
	)
	(segment
		(start 106.8578 0.37592)
		(end 105.36428 0.37592)
		(width 0.1016)
		(layer "B.Cu")
		(net "SMDAT_BMC_SLOT2")
	)
	(segment
		(start 42.03573 -0.73787)
		(end 42.33037 -0.73787)
		(width 0.1016)
		(layer "B.Cu")
		(net "SMDAT_BMC_SLOT2")
	)
	(segment
		(start 44.448476 1.192276)
		(end 44.260516 1.192276)
		(width 0.127)
		(layer "In3.Cu")
		(net "SMDAT_BMC_SLOT2")
	)
	(segment
		(start 99.161854 2.083054)
		(end 46.126654 2.083054)
		(width 0.127)
		(layer "In3.Cu")
		(net "SMDAT_BMC_SLOT2")
	)
	(segment
		(start 99.568 2.4892)
		(end 99.161854 2.083054)
		(width 0.127)
		(layer "In3.Cu")
		(net "SMDAT_BMC_SLOT2")
	)
	(segment
		(start 46.126654 2.083054)
		(end 45.466 1.4224)
		(width 0.127)
		(layer "In3.Cu")
		(net "SMDAT_BMC_SLOT2")
	)
	(segment
		(start 45.466 1.4224)
		(end 44.6786 1.4224)
		(width 0.127)
		(layer "In3.Cu")
		(net "SMDAT_BMC_SLOT2")
	)
	(segment
		(start 44.6786 1.4224)
		(end 44.448476 1.192276)
		(width 0.127)
		(layer "In3.Cu")
		(net "SMDAT_BMC_SLOT2")
	)
	(via
		(at 114.0714 2.3368)
		(size 0.7112)
		(drill 0.3556)
		(layers "F.Cu" "B.Cu")
		(net "SMDAT_BMC_R")
	)
	(segment
		(start 112.4966 2.32664)
		(end 114.06124 2.32664)
		(width 0.1016)
		(layer "B.Cu")
		(net "SMDAT_BMC_R")
	)
	(segment
		(start 108.698538 4.9276)
		(end 107.8865 4.9276)
		(width 0.1016)
		(layer "B.Cu")
		(net "SMDAT_BMC_R")
	)
	(segment
		(start 111.484918 2.24282)
		(end 111.383318 2.24282)
		(width 0.1016)
		(layer "B.Cu")
		(net "SMDAT_BMC_R")
	)
	(segment
		(start 111.383318 2.24282)
		(end 108.698538 4.9276)
		(width 0.1016)
		(layer "B.Cu")
		(net "SMDAT_BMC_R")
	)
	(segment
		(start 111.568738 2.32664)
		(end 111.484918 2.24282)
		(width 0.1016)
		(layer "B.Cu")
		(net "SMDAT_BMC_R")
	)
	(segment
		(start 107.8865 4.9276)
		(end 107.6071 5.207)
		(width 0.1016)
		(layer "B.Cu")
		(net "SMDAT_BMC_R")
	)
	(segment
		(start 114.06124 2.32664)
		(end 114.0714 2.3368)
		(width 0.1016)
		(layer "B.Cu")
		(net "SMDAT_BMC_R")
	)
	(segment
		(start 112.4966 2.32664)
		(end 111.568738 2.32664)
		(width 0.1016)
		(layer "B.Cu")
		(net "SMDAT_BMC_R")
	)
	(segment
		(start 129.1082 -19.304)
		(end 128.63068 -18.82648)
		(width 0.1016)
		(layer "F.Cu")
		(net "SMDAT_BMC_DEVICE")
	)
	(segment
		(start 128.63068 -18.82648)
		(end 127.6858 -18.82648)
		(width 0.1016)
		(layer "F.Cu")
		(net "SMDAT_BMC_DEVICE")
	)
	(segment
		(start 28.0162 -20.3454)
		(end 27.051 -20.3454)
		(width 0.1016)
		(layer "F.Cu")
		(net "SMDAT_BMC_DEVICE")
	)
	(segment
		(start 129.1082 -21.0058)
		(end 129.1082 -19.304)
		(width 0.1016)
		(layer "F.Cu")
		(net "SMDAT_BMC_DEVICE")
	)
	(segment
		(start 129.2352 -21.1328)
		(end 129.1082 -21.0058)
		(width 0.1016)
		(layer "F.Cu")
		(net "SMDAT_BMC_DEVICE")
	)
	(segment
		(start 26.2128 -19.5072)
		(end 26.2128 -19.1008)
		(width 0.1016)
		(layer "F.Cu")
		(net "SMDAT_BMC_DEVICE")
	)
	(segment
		(start 28.0924 -20.2692)
		(end 28.0162 -20.3454)
		(width 0.1016)
		(layer "F.Cu")
		(net "SMDAT_BMC_DEVICE")
	)
	(segment
		(start 27.051 -20.3454)
		(end 26.2128 -19.5072)
		(width 0.1016)
		(layer "F.Cu")
		(net "SMDAT_BMC_DEVICE")
	)
	(via
		(at 128.9558 -15.0876)
		(size 0.508)
		(drill 0.254)
		(layers "F.Cu" "B.Cu")
		(net "SMDAT_BMC_DEVICE")
	)
	(via
		(at 28.0924 -20.2692)
		(size 0.508)
		(drill 0.254)
		(layers "F.Cu" "B.Cu")
		(net "SMDAT_BMC_DEVICE")
	)
	(via
		(at 129.2352 -18.9103)
		(size 0.7112)
		(drill 0.3556)
		(layers "F.Cu" "B.Cu")
		(net "SMDAT_BMC_DEVICE")
	)
	(via
		(at 129.2352 -21.1328)
		(size 0.508)
		(drill 0.254)
		(layers "F.Cu" "B.Cu")
		(net "SMDAT_BMC_DEVICE")
	)
	(segment
		(start 118.8339 -9.709912)
		(end 118.833646 -9.710166)
		(width 0.1016)
		(layer "B.Cu")
		(net "SMDAT_BMC_DEVICE")
	)
	(segment
		(start 114.916204 0.1397)
		(end 114.941604 0.1651)
		(width 0.1016)
		(layer "B.Cu")
		(net "SMDAT_BMC_DEVICE")
	)
	(segment
		(start 129.159 -18.8341)
		(end 129.159 -16.697452)
		(width 0.1016)
		(layer "B.Cu")
		(net "SMDAT_BMC_DEVICE")
	)
	(segment
		(start 129.159 -16.697452)
		(end 129.227834 -16.628618)
		(width 0.1016)
		(layer "B.Cu")
		(net "SMDAT_BMC_DEVICE")
	)
	(segment
		(start 125.447298 -14.36624)
		(end 127.62484 -14.36624)
		(width 0.1016)
		(layer "B.Cu")
		(net "SMDAT_BMC_DEVICE")
	)
	(segment
		(start 27.305 -20.2692)
		(end 26.8859 -19.8501)
		(width 0.1016)
		(layer "B.Cu")
		(net "SMDAT_BMC_DEVICE")
	)
	(segment
		(start 129.2352 -21.1328)
		(end 129.2352 -18.9103)
		(width 0.1016)
		(layer "B.Cu")
		(net "SMDAT_BMC_DEVICE")
	)
	(segment
		(start 118.8339 -3.160268)
		(end 118.8339 -9.709912)
		(width 0.1016)
		(layer "B.Cu")
		(net "SMDAT_BMC_DEVICE")
	)
	(segment
		(start 118.7958 -0.682752)
		(end 118.7958 -3.122168)
		(width 0.1016)
		(layer "B.Cu")
		(net "SMDAT_BMC_DEVICE")
	)
	(segment
		(start 117.4496 0.1143)
		(end 117.998748 0.1143)
		(width 0.1016)
		(layer "B.Cu")
		(net "SMDAT_BMC_DEVICE")
	)
	(segment
		(start 114.941604 0.1651)
		(end 117.3988 0.1651)
		(width 0.1016)
		(layer "B.Cu")
		(net "SMDAT_BMC_DEVICE")
	)
	(segment
		(start 118.833646 -9.710166)
		(end 118.833646 -10.109962)
		(width 0.1016)
		(layer "B.Cu")
		(net "SMDAT_BMC_DEVICE")
	)
	(segment
		(start 112.4966 -0.27432)
		(end 113.571528 -0.27432)
		(width 0.1016)
		(layer "B.Cu")
		(net "SMDAT_BMC_DEVICE")
	)
	(segment
		(start 117.998748 0.1143)
		(end 118.7958 -0.682752)
		(width 0.1016)
		(layer "B.Cu")
		(net "SMDAT_BMC_DEVICE")
	)
	(segment
		(start 129.227834 -15.359634)
		(end 128.9558 -15.0876)
		(width 0.1016)
		(layer "B.Cu")
		(net "SMDAT_BMC_DEVICE")
	)
	(segment
		(start 122.939048 -14.5034)
		(end 125.310138 -14.5034)
		(width 0.1016)
		(layer "B.Cu")
		(net "SMDAT_BMC_DEVICE")
	)
	(segment
		(start 118.7958 -3.122168)
		(end 118.8339 -3.160268)
		(width 0.1016)
		(layer "B.Cu")
		(net "SMDAT_BMC_DEVICE")
	)
	(segment
		(start 26.8859 -19.8501)
		(end 26.6446 -19.8501)
		(width 0.1016)
		(layer "B.Cu")
		(net "SMDAT_BMC_DEVICE")
	)
	(segment
		(start 113.985548 0.1397)
		(end 114.916204 0.1397)
		(width 0.1016)
		(layer "B.Cu")
		(net "SMDAT_BMC_DEVICE")
	)
	(segment
		(start 113.571528 -0.27432)
		(end 113.985548 0.1397)
		(width 0.1016)
		(layer "B.Cu")
		(net "SMDAT_BMC_DEVICE")
	)
	(segment
		(start 129.2352 -21.9583)
		(end 129.2352 -21.1328)
		(width 0.1016)
		(layer "B.Cu")
		(net "SMDAT_BMC_DEVICE")
	)
	(segment
		(start 125.310138 -14.5034)
		(end 125.447298 -14.36624)
		(width 0.1016)
		(layer "B.Cu")
		(net "SMDAT_BMC_DEVICE")
	)
	(segment
		(start 117.3988 0.1651)
		(end 117.4496 0.1143)
		(width 0.1016)
		(layer "B.Cu")
		(net "SMDAT_BMC_DEVICE")
	)
	(segment
		(start 118.833646 -10.109962)
		(end 118.8339 -10.110216)
		(width 0.1016)
		(layer "B.Cu")
		(net "SMDAT_BMC_DEVICE")
	)
	(segment
		(start 25.1206 -19.8501)
		(end 25.0698 -19.7993)
		(width 0.1016)
		(layer "B.Cu")
		(net "SMDAT_BMC_DEVICE")
	)
	(segment
		(start 129.2352 -18.9103)
		(end 129.159 -18.8341)
		(width 0.1016)
		(layer "B.Cu")
		(net "SMDAT_BMC_DEVICE")
	)
	(segment
		(start 28.0924 -20.2692)
		(end 27.305 -20.2692)
		(width 0.1016)
		(layer "B.Cu")
		(net "SMDAT_BMC_DEVICE")
	)
	(segment
		(start 129.227834 -16.628618)
		(end 129.227834 -15.359634)
		(width 0.1016)
		(layer "B.Cu")
		(net "SMDAT_BMC_DEVICE")
	)
	(segment
		(start 128.3462 -15.0876)
		(end 128.9558 -15.0876)
		(width 0.1016)
		(layer "B.Cu")
		(net "SMDAT_BMC_DEVICE")
	)
	(segment
		(start 26.6446 -19.8501)
		(end 25.1206 -19.8501)
		(width 0.1016)
		(layer "B.Cu")
		(net "SMDAT_BMC_DEVICE")
	)
	(segment
		(start 118.8339 -10.398252)
		(end 122.939048 -14.5034)
		(width 0.1016)
		(layer "B.Cu")
		(net "SMDAT_BMC_DEVICE")
	)
	(segment
		(start 127.62484 -14.36624)
		(end 128.3462 -15.0876)
		(width 0.1016)
		(layer "B.Cu")
		(net "SMDAT_BMC_DEVICE")
	)
	(segment
		(start 118.8339 -10.110216)
		(end 118.8339 -10.398252)
		(width 0.1016)
		(layer "B.Cu")
		(net "SMDAT_BMC_DEVICE")
	)
	(segment
		(start 85.250782 -18.9865)
		(end 85.640418 -18.9865)
		(width 0.127)
		(layer "In3.Cu")
		(net "SMDAT_BMC_DEVICE")
	)
	(segment
		(start 120.541034 -17.8816)
		(end 123.630436 -14.792198)
		(width 0.127)
		(layer "In3.Cu")
		(net "SMDAT_BMC_DEVICE")
	)
	(segment
		(start 110.563406 -19.304)
		(end 110.82782 -19.568414)
		(width 0.127)
		(layer "In3.Cu")
		(net "SMDAT_BMC_DEVICE")
	)
	(segment
		(start 97.480882 -19.304)
		(end 110.563406 -19.304)
		(width 0.127)
		(layer "In3.Cu")
		(net "SMDAT_BMC_DEVICE")
	)
	(segment
		(start 128.660398 -14.792198)
		(end 128.9558 -15.0876)
		(width 0.127)
		(layer "In3.Cu")
		(net "SMDAT_BMC_DEVICE")
	)
	(segment
		(start 85.792818 -18.8341)
		(end 97.010982 -18.8341)
		(width 0.127)
		(layer "In3.Cu")
		(net "SMDAT_BMC_DEVICE")
	)
	(segment
		(start 29.718 -18.6944)
		(end 36.4998 -18.6944)
		(width 0.127)
		(layer "In3.Cu")
		(net "SMDAT_BMC_DEVICE")
	)
	(segment
		(start 110.82782 -19.568414)
		(end 111.386366 -19.568414)
		(width 0.127)
		(layer "In3.Cu")
		(net "SMDAT_BMC_DEVICE")
	)
	(segment
		(start 28.0924 -20.2692)
		(end 28.194 -20.1676)
		(width 0.127)
		(layer "In3.Cu")
		(net "SMDAT_BMC_DEVICE")
	)
	(segment
		(start 113.07318 -17.8816)
		(end 120.541034 -17.8816)
		(width 0.127)
		(layer "In3.Cu")
		(net "SMDAT_BMC_DEVICE")
	)
	(segment
		(start 42.1894 -24.384)
		(end 52.432966 -24.384)
		(width 0.127)
		(layer "In3.Cu")
		(net "SMDAT_BMC_DEVICE")
	)
	(segment
		(start 57.881266 -18.9357)
		(end 85.199982 -18.9357)
		(width 0.127)
		(layer "In3.Cu")
		(net "SMDAT_BMC_DEVICE")
	)
	(segment
		(start 28.194 -20.1676)
		(end 28.2448 -20.1676)
		(width 0.127)
		(layer "In3.Cu")
		(net "SMDAT_BMC_DEVICE")
	)
	(segment
		(start 52.432966 -24.384)
		(end 57.881266 -18.9357)
		(width 0.127)
		(layer "In3.Cu")
		(net "SMDAT_BMC_DEVICE")
	)
	(segment
		(start 36.4998 -18.6944)
		(end 42.1894 -24.384)
		(width 0.127)
		(layer "In3.Cu")
		(net "SMDAT_BMC_DEVICE")
	)
	(segment
		(start 85.199982 -18.9357)
		(end 85.250782 -18.9865)
		(width 0.127)
		(layer "In3.Cu")
		(net "SMDAT_BMC_DEVICE")
	)
	(segment
		(start 111.386366 -19.568414)
		(end 113.07318 -17.8816)
		(width 0.127)
		(layer "In3.Cu")
		(net "SMDAT_BMC_DEVICE")
	)
	(segment
		(start 28.2448 -20.1676)
		(end 29.718 -18.6944)
		(width 0.127)
		(layer "In3.Cu")
		(net "SMDAT_BMC_DEVICE")
	)
	(segment
		(start 123.630436 -14.792198)
		(end 128.660398 -14.792198)
		(width 0.127)
		(layer "In3.Cu")
		(net "SMDAT_BMC_DEVICE")
	)
	(segment
		(start 85.640418 -18.9865)
		(end 85.792818 -18.8341)
		(width 0.127)
		(layer "In3.Cu")
		(net "SMDAT_BMC_DEVICE")
	)
	(segment
		(start 97.010982 -18.8341)
		(end 97.480882 -19.304)
		(width 0.127)
		(layer "In3.Cu")
		(net "SMDAT_BMC_DEVICE")
	)
	(via
		(at 129.921 -23.6474)
		(size 0.508)
		(drill 0.254)
		(layers "F.Cu" "B.Cu")
		(net "SMCLK_USB_HUB")
	)
	(via
		(at 125.603 -18.3642)
		(size 0.508)
		(drill 0.254)
		(layers "F.Cu" "B.Cu")
		(net "SMCLK_USB_HUB")
	)
	(via
		(at 120.142 -24.003)
		(size 0.508)
		(drill 0.254)
		(layers "F.Cu" "B.Cu")
		(net "SMCLK_USB_HUB")
	)
	(via
		(at 128.4986 -16.0147)
		(size 0.7112)
		(drill 0.3556)
		(layers "F.Cu" "B.Cu")
		(net "SMCLK_USB_HUB")
	)
	(segment
		(start 130.2766 -23.4442)
		(end 130.0734 -23.6474)
		(width 0.1016)
		(layer "B.Cu")
		(net "SMCLK_USB_HUB")
	)
	(segment
		(start 130.0734 -23.6474)
		(end 129.921 -23.6474)
		(width 0.1016)
		(layer "B.Cu")
		(net "SMCLK_USB_HUB")
	)
	(segment
		(start 125.4506 -18.2118)
		(end 125.4506 -16.749014)
		(width 0.1016)
		(layer "B.Cu")
		(net "SMCLK_USB_HUB")
	)
	(segment
		(start 125.603 -18.3642)
		(end 125.4506 -18.2118)
		(width 0.1016)
		(layer "B.Cu")
		(net "SMCLK_USB_HUB")
	)
	(segment
		(start 120.142 -23.9903)
		(end 120.142 -24.003)
		(width 0.1016)
		(layer "B.Cu")
		(net "SMCLK_USB_HUB")
	)
	(segment
		(start 129.921 -23.744174)
		(end 130.0988 -23.921974)
		(width 0.1016)
		(layer "B.Cu")
		(net "SMCLK_USB_HUB")
	)
	(segment
		(start 125.4506 -16.749014)
		(end 125.948694 -16.25092)
		(width 0.1016)
		(layer "B.Cu")
		(net "SMCLK_USB_HUB")
	)
	(segment
		(start 130.2766 -22.8473)
		(end 130.2766 -23.4442)
		(width 0.1016)
		(layer "B.Cu")
		(net "SMCLK_USB_HUB")
	)
	(segment
		(start 129.921 -23.6474)
		(end 129.921 -23.744174)
		(width 0.1016)
		(layer "B.Cu")
		(net "SMCLK_USB_HUB")
	)
	(segment
		(start 130.0988 -23.921974)
		(end 130.0988 -24.5491)
		(width 0.1016)
		(layer "B.Cu")
		(net "SMCLK_USB_HUB")
	)
	(segment
		(start 125.948694 -16.25092)
		(end 126.59106 -16.25092)
		(width 0.1016)
		(layer "B.Cu")
		(net "SMCLK_USB_HUB")
	)
	(segment
		(start 128.26238 -16.25092)
		(end 128.4986 -16.0147)
		(width 0.1016)
		(layer "B.Cu")
		(net "SMCLK_USB_HUB")
	)
	(segment
		(start 120.8278 -23.3045)
		(end 120.142 -23.9903)
		(width 0.1016)
		(layer "B.Cu")
		(net "SMCLK_USB_HUB")
	)
	(segment
		(start 126.59106 -16.25092)
		(end 128.26238 -16.25092)
		(width 0.1016)
		(layer "B.Cu")
		(net "SMCLK_USB_HUB")
	)
	(segment
		(start 127.100076 -21.668994)
		(end 125.5268 -20.095718)
		(width 0.127)
		(layer "In2.Cu")
		(net "SMCLK_USB_HUB")
	)
	(segment
		(start 127.500634 -22.098)
		(end 127.100076 -21.697442)
		(width 0.127)
		(layer "In2.Cu")
		(net "SMCLK_USB_HUB")
	)
	(segment
		(start 129.921 -23.6474)
		(end 129.824226 -23.6474)
		(width 0.127)
		(layer "In2.Cu")
		(net "SMCLK_USB_HUB")
	)
	(segment
		(start 127.100076 -21.697442)
		(end 127.100076 -21.668994)
		(width 0.127)
		(layer "In2.Cu")
		(net "SMCLK_USB_HUB")
	)
	(segment
		(start 125.5268 -20.095718)
		(end 125.5268 -18.4404)
		(width 0.127)
		(layer "In2.Cu")
		(net "SMCLK_USB_HUB")
	)
	(segment
		(start 125.5268 -18.4404)
		(end 125.603 -18.3642)
		(width 0.127)
		(layer "In2.Cu")
		(net "SMCLK_USB_HUB")
	)
	(segment
		(start 129.824226 -23.6474)
		(end 128.274826 -22.098)
		(width 0.127)
		(layer "In2.Cu")
		(net "SMCLK_USB_HUB")
	)
	(segment
		(start 128.274826 -22.098)
		(end 127.500634 -22.098)
		(width 0.127)
		(layer "In2.Cu")
		(net "SMCLK_USB_HUB")
	)
	(segment
		(start 121.230898 -24.003)
		(end 123.453398 -21.7805)
		(width 0.127)
		(layer "In3.Cu")
		(net "SMCLK_USB_HUB")
	)
	(segment
		(start 120.142 -24.003)
		(end 121.230898 -24.003)
		(width 0.127)
		(layer "In3.Cu")
		(net "SMCLK_USB_HUB")
	)
	(segment
		(start 128.560068 -24.216868)
		(end 129.351532 -24.216868)
		(width 0.127)
		(layer "In3.Cu")
		(net "SMCLK_USB_HUB")
	)
	(segment
		(start 126.1237 -21.7805)
		(end 128.560068 -24.216868)
		(width 0.127)
		(layer "In3.Cu")
		(net "SMCLK_USB_HUB")
	)
	(segment
		(start 129.351532 -24.216868)
		(end 129.921 -23.6474)
		(width 0.127)
		(layer "In3.Cu")
		(net "SMCLK_USB_HUB")
	)
	(segment
		(start 123.453398 -21.7805)
		(end 126.1237 -21.7805)
		(width 0.127)
		(layer "In3.Cu")
		(net "SMCLK_USB_HUB")
	)
	(segment
		(start 33.04032 -25.1714)
		(end 34.9377 -25.1714)
		(width 0.1016)
		(layer "F.Cu")
		(net "SMCLK_PCH_SLOT3_R")
	)
	(segment
		(start 36.804346 -27.038046)
		(end 36.804346 -28.012898)
		(width 0.1016)
		(layer "F.Cu")
		(net "SMCLK_PCH_SLOT3_R")
	)
	(segment
		(start 37.8714 -30.3022)
		(end 37.079682 -31.093918)
		(width 0.1016)
		(layer "F.Cu")
		(net "SMCLK_PCH_SLOT3_R")
	)
	(segment
		(start 36.804346 -28.012898)
		(end 37.8714 -29.079952)
		(width 0.1016)
		(layer "F.Cu")
		(net "SMCLK_PCH_SLOT3_R")
	)
	(segment
		(start 37.079682 -31.093918)
		(end 37.079682 -32.069786)
		(width 0.1016)
		(layer "F.Cu")
		(net "SMCLK_PCH_SLOT3_R")
	)
	(segment
		(start 34.9377 -25.1714)
		(end 36.804346 -27.038046)
		(width 0.1016)
		(layer "F.Cu")
		(net "SMCLK_PCH_SLOT3_R")
	)
	(segment
		(start 32.40024 -24.53132)
		(end 33.04032 -25.1714)
		(width 0.1016)
		(layer "F.Cu")
		(net "SMCLK_PCH_SLOT3_R")
	)
	(segment
		(start 37.8714 -29.079952)
		(end 37.8714 -30.3022)
		(width 0.1016)
		(layer "F.Cu")
		(net "SMCLK_PCH_SLOT3_R")
	)
	(segment
		(start 32.40024 -23.64232)
		(end 32.40024 -23.05304)
		(width 0.1016)
		(layer "F.Cu")
		(net "SMCLK_PCH_SLOT3")
	)
	(segment
		(start 32.40024 -23.05304)
		(end 31.7246 -22.3774)
		(width 0.1016)
		(layer "F.Cu")
		(net "SMCLK_PCH_SLOT3")
	)
	(segment
		(start 31.7246 -22.3774)
		(end 30.6578 -22.3774)
		(width 0.1016)
		(layer "F.Cu")
		(net "SMCLK_PCH_SLOT3")
	)
	(via
		(at 131.0386 -11.684)
		(size 0.7112)
		(drill 0.3556)
		(layers "F.Cu" "B.Cu")
		(net "SMCLK_PCH_SLOT3")
	)
	(via
		(at 30.6578 -22.3774)
		(size 0.508)
		(drill 0.254)
		(layers "F.Cu" "B.Cu")
		(net "SMCLK_PCH_SLOT3")
	)
	(via
		(at 130.108452 -11.9888)
		(size 0.508)
		(drill 0.254)
		(layers "F.Cu" "B.Cu")
		(net "SMCLK_PCH_SLOT3")
	)
	(segment
		(start 131.0386 -11.7475)
		(end 131.0386 -11.684)
		(width 0.1016)
		(layer "B.Cu")
		(net "SMCLK_PCH_SLOT3")
	)
	(segment
		(start 130.108452 -11.922252)
		(end 130.108452 -11.9888)
		(width 0.1016)
		(layer "B.Cu")
		(net "SMCLK_PCH_SLOT3")
	)
	(segment
		(start 129.9591 -10.4902)
		(end 129.9591 -11.7729)
		(width 0.1016)
		(layer "B.Cu")
		(net "SMCLK_PCH_SLOT3")
	)
	(segment
		(start 129.9591 -11.7729)
		(end 130.108452 -11.922252)
		(width 0.1016)
		(layer "B.Cu")
		(net "SMCLK_PCH_SLOT3")
	)
	(segment
		(start 129.9083 -10.4394)
		(end 129.9591 -10.4902)
		(width 0.1016)
		(layer "B.Cu")
		(net "SMCLK_PCH_SLOT3")
	)
	(segment
		(start 129.72288 -8.8138)
		(end 129.72288 -10.25398)
		(width 0.1016)
		(layer "B.Cu")
		(net "SMCLK_PCH_SLOT3")
	)
	(segment
		(start 129.72288 -10.25398)
		(end 129.9083 -10.4394)
		(width 0.1016)
		(layer "B.Cu")
		(net "SMCLK_PCH_SLOT3")
	)
	(segment
		(start 130.7973 -11.9888)
		(end 131.0386 -11.7475)
		(width 0.1016)
		(layer "B.Cu")
		(net "SMCLK_PCH_SLOT3")
	)
	(segment
		(start 130.108452 -11.9888)
		(end 130.7973 -11.9888)
		(width 0.1016)
		(layer "B.Cu")
		(net "SMCLK_PCH_SLOT3")
	)
	(segment
		(start 36.035234 -26.416)
		(end 31.996634 -22.3774)
		(width 0.127)
		(layer "In3.Cu")
		(net "SMCLK_PCH_SLOT3")
	)
	(segment
		(start 122.490992 -20.884642)
		(end 122.491246 -20.884896)
		(width 0.127)
		(layer "In3.Cu")
		(net "SMCLK_PCH_SLOT3")
	)
	(segment
		(start 130.108452 -11.9888)
		(end 130.542284 -11.9888)
		(width 0.127)
		(layer "In3.Cu")
		(net "SMCLK_PCH_SLOT3")
	)
	(segment
		(start 58.19013 -21.5011)
		(end 53.27523 -26.416)
		(width 0.127)
		(layer "In3.Cu")
		(net "SMCLK_PCH_SLOT3")
	)
	(segment
		(start 124.87783 -17.6149)
		(end 122.490992 -20.001738)
		(width 0.127)
		(layer "In3.Cu")
		(net "SMCLK_PCH_SLOT3")
	)
	(segment
		(start 122.490992 -20.001738)
		(end 122.490992 -20.884642)
		(width 0.127)
		(layer "In3.Cu")
		(net "SMCLK_PCH_SLOT3")
	)
	(segment
		(start 130.542284 -11.9888)
		(end 131.1275 -12.574016)
		(width 0.127)
		(layer "In3.Cu")
		(net "SMCLK_PCH_SLOT3")
	)
	(segment
		(start 41.768014 -26.416254)
		(end 41.34739 -26.416254)
		(width 0.127)
		(layer "In3.Cu")
		(net "SMCLK_PCH_SLOT3")
	)
	(segment
		(start 41.34739 -26.416254)
		(end 41.347136 -26.416)
		(width 0.127)
		(layer "In3.Cu")
		(net "SMCLK_PCH_SLOT3")
	)
	(segment
		(start 31.996634 -22.3774)
		(end 30.6578 -22.3774)
		(width 0.127)
		(layer "In3.Cu")
		(net "SMCLK_PCH_SLOT3")
	)
	(segment
		(start 53.27523 -26.416)
		(end 41.768268 -26.416)
		(width 0.127)
		(layer "In3.Cu")
		(net "SMCLK_PCH_SLOT3")
	)
	(segment
		(start 129.306066 -17.6149)
		(end 124.87783 -17.6149)
		(width 0.127)
		(layer "In3.Cu")
		(net "SMCLK_PCH_SLOT3")
	)
	(segment
		(start 41.768268 -26.416)
		(end 41.768014 -26.416254)
		(width 0.127)
		(layer "In3.Cu")
		(net "SMCLK_PCH_SLOT3")
	)
	(segment
		(start 122.491246 -21.30552)
		(end 120.885966 -22.9108)
		(width 0.127)
		(layer "In3.Cu")
		(net "SMCLK_PCH_SLOT3")
	)
	(segment
		(start 41.347136 -26.416)
		(end 36.035234 -26.416)
		(width 0.127)
		(layer "In3.Cu")
		(net "SMCLK_PCH_SLOT3")
	)
	(segment
		(start 131.1275 -15.793466)
		(end 129.306066 -17.6149)
		(width 0.127)
		(layer "In3.Cu")
		(net "SMCLK_PCH_SLOT3")
	)
	(segment
		(start 131.1275 -12.574016)
		(end 131.1275 -15.793466)
		(width 0.127)
		(layer "In3.Cu")
		(net "SMCLK_PCH_SLOT3")
	)
	(segment
		(start 109.886242 -21.5011)
		(end 58.19013 -21.5011)
		(width 0.127)
		(layer "In3.Cu")
		(net "SMCLK_PCH_SLOT3")
	)
	(segment
		(start 122.491246 -20.884896)
		(end 122.491246 -21.30552)
		(width 0.127)
		(layer "In3.Cu")
		(net "SMCLK_PCH_SLOT3")
	)
	(segment
		(start 120.885966 -22.9108)
		(end 111.295942 -22.9108)
		(width 0.127)
		(layer "In3.Cu")
		(net "SMCLK_PCH_SLOT3")
	)
	(segment
		(start 111.295942 -22.9108)
		(end 109.886242 -21.5011)
		(width 0.127)
		(layer "In3.Cu")
		(net "SMCLK_PCH_SLOT3")
	)
	(via
		(at 42.9514 -3.4036)
		(size 0.7112)
		(drill 0.3556)
		(layers "F.Cu" "B.Cu")
		(net "SMCLK_PCH_SLOT2_R")
	)
	(segment
		(start 41.2369 -5.0165)
		(end 42.5958 -3.6576)
		(width 0.1016)
		(layer "B.Cu")
		(net "SMCLK_PCH_SLOT2_R")
	)
	(segment
		(start 42.5958 -3.6576)
		(end 42.6974 -3.6576)
		(width 0.1016)
		(layer "B.Cu")
		(net "SMCLK_PCH_SLOT2_R")
	)
	(segment
		(start 37.079682 -10.837418)
		(end 37.8841 -10.033)
		(width 0.1016)
		(layer "B.Cu")
		(net "SMCLK_PCH_SLOT2_R")
	)
	(segment
		(start 37.8841 -10.033)
		(end 37.8841 -8.651748)
		(width 0.1016)
		(layer "B.Cu")
		(net "SMCLK_PCH_SLOT2_R")
	)
	(segment
		(start 42.9514 -3.4036)
		(end 43.4848 -2.8702)
		(width 0.1016)
		(layer "B.Cu")
		(net "SMCLK_PCH_SLOT2_R")
	)
	(segment
		(start 37.079682 -11.749786)
		(end 37.079682 -10.837418)
		(width 0.1016)
		(layer "B.Cu")
		(net "SMCLK_PCH_SLOT2_R")
	)
	(segment
		(start 42.6974 -3.6576)
		(end 42.9514 -3.4036)
		(width 0.1016)
		(layer "B.Cu")
		(net "SMCLK_PCH_SLOT2_R")
	)
	(segment
		(start 38.862 -6.34492)
		(end 40.19042 -5.0165)
		(width 0.1016)
		(layer "B.Cu")
		(net "SMCLK_PCH_SLOT2_R")
	)
	(segment
		(start 43.4848 -1.81102)
		(end 43.97756 -1.31826)
		(width 0.1016)
		(layer "B.Cu")
		(net "SMCLK_PCH_SLOT2_R")
	)
	(segment
		(start 40.19042 -5.0165)
		(end 41.2369 -5.0165)
		(width 0.1016)
		(layer "B.Cu")
		(net "SMCLK_PCH_SLOT2_R")
	)
	(segment
		(start 43.4848 -2.8702)
		(end 43.4848 -1.81102)
		(width 0.1016)
		(layer "B.Cu")
		(net "SMCLK_PCH_SLOT2_R")
	)
	(segment
		(start 37.8841 -8.651748)
		(end 38.862 -7.673848)
		(width 0.1016)
		(layer "B.Cu")
		(net "SMCLK_PCH_SLOT2_R")
	)
	(segment
		(start 38.862 -7.673848)
		(end 38.862 -6.34492)
		(width 0.1016)
		(layer "B.Cu")
		(net "SMCLK_PCH_SLOT2_R")
	)
	(via
		(at 121.4628 -3.4417)
		(size 0.7112)
		(drill 0.3556)
		(layers "F.Cu" "B.Cu")
		(net "SMCLK_PCH_SLOT2")
	)
	(via
		(at 46.863 -3.0861)
		(size 0.508)
		(drill 0.254)
		(layers "F.Cu" "B.Cu")
		(net "SMCLK_PCH_SLOT2")
	)
	(via
		(at 120.3071 -3.3655)
		(size 0.508)
		(drill 0.254)
		(layers "F.Cu" "B.Cu")
		(net "SMCLK_PCH_SLOT2")
	)
	(segment
		(start 122.3391 -4.7117)
		(end 122.3391 -4.753864)
		(width 0.1016)
		(layer "B.Cu")
		(net "SMCLK_PCH_SLOT2")
	)
	(segment
		(start 122.3391 -4.753864)
		(end 124.087636 -6.5024)
		(width 0.1016)
		(layer "B.Cu")
		(net "SMCLK_PCH_SLOT2")
	)
	(segment
		(start 121.3866 -3.3655)
		(end 121.4628 -3.4417)
		(width 0.1016)
		(layer "B.Cu")
		(net "SMCLK_PCH_SLOT2")
	)
	(segment
		(start 122.2121 -4.191)
		(end 122.2121 -4.5339)
		(width 0.1016)
		(layer "B.Cu")
		(net "SMCLK_PCH_SLOT2")
	)
	(segment
		(start 124.087636 -6.5024)
		(end 126.215648 -6.5024)
		(width 0.1016)
		(layer "B.Cu")
		(net "SMCLK_PCH_SLOT2")
	)
	(segment
		(start 126.215648 -6.5024)
		(end 127.77216 -8.058912)
		(width 0.1016)
		(layer "B.Cu")
		(net "SMCLK_PCH_SLOT2")
	)
	(segment
		(start 122.3645 -4.6863)
		(end 122.3391 -4.7117)
		(width 0.1016)
		(layer "B.Cu")
		(net "SMCLK_PCH_SLOT2")
	)
	(segment
		(start 127.77216 -8.058912)
		(end 127.77216 -8.8138)
		(width 0.1016)
		(layer "B.Cu")
		(net "SMCLK_PCH_SLOT2")
	)
	(segment
		(start 45.09516 -1.31826)
		(end 46.863 -3.0861)
		(width 0.1016)
		(layer "B.Cu")
		(net "SMCLK_PCH_SLOT2")
	)
	(segment
		(start 44.86656 -1.31826)
		(end 45.09516 -1.31826)
		(width 0.1016)
		(layer "B.Cu")
		(net "SMCLK_PCH_SLOT2")
	)
	(segment
		(start 120.3071 -3.3655)
		(end 121.3866 -3.3655)
		(width 0.1016)
		(layer "B.Cu")
		(net "SMCLK_PCH_SLOT2")
	)
	(segment
		(start 122.2121 -4.5339)
		(end 122.3645 -4.6863)
		(width 0.1016)
		(layer "B.Cu")
		(net "SMCLK_PCH_SLOT2")
	)
	(segment
		(start 121.4628 -3.4417)
		(end 122.2121 -4.191)
		(width 0.1016)
		(layer "B.Cu")
		(net "SMCLK_PCH_SLOT2")
	)
	(segment
		(start 55.9943 -3.0861)
		(end 103.0224 -3.0861)
		(width 0.127)
		(layer "In3.Cu")
		(net "SMCLK_PCH_SLOT2")
	)
	(segment
		(start 48.354234 -2.6289)
		(end 55.5371 -2.6289)
		(width 0.127)
		(layer "In3.Cu")
		(net "SMCLK_PCH_SLOT2")
	)
	(segment
		(start 47.897034 -3.0861)
		(end 48.354234 -2.6289)
		(width 0.127)
		(layer "In3.Cu")
		(net "SMCLK_PCH_SLOT2")
	)
	(segment
		(start 120.0658 -3.1242)
		(end 120.3071 -3.3655)
		(width 0.127)
		(layer "In3.Cu")
		(net "SMCLK_PCH_SLOT2")
	)
	(segment
		(start 55.5371 -2.6289)
		(end 55.9943 -3.0861)
		(width 0.127)
		(layer "In3.Cu")
		(net "SMCLK_PCH_SLOT2")
	)
	(segment
		(start 103.0605 -3.1242)
		(end 120.0658 -3.1242)
		(width 0.127)
		(layer "In3.Cu")
		(net "SMCLK_PCH_SLOT2")
	)
	(segment
		(start 46.863 -3.0861)
		(end 47.897034 -3.0861)
		(width 0.127)
		(layer "In3.Cu")
		(net "SMCLK_PCH_SLOT2")
	)
	(segment
		(start 103.0224 -3.0861)
		(end 103.0605 -3.1242)
		(width 0.127)
		(layer "In3.Cu")
		(net "SMCLK_PCH_SLOT2")
	)
	(via
		(at 44.176188 2.352294)
		(size 0.508)
		(drill 0.254)
		(layers "F.Cu" "B.Cu")
		(net "SMCLK_PCH_R")
	)
	(via
		(at 122.468894 -0.345694)
		(size 0.508)
		(drill 0.254)
		(layers "F.Cu" "B.Cu")
		(net "SMCLK_PCH_R")
	)
	(via
		(at 125.2347 -1.5621)
		(size 0.7112)
		(drill 0.3556)
		(layers "F.Cu" "B.Cu")
		(net "SMCLK_PCH_R")
	)
	(via
		(at 36.5633 -0.5969)
		(size 0.508)
		(drill 0.254)
		(layers "F.Cu" "B.Cu")
		(net "SMCLK_PCH_R")
	)
	(segment
		(start 123.3424 -1.2192)
		(end 124.9807 -1.2192)
		(width 0.1016)
		(layer "B.Cu")
		(net "SMCLK_PCH_R")
	)
	(segment
		(start 125.2474 -1.651)
		(end 125.2474 -1.5748)
		(width 0.1016)
		(layer "B.Cu")
		(net "SMCLK_PCH_R")
	)
	(segment
		(start 43.815 1.8923)
		(end 44.173394 2.250694)
		(width 0.1016)
		(layer "B.Cu")
		(net "SMCLK_PCH_R")
	)
	(segment
		(start 42.164 1.9939)
		(end 42.2656 1.8923)
		(width 0.1016)
		(layer "B.Cu")
		(net "SMCLK_PCH_R")
	)
	(segment
		(start 125.7554 -2.454656)
		(end 125.7554 -2.159)
		(width 0.1016)
		(layer "B.Cu")
		(net "SMCLK_PCH_R")
	)
	(segment
		(start 125.82144 -2.520696)
		(end 125.7554 -2.454656)
		(width 0.1016)
		(layer "B.Cu")
		(net "SMCLK_PCH_R")
	)
	(segment
		(start 122.468894 -0.345694)
		(end 123.3424 -1.2192)
		(width 0.1016)
		(layer "B.Cu")
		(net "SMCLK_PCH_R")
	)
	(segment
		(start 124.9807 -1.2192)
		(end 125.2347 -1.4732)
		(width 0.1016)
		(layer "B.Cu")
		(net "SMCLK_PCH_R")
	)
	(segment
		(start 125.82144 -3.175)
		(end 125.82144 -2.520696)
		(width 0.1016)
		(layer "B.Cu")
		(net "SMCLK_PCH_R")
	)
	(segment
		(start 36.58362 2.57048)
		(end 35.09264 2.57048)
		(width 0.1016)
		(layer "B.Cu")
		(net "SMCLK_PCH_R")
	)
	(segment
		(start 125.2347 -1.4732)
		(end 125.2347 -1.5621)
		(width 0.1016)
		(layer "B.Cu")
		(net "SMCLK_PCH_R")
	)
	(segment
		(start 125.2474 -1.5748)
		(end 125.2347 -1.5621)
		(width 0.1016)
		(layer "B.Cu")
		(net "SMCLK_PCH_R")
	)
	(segment
		(start 36.7538 -0.0381)
		(end 36.4236 0.2921)
		(width 0.1016)
		(layer "B.Cu")
		(net "SMCLK_PCH_R")
	)
	(segment
		(start 36.5633 -0.5969)
		(end 36.7538 -0.4064)
		(width 0.1016)
		(layer "B.Cu")
		(net "SMCLK_PCH_R")
	)
	(segment
		(start 36.7538 -0.4064)
		(end 36.7538 -0.0381)
		(width 0.1016)
		(layer "B.Cu")
		(net "SMCLK_PCH_R")
	)
	(segment
		(start 44.173394 2.3495)
		(end 44.176188 2.352294)
		(width 0.1016)
		(layer "B.Cu")
		(net "SMCLK_PCH_R")
	)
	(segment
		(start 37.338 1.2065)
		(end 37.338 1.8161)
		(width 0.1016)
		(layer "B.Cu")
		(net "SMCLK_PCH_R")
	)
	(segment
		(start 125.7554 -2.159)
		(end 125.2474 -1.651)
		(width 0.1016)
		(layer "B.Cu")
		(net "SMCLK_PCH_R")
	)
	(segment
		(start 36.4236 0.2921)
		(end 37.338 1.2065)
		(width 0.1016)
		(layer "B.Cu")
		(net "SMCLK_PCH_R")
	)
	(segment
		(start 42.2656 1.8923)
		(end 43.815 1.8923)
		(width 0.1016)
		(layer "B.Cu")
		(net "SMCLK_PCH_R")
	)
	(segment
		(start 37.338 1.8161)
		(end 36.58362 2.57048)
		(width 0.1016)
		(layer "B.Cu")
		(net "SMCLK_PCH_R")
	)
	(segment
		(start 44.173394 2.250694)
		(end 44.173394 2.3495)
		(width 0.1016)
		(layer "B.Cu")
		(net "SMCLK_PCH_R")
	)
	(segment
		(start 36.5633 0.122174)
		(end 36.5633 -0.5969)
		(width 0.127)
		(layer "In3.Cu")
		(net "SMCLK_PCH_R")
	)
	(segment
		(start 42.932604 1.097534)
		(end 44.055538 -0.0254)
		(width 0.127)
		(layer "In3.Cu")
		(net "SMCLK_PCH_R")
	)
	(segment
		(start 46.5328 -0.0254)
		(end 47.6123 1.0541)
		(width 0.127)
		(layer "In3.Cu")
		(net "SMCLK_PCH_R")
	)
	(segment
		(start 42.932604 1.48717)
		(end 42.932604 1.097534)
		(width 0.127)
		(layer "In3.Cu")
		(net "SMCLK_PCH_R")
	)
	(segment
		(start 101.370892 2.864358)
		(end 110.869476 2.864358)
		(width 0.127)
		(layer "In3.Cu")
		(net "SMCLK_PCH_R")
	)
	(segment
		(start 44.176188 2.352294)
		(end 44.176188 2.668778)
		(width 0.127)
		(layer "In3.Cu")
		(net "SMCLK_PCH_R")
	)
	(segment
		(start 44.055538 -0.0254)
		(end 46.5328 -0.0254)
		(width 0.127)
		(layer "In3.Cu")
		(net "SMCLK_PCH_R")
	)
	(segment
		(start 47.6123 1.0541)
		(end 99.560634 1.0541)
		(width 0.127)
		(layer "In3.Cu")
		(net "SMCLK_PCH_R")
	)
	(segment
		(start 44.176188 2.668778)
		(end 43.085766 3.7592)
		(width 0.127)
		(layer "In3.Cu")
		(net "SMCLK_PCH_R")
	)
	(segment
		(start 40.200326 3.7592)
		(end 36.5633 0.122174)
		(width 0.127)
		(layer "In3.Cu")
		(net "SMCLK_PCH_R")
	)
	(segment
		(start 44.176188 2.352294)
		(end 43.741594 1.9177)
		(width 0.127)
		(layer "In3.Cu")
		(net "SMCLK_PCH_R")
	)
	(segment
		(start 119.989854 2.133346)
		(end 122.468894 -0.345694)
		(width 0.127)
		(layer "In3.Cu")
		(net "SMCLK_PCH_R")
	)
	(segment
		(start 43.741594 1.9177)
		(end 43.363134 1.9177)
		(width 0.127)
		(layer "In3.Cu")
		(net "SMCLK_PCH_R")
	)
	(segment
		(start 111.600488 2.133346)
		(end 119.989854 2.133346)
		(width 0.127)
		(layer "In3.Cu")
		(net "SMCLK_PCH_R")
	)
	(segment
		(start 110.869476 2.864358)
		(end 111.600488 2.133346)
		(width 0.127)
		(layer "In3.Cu")
		(net "SMCLK_PCH_R")
	)
	(segment
		(start 43.363134 1.9177)
		(end 42.932604 1.48717)
		(width 0.127)
		(layer "In3.Cu")
		(net "SMCLK_PCH_R")
	)
	(segment
		(start 43.085766 3.7592)
		(end 40.200326 3.7592)
		(width 0.127)
		(layer "In3.Cu")
		(net "SMCLK_PCH_R")
	)
	(segment
		(start 99.560634 1.0541)
		(end 101.370892 2.864358)
		(width 0.127)
		(layer "In3.Cu")
		(net "SMCLK_PCH_R")
	)
	(segment
		(start 129.794 -0.6477)
		(end 129.794 -0.859028)
		(width 0.1016)
		(layer "F.Cu")
		(net "SMCLK_EXP_R_PCH")
	)
	(segment
		(start 129.1082 0.0381)
		(end 129.794 -0.6477)
		(width 0.1016)
		(layer "F.Cu")
		(net "SMCLK_EXP_R_PCH")
	)
	(segment
		(start 129.07264 -3.175)
		(end 129.07264 -2.318512)
		(width 0.1016)
		(layer "F.Cu")
		(net "SMCLK_EXP_R_PCH")
	)
	(segment
		(start 129.2098 -2.1336)
		(end 129.794 -1.5494)
		(width 0.1016)
		(layer "F.Cu")
		(net "SMCLK_EXP_R_PCH")
	)
	(segment
		(start 129.2098 -2.181352)
		(end 129.2098 -2.1336)
		(width 0.1016)
		(layer "F.Cu")
		(net "SMCLK_EXP_R_PCH")
	)
	(segment
		(start 129.07264 -2.318512)
		(end 129.2098 -2.181352)
		(width 0.1016)
		(layer "F.Cu")
		(net "SMCLK_EXP_R_PCH")
	)
	(segment
		(start 129.794 -1.5494)
		(end 129.794 -0.859028)
		(width 0.1016)
		(layer "F.Cu")
		(net "SMCLK_EXP_R_PCH")
	)
	(via
		(at 129.794 -0.859028)
		(size 0.7112)
		(drill 0.3556)
		(layers "F.Cu" "B.Cu")
		(net "SMCLK_EXP_R_PCH")
	)
	(segment
		(start 130.0861 -19.3675)
		(end 129.286 -18.5674)
		(width 0.1016)
		(layer "F.Cu")
		(net "SMCLK_EXP_R_BMC")
	)
	(segment
		(start 129.286 -18.5674)
		(end 128.89484 -18.17624)
		(width 0.1016)
		(layer "F.Cu")
		(net "SMCLK_EXP_R_BMC")
	)
	(segment
		(start 130.2004 -19.3675)
		(end 130.0861 -19.3675)
		(width 0.1016)
		(layer "F.Cu")
		(net "SMCLK_EXP_R_BMC")
	)
	(segment
		(start 128.89484 -18.17624)
		(end 127.6858 -18.17624)
		(width 0.1016)
		(layer "F.Cu")
		(net "SMCLK_EXP_R_BMC")
	)
	(via
		(at 129.286 -18.5674)
		(size 0.7112)
		(drill 0.3556)
		(layers "F.Cu" "B.Cu")
		(net "SMCLK_EXP_R_BMC")
	)
	(segment
		(start 35.079432 -29.570426)
		(end 35.079432 -27.154632)
		(width 0.1016)
		(layer "F.Cu")
		(net "SMCLK_BMC_SLOT3_R")
	)
	(segment
		(start 30.9372 -26.1874)
		(end 30.21584 -25.46604)
		(width 0.1016)
		(layer "F.Cu")
		(net "SMCLK_BMC_SLOT3_R")
	)
	(segment
		(start 30.21584 -25.46604)
		(end 30.21584 -24.50592)
		(width 0.1016)
		(layer "F.Cu")
		(net "SMCLK_BMC_SLOT3_R")
	)
	(segment
		(start 34.1122 -26.1874)
		(end 30.9372 -26.1874)
		(width 0.1016)
		(layer "F.Cu")
		(net "SMCLK_BMC_SLOT3_R")
	)
	(segment
		(start 35.079432 -27.154632)
		(end 34.1122 -26.1874)
		(width 0.1016)
		(layer "F.Cu")
		(net "SMCLK_BMC_SLOT3_R")
	)
	(segment
		(start 30.1752 -16.1036)
		(end 29.5656 -16.7132)
		(width 0.1016)
		(layer "F.Cu")
		(net "SMCLK_BMC_SLOT3")
	)
	(segment
		(start 30.1752 -15.4686)
		(end 30.1752 -16.1036)
		(width 0.1016)
		(layer "F.Cu")
		(net "SMCLK_BMC_SLOT3")
	)
	(segment
		(start 29.5656 -16.7132)
		(end 29.5656 -22.96668)
		(width 0.1016)
		(layer "F.Cu")
		(net "SMCLK_BMC_SLOT3")
	)
	(segment
		(start 30.0736 -15.367)
		(end 30.1752 -15.4686)
		(width 0.1016)
		(layer "F.Cu")
		(net "SMCLK_BMC_SLOT3")
	)
	(segment
		(start 29.5656 -22.96668)
		(end 30.21584 -23.61692)
		(width 0.1016)
		(layer "F.Cu")
		(net "SMCLK_BMC_SLOT3")
	)
	(via
		(at 30.0736 -15.367)
		(size 0.508)
		(drill 0.254)
		(layers "F.Cu" "B.Cu")
		(net "SMCLK_BMC_SLOT3")
	)
	(via
		(at 105.0417 -1.5748)
		(size 0.7112)
		(drill 0.3556)
		(layers "F.Cu" "B.Cu")
		(net "SMCLK_BMC_SLOT3")
	)
	(via
		(at 101.854 -1.5113)
		(size 0.508)
		(drill 0.254)
		(layers "F.Cu" "B.Cu")
		(net "SMCLK_BMC_SLOT3")
	)
	(segment
		(start 104.8131 -1.3462)
		(end 104.1781 -1.3462)
		(width 0.1016)
		(layer "B.Cu")
		(net "SMCLK_BMC_SLOT3")
	)
	(segment
		(start 101.854 -1.5113)
		(end 102.235 -1.8923)
		(width 0.1016)
		(layer "B.Cu")
		(net "SMCLK_BMC_SLOT3")
	)
	(segment
		(start 105.69194 -2.22504)
		(end 105.0417 -1.5748)
		(width 0.1016)
		(layer "B.Cu")
		(net "SMCLK_BMC_SLOT3")
	)
	(segment
		(start 105.0417 -1.5748)
		(end 104.8131 -1.3462)
		(width 0.1016)
		(layer "B.Cu")
		(net "SMCLK_BMC_SLOT3")
	)
	(segment
		(start 103.632 -1.8923)
		(end 103.886 -1.6383)
		(width 0.1016)
		(layer "B.Cu")
		(net "SMCLK_BMC_SLOT3")
	)
	(segment
		(start 102.235 -1.8923)
		(end 103.632 -1.8923)
		(width 0.1016)
		(layer "B.Cu")
		(net "SMCLK_BMC_SLOT3")
	)
	(segment
		(start 106.8578 -2.22504)
		(end 105.69194 -2.22504)
		(width 0.1016)
		(layer "B.Cu")
		(net "SMCLK_BMC_SLOT3")
	)
	(segment
		(start 104.1781 -1.3462)
		(end 103.886 -1.6383)
		(width 0.1016)
		(layer "B.Cu")
		(net "SMCLK_BMC_SLOT3")
	)
	(segment
		(start 30.0736 -15.367)
		(end 29.2354 -14.5288)
		(width 0.127)
		(layer "In3.Cu")
		(net "SMCLK_BMC_SLOT3")
	)
	(segment
		(start 33.312354 -3.339846)
		(end 33.751012 -3.339846)
		(width 0.127)
		(layer "In3.Cu")
		(net "SMCLK_BMC_SLOT3")
	)
	(segment
		(start 101.3714 -1.9939)
		(end 101.854 -1.5113)
		(width 0.127)
		(layer "In3.Cu")
		(net "SMCLK_BMC_SLOT3")
	)
	(segment
		(start 55.792878 -1.447546)
		(end 56.339232 -1.9939)
		(width 0.127)
		(layer "In3.Cu")
		(net "SMCLK_BMC_SLOT3")
	)
	(segment
		(start 47.960788 -1.447546)
		(end 55.792878 -1.447546)
		(width 0.127)
		(layer "In3.Cu")
		(net "SMCLK_BMC_SLOT3")
	)
	(segment
		(start 44.0182 -2.0701)
		(end 47.338234 -2.0701)
		(width 0.127)
		(layer "In3.Cu")
		(net "SMCLK_BMC_SLOT3")
	)
	(segment
		(start 47.338234 -2.0701)
		(end 47.960788 -1.447546)
		(width 0.127)
		(layer "In3.Cu")
		(net "SMCLK_BMC_SLOT3")
	)
	(segment
		(start 29.2354 -7.4168)
		(end 33.312354 -3.339846)
		(width 0.127)
		(layer "In3.Cu")
		(net "SMCLK_BMC_SLOT3")
	)
	(segment
		(start 29.2354 -14.5288)
		(end 29.2354 -7.4168)
		(width 0.127)
		(layer "In3.Cu")
		(net "SMCLK_BMC_SLOT3")
	)
	(segment
		(start 42.7482 -3.3401)
		(end 44.0182 -2.0701)
		(width 0.127)
		(layer "In3.Cu")
		(net "SMCLK_BMC_SLOT3")
	)
	(segment
		(start 33.751012 -3.339846)
		(end 33.751266 -3.3401)
		(width 0.127)
		(layer "In3.Cu")
		(net "SMCLK_BMC_SLOT3")
	)
	(segment
		(start 33.751266 -3.3401)
		(end 42.7482 -3.3401)
		(width 0.127)
		(layer "In3.Cu")
		(net "SMCLK_BMC_SLOT3")
	)
	(segment
		(start 56.339232 -1.9939)
		(end 101.3714 -1.9939)
		(width 0.127)
		(layer "In3.Cu")
		(net "SMCLK_BMC_SLOT3")
	)
	(via
		(at 41.4782 -3.8354)
		(size 0.7112)
		(drill 0.3556)
		(layers "F.Cu" "B.Cu")
		(net "SMCLK_BMC_SLOT2_R")
	)
	(segment
		(start 42.7482 -2.5654)
		(end 41.4782 -3.8354)
		(width 0.1016)
		(layer "B.Cu")
		(net "SMCLK_BMC_SLOT2_R")
	)
	(segment
		(start 37.0967 -6.2611)
		(end 38.989 -4.3688)
		(width 0.1016)
		(layer "B.Cu")
		(net "SMCLK_BMC_SLOT2_R")
	)
	(segment
		(start 42.7482 -1.9812)
		(end 42.7482 -2.5654)
		(width 0.1016)
		(layer "B.Cu")
		(net "SMCLK_BMC_SLOT2_R")
	)
	(segment
		(start 35.555174 -9.250426)
		(end 37.0967 -7.7089)
		(width 0.1016)
		(layer "B.Cu")
		(net "SMCLK_BMC_SLOT2_R")
	)
	(segment
		(start 35.079432 -9.250426)
		(end 35.555174 -9.250426)
		(width 0.1016)
		(layer "B.Cu")
		(net "SMCLK_BMC_SLOT2_R")
	)
	(segment
		(start 37.0967 -7.7089)
		(end 37.0967 -6.2611)
		(width 0.1016)
		(layer "B.Cu")
		(net "SMCLK_BMC_SLOT2_R")
	)
	(segment
		(start 40.9448 -4.3688)
		(end 41.4782 -3.8354)
		(width 0.1016)
		(layer "B.Cu")
		(net "SMCLK_BMC_SLOT2_R")
	)
	(segment
		(start 38.989 -4.3688)
		(end 40.9448 -4.3688)
		(width 0.1016)
		(layer "B.Cu")
		(net "SMCLK_BMC_SLOT2_R")
	)
	(via
		(at 99.7712 1.3716)
		(size 0.7112)
		(drill 0.3556)
		(layers "F.Cu" "B.Cu")
		(net "SMCLK_BMC_SLOT2")
	)
	(via
		(at 44.7802 0.45974)
		(size 0.508)
		(drill 0.254)
		(layers "F.Cu" "B.Cu")
		(net "SMCLK_BMC_SLOT2")
	)
	(via
		(at 98.6282 1.524)
		(size 0.508)
		(drill 0.254)
		(layers "F.Cu" "B.Cu")
		(net "SMCLK_BMC_SLOT2")
	)
	(segment
		(start 99.7712 1.3716)
		(end 100.5332 1.3716)
		(width 0.1016)
		(layer "B.Cu")
		(net "SMCLK_BMC_SLOT2")
	)
	(segment
		(start 98.7806 1.3716)
		(end 99.7712 1.3716)
		(width 0.1016)
		(layer "B.Cu")
		(net "SMCLK_BMC_SLOT2")
	)
	(segment
		(start 98.6282 1.524)
		(end 98.7806 1.3716)
		(width 0.1016)
		(layer "B.Cu")
		(net "SMCLK_BMC_SLOT2")
	)
	(segment
		(start 100.9142 1.7526)
		(end 102.0191 1.7526)
		(width 0.1016)
		(layer "B.Cu")
		(net "SMCLK_BMC_SLOT2")
	)
	(segment
		(start 103.381048 1.6764)
		(end 102.4255 1.6764)
		(width 0.1016)
		(layer "B.Cu")
		(net "SMCLK_BMC_SLOT2")
	)
	(segment
		(start 100.5332 1.3716)
		(end 100.9142 1.7526)
		(width 0.1016)
		(layer "B.Cu")
		(net "SMCLK_BMC_SLOT2")
	)
	(segment
		(start 102.0191 1.7526)
		(end 102.2604 1.5113)
		(width 0.1016)
		(layer "B.Cu")
		(net "SMCLK_BMC_SLOT2")
	)
	(segment
		(start 105.331768 -0.27432)
		(end 103.381048 1.6764)
		(width 0.1016)
		(layer "B.Cu")
		(net "SMCLK_BMC_SLOT2")
	)
	(segment
		(start 42.7482 -1.0922)
		(end 44.30014 0.45974)
		(width 0.1016)
		(layer "B.Cu")
		(net "SMCLK_BMC_SLOT2")
	)
	(segment
		(start 102.4255 1.6764)
		(end 102.2604 1.5113)
		(width 0.1016)
		(layer "B.Cu")
		(net "SMCLK_BMC_SLOT2")
	)
	(segment
		(start 44.30014 0.45974)
		(end 44.7802 0.45974)
		(width 0.1016)
		(layer "B.Cu")
		(net "SMCLK_BMC_SLOT2")
	)
	(segment
		(start 106.8578 -0.27432)
		(end 105.331768 -0.27432)
		(width 0.1016)
		(layer "B.Cu")
		(net "SMCLK_BMC_SLOT2")
	)
	(segment
		(start 45.676566 0.9144)
		(end 46.324266 1.5621)
		(width 0.127)
		(layer "In3.Cu")
		(net "SMCLK_BMC_SLOT2")
	)
	(segment
		(start 45.23486 0.9144)
		(end 45.676566 0.9144)
		(width 0.127)
		(layer "In3.Cu")
		(net "SMCLK_BMC_SLOT2")
	)
	(segment
		(start 46.324266 1.5621)
		(end 98.5901 1.5621)
		(width 0.127)
		(layer "In3.Cu")
		(net "SMCLK_BMC_SLOT2")
	)
	(segment
		(start 44.7802 0.45974)
		(end 45.23486 0.9144)
		(width 0.127)
		(layer "In3.Cu")
		(net "SMCLK_BMC_SLOT2")
	)
	(segment
		(start 98.5901 1.5621)
		(end 98.6282 1.524)
		(width 0.127)
		(layer "In3.Cu")
		(net "SMCLK_BMC_SLOT2")
	)
	(via
		(at 114.7953 1.2827)
		(size 0.7112)
		(drill 0.3556)
		(layers "F.Cu" "B.Cu")
		(net "SMCLK_BMC_R")
	)
	(segment
		(start 113.919 1.2573)
		(end 113.4999 1.6764)
		(width 0.1016)
		(layer "B.Cu")
		(net "SMCLK_BMC_R")
	)
	(segment
		(start 114.7953 1.2827)
		(end 114.7699 1.2573)
		(width 0.1016)
		(layer "B.Cu")
		(net "SMCLK_BMC_R")
	)
	(segment
		(start 108.498386 4.445)
		(end 107.8865 4.445)
		(width 0.1016)
		(layer "B.Cu")
		(net "SMCLK_BMC_R")
	)
	(segment
		(start 112.4966 1.6764)
		(end 111.568738 1.6764)
		(width 0.1016)
		(layer "B.Cu")
		(net "SMCLK_BMC_R")
	)
	(segment
		(start 114.7699 1.2573)
		(end 113.919 1.2573)
		(width 0.1016)
		(layer "B.Cu")
		(net "SMCLK_BMC_R")
	)
	(segment
		(start 111.568738 1.6764)
		(end 111.484918 1.76022)
		(width 0.1016)
		(layer "B.Cu")
		(net "SMCLK_BMC_R")
	)
	(segment
		(start 111.484918 1.76022)
		(end 111.183166 1.76022)
		(width 0.1016)
		(layer "B.Cu")
		(net "SMCLK_BMC_R")
	)
	(segment
		(start 113.4999 1.6764)
		(end 112.4966 1.6764)
		(width 0.1016)
		(layer "B.Cu")
		(net "SMCLK_BMC_R")
	)
	(segment
		(start 107.8865 4.445)
		(end 107.6071 4.1656)
		(width 0.1016)
		(layer "B.Cu")
		(net "SMCLK_BMC_R")
	)
	(segment
		(start 111.183166 1.76022)
		(end 108.498386 4.445)
		(width 0.1016)
		(layer "B.Cu")
		(net "SMCLK_BMC_R")
	)
	(segment
		(start 24.6253 -19.0754)
		(end 24.8412 -19.0754)
		(width 0.1016)
		(layer "F.Cu")
		(net "SMCLK_BMC_DEVICE")
	)
	(segment
		(start 130.2004 -20.2565)
		(end 130.2004 -21.1328)
		(width 0.1016)
		(layer "F.Cu")
		(net "SMCLK_BMC_DEVICE")
	)
	(segment
		(start 25.7175 -20.9296)
		(end 26.0731 -21.2852)
		(width 0.1016)
		(layer "F.Cu")
		(net "SMCLK_BMC_DEVICE")
	)
	(segment
		(start 26.0731 -21.2852)
		(end 28.007564 -21.2852)
		(width 0.1016)
		(layer "F.Cu")
		(net "SMCLK_BMC_DEVICE")
	)
	(segment
		(start 24.5491 -18.9992)
		(end 24.6253 -19.0754)
		(width 0.1016)
		(layer "F.Cu")
		(net "SMCLK_BMC_DEVICE")
	)
	(segment
		(start 24.8412 -19.0754)
		(end 25.654 -19.8882)
		(width 0.1016)
		(layer "F.Cu")
		(net "SMCLK_BMC_DEVICE")
	)
	(segment
		(start 28.007564 -21.2852)
		(end 28.134564 -21.1582)
		(width 0.1016)
		(layer "F.Cu")
		(net "SMCLK_BMC_DEVICE")
	)
	(segment
		(start 25.654 -20.8661)
		(end 25.7175 -20.9296)
		(width 0.1016)
		(layer "F.Cu")
		(net "SMCLK_BMC_DEVICE")
	)
	(segment
		(start 25.654 -19.8882)
		(end 25.654 -20.8661)
		(width 0.1016)
		(layer "F.Cu")
		(net "SMCLK_BMC_DEVICE")
	)
	(via
		(at 130.2004 -21.1328)
		(size 0.508)
		(drill 0.254)
		(layers "F.Cu" "B.Cu")
		(net "SMCLK_BMC_DEVICE")
	)
	(via
		(at 129.7178 -16.9291)
		(size 0.7112)
		(drill 0.3556)
		(layers "F.Cu" "B.Cu")
		(net "SMCLK_BMC_DEVICE")
	)
	(via
		(at 129.8702 -15.113)
		(size 0.508)
		(drill 0.254)
		(layers "F.Cu" "B.Cu")
		(net "SMCLK_BMC_DEVICE")
	)
	(via
		(at 24.5491 -18.9992)
		(size 0.508)
		(drill 0.254)
		(layers "F.Cu" "B.Cu")
		(net "SMCLK_BMC_DEVICE")
	)
	(via
		(at 28.134564 -21.1582)
		(size 0.508)
		(drill 0.254)
		(layers "F.Cu" "B.Cu")
		(net "SMCLK_BMC_DEVICE")
	)
	(segment
		(start 23.1267 -19.5453)
		(end 23.1267 -18.5166)
		(width 0.1016)
		(layer "B.Cu")
		(net "SMCLK_BMC_DEVICE")
	)
	(segment
		(start 119.3165 -2.960116)
		(end 119.3165 -10.1981)
		(width 0.1016)
		(layer "B.Cu")
		(net "SMCLK_BMC_DEVICE")
	)
	(segment
		(start 128.4351 -14.4653)
		(end 129.0193 -14.4653)
		(width 0.1016)
		(layer "B.Cu")
		(net "SMCLK_BMC_DEVICE")
	)
	(segment
		(start 130.2766 -21.209)
		(end 130.2004 -21.1328)
		(width 0.1016)
		(layer "B.Cu")
		(net "SMCLK_BMC_DEVICE")
	)
	(segment
		(start 129.0193 -14.4653)
		(end 129.667 -15.113)
		(width 0.1016)
		(layer "B.Cu")
		(net "SMCLK_BMC_DEVICE")
	)
	(segment
		(start 24.5491 -18.9992)
		(end 24.4856 -19.0627)
		(width 0.1016)
		(layer "B.Cu")
		(net "SMCLK_BMC_DEVICE")
	)
	(segment
		(start 117.5258 1.1049)
		(end 117.6909 1.1049)
		(width 0.1016)
		(layer "B.Cu")
		(net "SMCLK_BMC_DEVICE")
	)
	(segment
		(start 129.8702 -15.185898)
		(end 129.8702 -15.113)
		(width 0.1016)
		(layer "B.Cu")
		(net "SMCLK_BMC_DEVICE")
	)
	(segment
		(start 24.4856 -19.0627)
		(end 23.8379 -19.0627)
		(width 0.1016)
		(layer "B.Cu")
		(net "SMCLK_BMC_DEVICE")
	)
	(segment
		(start 125.109986 -14.0208)
		(end 125.247146 -13.88364)
		(width 0.1016)
		(layer "B.Cu")
		(net "SMCLK_BMC_DEVICE")
	)
	(segment
		(start 117.4496 1.1811)
		(end 117.5258 1.1049)
		(width 0.1016)
		(layer "B.Cu")
		(net "SMCLK_BMC_DEVICE")
	)
	(segment
		(start 129.794 -18.678652)
		(end 129.7178 -18.602452)
		(width 0.1016)
		(layer "B.Cu")
		(net "SMCLK_BMC_DEVICE")
	)
	(segment
		(start 113.539016 0.37592)
		(end 112.4966 0.37592)
		(width 0.1016)
		(layer "B.Cu")
		(net "SMCLK_BMC_DEVICE")
	)
	(segment
		(start 119.3165 -10.1981)
		(end 123.1392 -14.0208)
		(width 0.1016)
		(layer "B.Cu")
		(net "SMCLK_BMC_DEVICE")
	)
	(segment
		(start 129.667 -15.113)
		(end 129.8702 -15.113)
		(width 0.1016)
		(layer "B.Cu")
		(net "SMCLK_BMC_DEVICE")
	)
	(segment
		(start 23.1267 -18.5166)
		(end 23.1394 -18.5039)
		(width 0.1016)
		(layer "B.Cu")
		(net "SMCLK_BMC_DEVICE")
	)
	(segment
		(start 116.9162 0.6477)
		(end 113.810796 0.6477)
		(width 0.1016)
		(layer "B.Cu")
		(net "SMCLK_BMC_DEVICE")
	)
	(segment
		(start 129.7178 -16.9291)
		(end 129.8956 -16.7513)
		(width 0.1016)
		(layer "B.Cu")
		(net "SMCLK_BMC_DEVICE")
	)
	(segment
		(start 119.2911 -0.4953)
		(end 119.2911 -2.934716)
		(width 0.1016)
		(layer "B.Cu")
		(net "SMCLK_BMC_DEVICE")
	)
	(segment
		(start 130.2766 -21.9583)
		(end 130.2766 -21.209)
		(width 0.1016)
		(layer "B.Cu")
		(net "SMCLK_BMC_DEVICE")
	)
	(segment
		(start 117.6909 1.1049)
		(end 119.2911 -0.4953)
		(width 0.1016)
		(layer "B.Cu")
		(net "SMCLK_BMC_DEVICE")
	)
	(segment
		(start 23.8379 -19.0627)
		(end 23.2791 -18.5039)
		(width 0.1016)
		(layer "B.Cu")
		(net "SMCLK_BMC_DEVICE")
	)
	(segment
		(start 117.4496 1.1811)
		(end 116.9162 0.6477)
		(width 0.1016)
		(layer "B.Cu")
		(net "SMCLK_BMC_DEVICE")
	)
	(segment
		(start 129.7178 -18.602452)
		(end 129.7178 -16.9291)
		(width 0.1016)
		(layer "B.Cu")
		(net "SMCLK_BMC_DEVICE")
	)
	(segment
		(start 129.794 -20.7264)
		(end 129.794 -18.678652)
		(width 0.1016)
		(layer "B.Cu")
		(net "SMCLK_BMC_DEVICE")
	)
	(segment
		(start 129.8956 -15.211298)
		(end 129.8702 -15.185898)
		(width 0.1016)
		(layer "B.Cu")
		(net "SMCLK_BMC_DEVICE")
	)
	(segment
		(start 113.810796 0.6477)
		(end 113.539016 0.37592)
		(width 0.1016)
		(layer "B.Cu")
		(net "SMCLK_BMC_DEVICE")
	)
	(segment
		(start 125.247146 -13.88364)
		(end 127.85344 -13.88364)
		(width 0.1016)
		(layer "B.Cu")
		(net "SMCLK_BMC_DEVICE")
	)
	(segment
		(start 130.2004 -21.1328)
		(end 129.794 -20.7264)
		(width 0.1016)
		(layer "B.Cu")
		(net "SMCLK_BMC_DEVICE")
	)
	(segment
		(start 129.8956 -16.7513)
		(end 129.8956 -15.211298)
		(width 0.1016)
		(layer "B.Cu")
		(net "SMCLK_BMC_DEVICE")
	)
	(segment
		(start 127.85344 -13.88364)
		(end 128.4351 -14.4653)
		(width 0.1016)
		(layer "B.Cu")
		(net "SMCLK_BMC_DEVICE")
	)
	(segment
		(start 123.1392 -14.0208)
		(end 125.109986 -14.0208)
		(width 0.1016)
		(layer "B.Cu")
		(net "SMCLK_BMC_DEVICE")
	)
	(segment
		(start 23.2791 -18.5039)
		(end 23.1394 -18.5039)
		(width 0.1016)
		(layer "B.Cu")
		(net "SMCLK_BMC_DEVICE")
	)
	(segment
		(start 119.2911 -2.934716)
		(end 119.3165 -2.960116)
		(width 0.1016)
		(layer "B.Cu")
		(net "SMCLK_BMC_DEVICE")
	)
	(segment
		(start 28.2194 -21.1582)
		(end 30.1752 -19.2024)
		(width 0.127)
		(layer "In3.Cu")
		(net "SMCLK_BMC_DEVICE")
	)
	(segment
		(start 121.585482 -18.3896)
		(end 124.493782 -15.4813)
		(width 0.127)
		(layer "In3.Cu")
		(net "SMCLK_BMC_DEVICE")
	)
	(segment
		(start 41.978834 -24.892)
		(end 52.643532 -24.892)
		(width 0.127)
		(layer "In3.Cu")
		(net "SMCLK_BMC_DEVICE")
	)
	(segment
		(start 52.643532 -24.892)
		(end 57.558432 -19.9771)
		(width 0.127)
		(layer "In3.Cu")
		(net "SMCLK_BMC_DEVICE")
	)
	(segment
		(start 128.707134 -15.5575)
		(end 129.4257 -15.5575)
		(width 0.127)
		(layer "In3.Cu")
		(net "SMCLK_BMC_DEVICE")
	)
	(segment
		(start 30.1752 -19.2024)
		(end 36.289234 -19.2024)
		(width 0.127)
		(layer "In3.Cu")
		(net "SMCLK_BMC_DEVICE")
	)
	(segment
		(start 28.134564 -21.1582)
		(end 28.2194 -21.1582)
		(width 0.127)
		(layer "In3.Cu")
		(net "SMCLK_BMC_DEVICE")
	)
	(segment
		(start 114.231166 -18.3896)
		(end 121.585482 -18.3896)
		(width 0.127)
		(layer "In3.Cu")
		(net "SMCLK_BMC_DEVICE")
	)
	(segment
		(start 129.4257 -15.5575)
		(end 129.8702 -15.113)
		(width 0.127)
		(layer "In3.Cu")
		(net "SMCLK_BMC_DEVICE")
	)
	(segment
		(start 36.289234 -19.2024)
		(end 41.978834 -24.892)
		(width 0.127)
		(layer "In3.Cu")
		(net "SMCLK_BMC_DEVICE")
	)
	(segment
		(start 110.51794 -19.9771)
		(end 110.617254 -20.076414)
		(width 0.127)
		(layer "In3.Cu")
		(net "SMCLK_BMC_DEVICE")
	)
	(segment
		(start 57.558432 -19.9771)
		(end 110.51794 -19.9771)
		(width 0.127)
		(layer "In3.Cu")
		(net "SMCLK_BMC_DEVICE")
	)
	(segment
		(start 124.493782 -15.4813)
		(end 128.630934 -15.4813)
		(width 0.127)
		(layer "In3.Cu")
		(net "SMCLK_BMC_DEVICE")
	)
	(segment
		(start 128.630934 -15.4813)
		(end 128.707134 -15.5575)
		(width 0.127)
		(layer "In3.Cu")
		(net "SMCLK_BMC_DEVICE")
	)
	(segment
		(start 112.544352 -20.076414)
		(end 114.231166 -18.3896)
		(width 0.127)
		(layer "In3.Cu")
		(net "SMCLK_BMC_DEVICE")
	)
	(segment
		(start 110.617254 -20.076414)
		(end 112.544352 -20.076414)
		(width 0.127)
		(layer "In3.Cu")
		(net "SMCLK_BMC_DEVICE")
	)
	(via
		(at 24.1808 -20.7772)
		(size 0.7112)
		(drill 0.3556)
		(layers "F.Cu" "B.Cu")
		(net "SMB_VMONITOR_ATX_MUX_SDA")
	)
	(segment
		(start 24.1681 -19.812)
		(end 24.1808 -19.7993)
		(width 0.1016)
		(layer "B.Cu")
		(net "SMB_VMONITOR_ATX_MUX_SDA")
	)
	(segment
		(start 23.801324 -21.207476)
		(end 24.1808 -20.828)
		(width 0.1016)
		(layer "B.Cu")
		(net "SMB_VMONITOR_ATX_MUX_SDA")
	)
	(segment
		(start 24.1808 -20.7772)
		(end 24.1681 -20.7645)
		(width 0.1016)
		(layer "B.Cu")
		(net "SMB_VMONITOR_ATX_MUX_SDA")
	)
	(segment
		(start 23.801324 -23.151338)
		(end 23.801324 -21.207476)
		(width 0.1016)
		(layer "B.Cu")
		(net "SMB_VMONITOR_ATX_MUX_SDA")
	)
	(segment
		(start 24.1808 -20.828)
		(end 24.1808 -20.7772)
		(width 0.1016)
		(layer "B.Cu")
		(net "SMB_VMONITOR_ATX_MUX_SDA")
	)
	(segment
		(start 24.1681 -20.7645)
		(end 24.1681 -19.812)
		(width 0.1016)
		(layer "B.Cu")
		(net "SMB_VMONITOR_ATX_MUX_SDA")
	)
	(via
		(at 22.1996 -20.8026)
		(size 0.7112)
		(drill 0.3556)
		(layers "F.Cu" "B.Cu")
		(net "SMB_VMONITOR_ATX_MUX_SCL")
	)
	(segment
		(start 22.5679 -20.4343)
		(end 22.1996 -20.8026)
		(width 0.1016)
		(layer "B.Cu")
		(net "SMB_VMONITOR_ATX_MUX_SCL")
	)
	(segment
		(start 22.1996 -20.9677)
		(end 22.1996 -20.8026)
		(width 0.1016)
		(layer "B.Cu")
		(net "SMB_VMONITOR_ATX_MUX_SCL")
	)
	(segment
		(start 23.1267 -20.4343)
		(end 22.5679 -20.4343)
		(width 0.1016)
		(layer "B.Cu")
		(net "SMB_VMONITOR_ATX_MUX_SCL")
	)
	(segment
		(start 23.000462 -22.350476)
		(end 23.000462 -21.768562)
		(width 0.1016)
		(layer "B.Cu")
		(net "SMB_VMONITOR_ATX_MUX_SCL")
	)
	(segment
		(start 23.000462 -21.768562)
		(end 22.1996 -20.9677)
		(width 0.1016)
		(layer "B.Cu")
		(net "SMB_VMONITOR_ATX_MUX_SCL")
	)
	(via
		(at 120.904 -13.589)
		(size 0.7112)
		(drill 0.3556)
		(layers "F.Cu" "B.Cu")
		(net "SMB_U_REPEATER_EN")
	)
	(segment
		(start 122.48134 -14.728444)
		(end 121.341896 -13.589)
		(width 0.1016)
		(layer "B.Cu")
		(net "SMB_U_REPEATER_EN")
	)
	(segment
		(start 120.3833 -14.6304)
		(end 120.3833 -14.1097)
		(width 0.1016)
		(layer "B.Cu")
		(net "SMB_U_REPEATER_EN")
	)
	(segment
		(start 121.341896 -13.589)
		(end 120.904 -13.589)
		(width 0.1016)
		(layer "B.Cu")
		(net "SMB_U_REPEATER_EN")
	)
	(segment
		(start 122.48134 -14.95044)
		(end 122.48134 -14.728444)
		(width 0.1016)
		(layer "B.Cu")
		(net "SMB_U_REPEATER_EN")
	)
	(segment
		(start 120.3833 -14.1097)
		(end 120.904 -13.589)
		(width 0.1016)
		(layer "B.Cu")
		(net "SMB_U_REPEATER_EN")
	)
	(via
		(at 35.4076 5.461)
		(size 0.7112)
		(drill 0.3556)
		(layers "F.Cu" "B.Cu")
		(net "SMB_P_REPEATER_EN")
	)
	(segment
		(start 35.5092 5.3594)
		(end 35.5092 4.7752)
		(width 0.1016)
		(layer "B.Cu")
		(net "SMB_P_REPEATER_EN")
	)
	(segment
		(start 34.4297 5.461)
		(end 35.4076 5.461)
		(width 0.1016)
		(layer "B.Cu")
		(net "SMB_P_REPEATER_EN")
	)
	(segment
		(start 35.4076 5.461)
		(end 35.5092 5.3594)
		(width 0.1016)
		(layer "B.Cu")
		(net "SMB_P_REPEATER_EN")
	)
	(segment
		(start 35.09264 4.35864)
		(end 35.09264 3.87096)
		(width 0.1016)
		(layer "B.Cu")
		(net "SMB_P_REPEATER_EN")
	)
	(segment
		(start 35.5092 4.7752)
		(end 35.09264 4.35864)
		(width 0.1016)
		(layer "B.Cu")
		(net "SMB_P_REPEATER_EN")
	)
	(via
		(at 126.3396 -10.3251)
		(size 0.7112)
		(drill 0.3556)
		(layers "F.Cu" "B.Cu")
		(net "SMB_P_HUB_A2")
	)
	(segment
		(start 126.6952 -11.2649)
		(end 126.6952 -10.6807)
		(width 0.1016)
		(layer "B.Cu")
		(net "SMB_P_HUB_A2")
	)
	(segment
		(start 126.6952 -11.2649)
		(end 125.6284 -11.2649)
		(width 0.1016)
		(layer "B.Cu")
		(net "SMB_P_HUB_A2")
	)
	(segment
		(start 125.82144 -8.8138)
		(end 125.82144 -9.80694)
		(width 0.1016)
		(layer "B.Cu")
		(net "SMB_P_HUB_A2")
	)
	(segment
		(start 126.6952 -10.6807)
		(end 126.3396 -10.3251)
		(width 0.1016)
		(layer "B.Cu")
		(net "SMB_P_HUB_A2")
	)
	(segment
		(start 125.82144 -9.80694)
		(end 126.3396 -10.3251)
		(width 0.1016)
		(layer "B.Cu")
		(net "SMB_P_HUB_A2")
	)
	(via
		(at 123.444 -9.779)
		(size 0.7112)
		(drill 0.3556)
		(layers "F.Cu" "B.Cu")
		(net "SMB_P_HUB_A1")
	)
	(segment
		(start 123.444 -9.779)
		(end 123.4948 -9.7282)
		(width 0.1016)
		(layer "B.Cu")
		(net "SMB_P_HUB_A1")
	)
	(segment
		(start 122.4153 -9.8933)
		(end 122.6566 -10.1346)
		(width 0.1016)
		(layer "B.Cu")
		(net "SMB_P_HUB_A1")
	)
	(segment
		(start 123.2789 -8.5725)
		(end 124.0536 -7.7978)
		(width 0.1016)
		(layer "B.Cu")
		(net "SMB_P_HUB_A1")
	)
	(segment
		(start 123.2789 -8.8392)
		(end 123.2789 -8.5725)
		(width 0.1016)
		(layer "B.Cu")
		(net "SMB_P_HUB_A1")
	)
	(segment
		(start 124.0536 -7.7978)
		(end 125.0442 -7.7978)
		(width 0.1016)
		(layer "B.Cu")
		(net "SMB_P_HUB_A1")
	)
	(segment
		(start 123.4948 -9.0551)
		(end 123.2789 -8.8392)
		(width 0.1016)
		(layer "B.Cu")
		(net "SMB_P_HUB_A1")
	)
	(segment
		(start 123.0884 -10.1346)
		(end 123.444 -9.779)
		(width 0.1016)
		(layer "B.Cu")
		(net "SMB_P_HUB_A1")
	)
	(segment
		(start 125.1712 -7.9248)
		(end 125.1712 -8.8138)
		(width 0.1016)
		(layer "B.Cu")
		(net "SMB_P_HUB_A1")
	)
	(segment
		(start 122.6566 -10.1346)
		(end 123.0884 -10.1346)
		(width 0.1016)
		(layer "B.Cu")
		(net "SMB_P_HUB_A1")
	)
	(segment
		(start 123.4948 -9.7282)
		(end 123.4948 -9.0551)
		(width 0.1016)
		(layer "B.Cu")
		(net "SMB_P_HUB_A1")
	)
	(segment
		(start 125.0442 -7.7978)
		(end 125.1712 -7.9248)
		(width 0.1016)
		(layer "B.Cu")
		(net "SMB_P_HUB_A1")
	)
	(via
		(at 124.8283 -10.2997)
		(size 0.7112)
		(drill 0.3556)
		(layers "F.Cu" "B.Cu")
		(net "SMB_P_HUB_A0")
	)
	(segment
		(start 124.8791 -10.3505)
		(end 124.8283 -10.2997)
		(width 0.1016)
		(layer "B.Cu")
		(net "SMB_P_HUB_A0")
	)
	(segment
		(start 124.52096 -9.99236)
		(end 124.8283 -10.2997)
		(width 0.1016)
		(layer "B.Cu")
		(net "SMB_P_HUB_A0")
	)
	(segment
		(start 124.8791 -10.9728)
		(end 124.8791 -10.3505)
		(width 0.1016)
		(layer "B.Cu")
		(net "SMB_P_HUB_A0")
	)
	(segment
		(start 123.5075 -11.1506)
		(end 123.444 -11.0871)
		(width 0.1016)
		(layer "B.Cu")
		(net "SMB_P_HUB_A0")
	)
	(segment
		(start 124.52096 -8.8138)
		(end 124.52096 -9.99236)
		(width 0.1016)
		(layer "B.Cu")
		(net "SMB_P_HUB_A0")
	)
	(segment
		(start 124.587 -11.2649)
		(end 124.4727 -11.1506)
		(width 0.1016)
		(layer "B.Cu")
		(net "SMB_P_HUB_A0")
	)
	(segment
		(start 124.587 -11.2649)
		(end 124.8791 -10.9728)
		(width 0.1016)
		(layer "B.Cu")
		(net "SMB_P_HUB_A0")
	)
	(segment
		(start 124.4727 -11.1506)
		(end 123.5075 -11.1506)
		(width 0.1016)
		(layer "B.Cu")
		(net "SMB_P_HUB_A0")
	)
	(segment
		(start 105.3084 1.5494)
		(end 105.5878 1.27)
		(width 0.1016)
		(layer "F.Cu")
		(net "SMB_B_HUB_A2")
	)
	(segment
		(start 106.5784 0.7493)
		(end 106.1085 0.7493)
		(width 0.1016)
		(layer "F.Cu")
		(net "SMB_B_HUB_A2")
	)
	(segment
		(start 105.3084 2.3241)
		(end 105.3084 1.5494)
		(width 0.1016)
		(layer "F.Cu")
		(net "SMB_B_HUB_A2")
	)
	(segment
		(start 106.1085 0.7493)
		(end 105.5878 1.27)
		(width 0.1016)
		(layer "F.Cu")
		(net "SMB_B_HUB_A2")
	)
	(via
		(at 105.5878 1.27)
		(size 0.508)
		(drill 0.254)
		(layers "F.Cu" "B.Cu")
		(net "SMB_B_HUB_A2")
	)
	(via
		(at 104.8385 1.9431)
		(size 0.7112)
		(drill 0.3556)
		(layers "F.Cu" "B.Cu")
		(net "SMB_B_HUB_A2")
	)
	(segment
		(start 105.5116 1.27)
		(end 105.5878 1.27)
		(width 0.1016)
		(layer "B.Cu")
		(net "SMB_B_HUB_A2")
	)
	(segment
		(start 104.8385 1.9431)
		(end 105.5116 1.27)
		(width 0.1016)
		(layer "B.Cu")
		(net "SMB_B_HUB_A2")
	)
	(segment
		(start 105.6386 1.3462)
		(end 105.6386 1.3208)
		(width 0.1016)
		(layer "B.Cu")
		(net "SMB_B_HUB_A2")
	)
	(segment
		(start 105.6386 1.3208)
		(end 105.5878 1.27)
		(width 0.1016)
		(layer "B.Cu")
		(net "SMB_B_HUB_A2")
	)
	(segment
		(start 105.9688 1.6764)
		(end 105.6386 1.3462)
		(width 0.1016)
		(layer "B.Cu")
		(net "SMB_B_HUB_A2")
	)
	(segment
		(start 106.8578 1.6764)
		(end 105.9688 1.6764)
		(width 0.1016)
		(layer "B.Cu")
		(net "SMB_B_HUB_A2")
	)
	(segment
		(start 107.7468 2.7051)
		(end 107.7468 2.3368)
		(width 0.1016)
		(layer "F.Cu")
		(net "SMB_B_HUB_A1")
	)
	(segment
		(start 107.8865 0.7239)
		(end 107.1372 1.4732)
		(width 0.1016)
		(layer "F.Cu")
		(net "SMB_B_HUB_A1")
	)
	(segment
		(start 108.1532 0.7239)
		(end 108.1532 1.7272)
		(width 0.1016)
		(layer "F.Cu")
		(net "SMB_B_HUB_A1")
	)
	(segment
		(start 107.1372 1.4732)
		(end 107.1372 1.7272)
		(width 0.1016)
		(layer "F.Cu")
		(net "SMB_B_HUB_A1")
	)
	(segment
		(start 108.1532 0.7239)
		(end 107.8865 0.7239)
		(width 0.1016)
		(layer "F.Cu")
		(net "SMB_B_HUB_A1")
	)
	(segment
		(start 107.7468 2.3368)
		(end 107.1372 1.7272)
		(width 0.1016)
		(layer "F.Cu")
		(net "SMB_B_HUB_A1")
	)
	(via
		(at 107.1372 1.7272)
		(size 0.7112)
		(drill 0.3556)
		(layers "F.Cu" "B.Cu")
		(net "SMB_B_HUB_A1")
	)
	(via
		(at 108.1532 1.7272)
		(size 0.508)
		(drill 0.254)
		(layers "F.Cu" "B.Cu")
		(net "SMB_B_HUB_A1")
	)
	(segment
		(start 108.1532 1.7272)
		(end 107.55376 2.32664)
		(width 0.1016)
		(layer "B.Cu")
		(net "SMB_B_HUB_A1")
	)
	(segment
		(start 107.55376 2.32664)
		(end 106.8578 2.32664)
		(width 0.1016)
		(layer "B.Cu")
		(net "SMB_B_HUB_A1")
	)
	(segment
		(start 109.9566 1.6383)
		(end 109.9566 1.4859)
		(width 0.1016)
		(layer "F.Cu")
		(net "SMB_B_HUB_A0")
	)
	(segment
		(start 108.7882 2.7051)
		(end 108.7882 2.100326)
		(width 0.1016)
		(layer "F.Cu")
		(net "SMB_B_HUB_A0")
	)
	(segment
		(start 109.9566 1.4859)
		(end 109.1946 0.7239)
		(width 0.1016)
		(layer "F.Cu")
		(net "SMB_B_HUB_A0")
	)
	(segment
		(start 108.7882 2.100326)
		(end 109.002068 1.886458)
		(width 0.1016)
		(layer "F.Cu")
		(net "SMB_B_HUB_A0")
	)
	(segment
		(start 109.002068 1.886458)
		(end 109.002068 0.916432)
		(width 0.1016)
		(layer "F.Cu")
		(net "SMB_B_HUB_A0")
	)
	(segment
		(start 109.002068 0.916432)
		(end 109.1946 0.7239)
		(width 0.1016)
		(layer "F.Cu")
		(net "SMB_B_HUB_A0")
	)
	(via
		(at 109.9566 1.6383)
		(size 0.7112)
		(drill 0.3556)
		(layers "F.Cu" "B.Cu")
		(net "SMB_B_HUB_A0")
	)
	(via
		(at 109.002068 1.886458)
		(size 0.508)
		(drill 0.254)
		(layers "F.Cu" "B.Cu")
		(net "SMB_B_HUB_A0")
	)
	(segment
		(start 108.984542 1.886458)
		(end 107.89412 2.97688)
		(width 0.1016)
		(layer "B.Cu")
		(net "SMB_B_HUB_A0")
	)
	(segment
		(start 109.002068 1.886458)
		(end 108.984542 1.886458)
		(width 0.1016)
		(layer "B.Cu")
		(net "SMB_B_HUB_A0")
	)
	(segment
		(start 107.89412 2.97688)
		(end 106.8578 2.97688)
		(width 0.1016)
		(layer "B.Cu")
		(net "SMB_B_HUB_A0")
	)
	(via
		(at 130.3528 -0.3683)
		(size 0.7112)
		(drill 0.3556)
		(layers "F.Cu" "B.Cu")
		(net "PU_P_MUX_SDA2")
	)
	(segment
		(start 129.72288 -3.175)
		(end 129.72288 -1.18872)
		(width 0.1016)
		(layer "B.Cu")
		(net "PU_P_MUX_SDA2")
	)
	(segment
		(start 129.3749 -0.1143)
		(end 130.0988 -0.1143)
		(width 0.1016)
		(layer "B.Cu")
		(net "PU_P_MUX_SDA2")
	)
	(segment
		(start 129.72288 -1.18872)
		(end 130.3528 -0.5588)
		(width 0.1016)
		(layer "B.Cu")
		(net "PU_P_MUX_SDA2")
	)
	(segment
		(start 130.0988 -0.1143)
		(end 130.3528 -0.3683)
		(width 0.1016)
		(layer "B.Cu")
		(net "PU_P_MUX_SDA2")
	)
	(segment
		(start 130.3528 -0.5588)
		(end 130.3528 -0.3683)
		(width 0.1016)
		(layer "B.Cu")
		(net "PU_P_MUX_SDA2")
	)
	(via
		(at 128.9304 -1.5113)
		(size 0.7112)
		(drill 0.3556)
		(layers "F.Cu" "B.Cu")
		(net "PU_P_MUX_SCL2")
	)
	(segment
		(start 128.2827 -0.1143)
		(end 128.2827 -0.8636)
		(width 0.1016)
		(layer "B.Cu")
		(net "PU_P_MUX_SCL2")
	)
	(segment
		(start 129.07264 -1.65354)
		(end 129.07264 -3.175)
		(width 0.1016)
		(layer "B.Cu")
		(net "PU_P_MUX_SCL2")
	)
	(segment
		(start 128.9304 -1.5113)
		(end 129.07264 -1.65354)
		(width 0.1016)
		(layer "B.Cu")
		(net "PU_P_MUX_SCL2")
	)
	(segment
		(start 128.2827 -0.8636)
		(end 128.9304 -1.5113)
		(width 0.1016)
		(layer "B.Cu")
		(net "PU_P_MUX_SCL2")
	)
	(via
		(at 130.4925 -1.6891)
		(size 0.7112)
		(drill 0.3556)
		(layers "F.Cu" "B.Cu")
		(net "PU_P_I2CMUX_INT2_N")
	)
	(segment
		(start 131.318 -0.9144)
		(end 131.2672 -0.9144)
		(width 0.1016)
		(layer "B.Cu")
		(net "PU_P_I2CMUX_INT2_N")
	)
	(segment
		(start 131.2672 -0.9144)
		(end 130.4925 -1.6891)
		(width 0.1016)
		(layer "B.Cu")
		(net "PU_P_I2CMUX_INT2_N")
	)
	(segment
		(start 130.37312 -1.80848)
		(end 130.4925 -1.6891)
		(width 0.1016)
		(layer "B.Cu")
		(net "PU_P_I2CMUX_INT2_N")
	)
	(segment
		(start 130.37312 -3.175)
		(end 130.37312 -1.80848)
		(width 0.1016)
		(layer "B.Cu")
		(net "PU_P_I2CMUX_INT2_N")
	)
	(segment
		(start 113.040414 -1.788414)
		(end 112.7252 -1.4732)
		(width 0.1016)
		(layer "F.Cu")
		(net "PU_I2CMUX_INT2_N")
	)
	(segment
		(start 113.9698 -2.2606)
		(end 113.47704 -2.2606)
		(width 0.1016)
		(layer "F.Cu")
		(net "PU_I2CMUX_INT2_N")
	)
	(segment
		(start 113.47704 -2.2606)
		(end 113.040414 -1.823974)
		(width 0.1016)
		(layer "F.Cu")
		(net "PU_I2CMUX_INT2_N")
	)
	(segment
		(start 113.040414 -1.823974)
		(end 113.040414 -1.788414)
		(width 0.1016)
		(layer "F.Cu")
		(net "PU_I2CMUX_INT2_N")
	)
	(segment
		(start 112.7252 -1.4732)
		(end 112.1029 -1.4732)
		(width 0.1016)
		(layer "F.Cu")
		(net "PU_I2CMUX_INT2_N")
	)
	(via
		(at 113.040414 -1.823974)
		(size 0.7112)
		(drill 0.3556)
		(layers "F.Cu" "B.Cu")
		(net "PU_I2CMUX_INT2_N")
	)
	(via
		(at 113.9698 -2.2606)
		(size 0.508)
		(drill 0.254)
		(layers "F.Cu" "B.Cu")
		(net "PU_I2CMUX_INT2_N")
	)
	(segment
		(start 113.9698 -2.2606)
		(end 113.9698 -2.3114)
		(width 0.1016)
		(layer "B.Cu")
		(net "PU_I2CMUX_INT2_N")
	)
	(segment
		(start 113.9698 -2.3114)
		(end 113.40592 -2.87528)
		(width 0.1016)
		(layer "B.Cu")
		(net "PU_I2CMUX_INT2_N")
	)
	(segment
		(start 113.40592 -2.87528)
		(end 112.4966 -2.87528)
		(width 0.1016)
		(layer "B.Cu")
		(net "PU_I2CMUX_INT2_N")
	)
	(segment
		(start 113.6396 -0.762)
		(end 113.4872 -0.762)
		(width 0.1016)
		(layer "F.Cu")
		(net "PU_B_MUX_SDA2")
	)
	(segment
		(start 113.4872 -0.762)
		(end 112.7633 -0.0381)
		(width 0.1016)
		(layer "F.Cu")
		(net "PU_B_MUX_SDA2")
	)
	(segment
		(start 114.635788 -1.402588)
		(end 113.9952 -0.762)
		(width 0.1016)
		(layer "F.Cu")
		(net "PU_B_MUX_SDA2")
	)
	(segment
		(start 113.9952 -0.762)
		(end 113.6396 -0.762)
		(width 0.1016)
		(layer "F.Cu")
		(net "PU_B_MUX_SDA2")
	)
	(segment
		(start 112.7633 -0.0381)
		(end 112.7252 -0.0381)
		(width 0.1016)
		(layer "F.Cu")
		(net "PU_B_MUX_SDA2")
	)
	(segment
		(start 114.635788 -1.710436)
		(end 114.635788 -1.402588)
		(width 0.1016)
		(layer "F.Cu")
		(net "PU_B_MUX_SDA2")
	)
	(via
		(at 114.635788 -1.710436)
		(size 0.508)
		(drill 0.254)
		(layers "F.Cu" "B.Cu")
		(net "PU_B_MUX_SDA2")
	)
	(via
		(at 113.6396 -0.762)
		(size 0.7112)
		(drill 0.3556)
		(layers "F.Cu" "B.Cu")
		(net "PU_B_MUX_SDA2")
	)
	(segment
		(start 113.783364 -1.710436)
		(end 113.26876 -2.22504)
		(width 0.1016)
		(layer "B.Cu")
		(net "PU_B_MUX_SDA2")
	)
	(segment
		(start 114.635788 -1.710436)
		(end 113.783364 -1.710436)
		(width 0.1016)
		(layer "B.Cu")
		(net "PU_B_MUX_SDA2")
	)
	(segment
		(start 113.26876 -2.22504)
		(end 112.4966 -2.22504)
		(width 0.1016)
		(layer "B.Cu")
		(net "PU_B_MUX_SDA2")
	)
	(segment
		(start 114.6048 -0.1397)
		(end 114.6048 -0.478282)
		(width 0.1016)
		(layer "F.Cu")
		(net "PU_B_MUX_SCL2")
	)
	(segment
		(start 114.6048 -0.478282)
		(end 115.34775 -1.221232)
		(width 0.1016)
		(layer "F.Cu")
		(net "PU_B_MUX_SCL2")
	)
	(via
		(at 116.0907 -1.9558)
		(size 0.7112)
		(drill 0.3556)
		(layers "F.Cu" "B.Cu")
		(net "PU_B_MUX_SCL2")
	)
	(via
		(at 115.34775 -1.221232)
		(size 0.508)
		(drill 0.254)
		(layers "F.Cu" "B.Cu")
		(net "PU_B_MUX_SCL2")
	)
	(segment
		(start 113.868708 -1.1938)
		(end 115.320318 -1.1938)
		(width 0.1016)
		(layer "B.Cu")
		(net "PU_B_MUX_SCL2")
	)
	(segment
		(start 116.082318 -1.9558)
		(end 115.34775 -1.221232)
		(width 0.1016)
		(layer "B.Cu")
		(net "PU_B_MUX_SCL2")
	)
	(segment
		(start 115.320318 -1.1938)
		(end 115.34775 -1.221232)
		(width 0.1016)
		(layer "B.Cu")
		(net "PU_B_MUX_SCL2")
	)
	(segment
		(start 112.4966 -1.5748)
		(end 113.487708 -1.5748)
		(width 0.1016)
		(layer "B.Cu")
		(net "PU_B_MUX_SCL2")
	)
	(segment
		(start 116.0907 -1.9558)
		(end 116.082318 -1.9558)
		(width 0.1016)
		(layer "B.Cu")
		(net "PU_B_MUX_SCL2")
	)
	(segment
		(start 113.487708 -1.5748)
		(end 113.868708 -1.1938)
		(width 0.1016)
		(layer "B.Cu")
		(net "PU_B_MUX_SCL2")
	)
	(segment
		(start 67.7799 -24.5237)
		(end 68.326 -23.9776)
		(width 0.1016)
		(layer "F.Cu")
		(net "PCIE_SLOT3_PRSNT2_2_N")
	)
	(segment
		(start 120.1166 -14.2748)
		(end 122.047 -14.2748)
		(width 0.1016)
		(layer "F.Cu")
		(net "PCIE_SLOT3_PRSNT2_2_N")
	)
	(segment
		(start 65.6082 -24.5237)
		(end 65.6082 -24.765)
		(width 0.1016)
		(layer "F.Cu")
		(net "PCIE_SLOT3_PRSNT2_2_N")
	)
	(segment
		(start 63.080392 -27.292808)
		(end 63.080392 -29.570426)
		(width 0.1016)
		(layer "F.Cu")
		(net "PCIE_SLOT3_PRSNT2_2_N")
	)
	(segment
		(start 125.1712 -9.603232)
		(end 123.5964 -11.178032)
		(width 0.1016)
		(layer "F.Cu")
		(net "PCIE_SLOT3_PRSNT2_2_N")
	)
	(segment
		(start 125.1712 -8.8138)
		(end 125.1712 -9.603232)
		(width 0.1016)
		(layer "F.Cu")
		(net "PCIE_SLOT3_PRSNT2_2_N")
	)
	(segment
		(start 123.5964 -13.7668)
		(end 123.0884 -14.2748)
		(width 0.1016)
		(layer "F.Cu")
		(net "PCIE_SLOT3_PRSNT2_2_N")
	)
	(segment
		(start 112.815624 -15.3162)
		(end 115.2398 -15.3162)
		(width 0.1016)
		(layer "F.Cu")
		(net "PCIE_SLOT3_PRSNT2_2_N")
	)
	(segment
		(start 123.0884 -14.2748)
		(end 122.047 -14.2748)
		(width 0.1016)
		(layer "F.Cu")
		(net "PCIE_SLOT3_PRSNT2_2_N")
	)
	(segment
		(start 123.5964 -11.178032)
		(end 123.5964 -13.7668)
		(width 0.1016)
		(layer "F.Cu")
		(net "PCIE_SLOT3_PRSNT2_2_N")
	)
	(segment
		(start 65.6082 -24.765)
		(end 63.080392 -27.292808)
		(width 0.1016)
		(layer "F.Cu")
		(net "PCIE_SLOT3_PRSNT2_2_N")
	)
	(segment
		(start 116.7638 -13.7922)
		(end 119.634 -13.7922)
		(width 0.1016)
		(layer "F.Cu")
		(net "PCIE_SLOT3_PRSNT2_2_N")
	)
	(segment
		(start 108.143294 -23.051516)
		(end 108.143294 -19.98853)
		(width 0.1016)
		(layer "F.Cu")
		(net "PCIE_SLOT3_PRSNT2_2_N")
	)
	(segment
		(start 65.6082 -24.5237)
		(end 67.7799 -24.5237)
		(width 0.1016)
		(layer "F.Cu")
		(net "PCIE_SLOT3_PRSNT2_2_N")
	)
	(segment
		(start 108.143294 -19.98853)
		(end 112.815624 -15.3162)
		(width 0.1016)
		(layer "F.Cu")
		(net "PCIE_SLOT3_PRSNT2_2_N")
	)
	(segment
		(start 119.634 -13.7922)
		(end 120.1166 -14.2748)
		(width 0.1016)
		(layer "F.Cu")
		(net "PCIE_SLOT3_PRSNT2_2_N")
	)
	(segment
		(start 115.2398 -15.3162)
		(end 116.7638 -13.7922)
		(width 0.1016)
		(layer "F.Cu")
		(net "PCIE_SLOT3_PRSNT2_2_N")
	)
	(via
		(at 107.1626 -22.7584)
		(size 0.7112)
		(drill 0.3556)
		(layers "F.Cu" "B.Cu")
		(net "PCIE_SLOT3_PRSNT2_2_N")
	)
	(via
		(at 108.143294 -23.051516)
		(size 0.508)
		(drill 0.254)
		(layers "F.Cu" "B.Cu")
		(net "PCIE_SLOT3_PRSNT2_2_N")
	)
	(via
		(at 68.326 -23.9776)
		(size 0.508)
		(drill 0.254)
		(layers "F.Cu" "B.Cu")
		(net "PCIE_SLOT3_PRSNT2_2_N")
	)
	(segment
		(start 107.1626 -22.7584)
		(end 107.455716 -23.051516)
		(width 0.1016)
		(layer "B.Cu")
		(net "PCIE_SLOT3_PRSNT2_2_N")
	)
	(segment
		(start 107.455716 -23.051516)
		(end 108.143294 -23.051516)
		(width 0.1016)
		(layer "B.Cu")
		(net "PCIE_SLOT3_PRSNT2_2_N")
	)
	(segment
		(start 80.9117 -23.2537)
		(end 107.94111 -23.2537)
		(width 0.127)
		(layer "In3.Cu")
		(net "PCIE_SLOT3_PRSNT2_2_N")
	)
	(segment
		(start 69.6087 -22.7203)
		(end 80.3783 -22.7203)
		(width 0.127)
		(layer "In3.Cu")
		(net "PCIE_SLOT3_PRSNT2_2_N")
	)
	(segment
		(start 68.3514 -23.9776)
		(end 69.6087 -22.7203)
		(width 0.127)
		(layer "In3.Cu")
		(net "PCIE_SLOT3_PRSNT2_2_N")
	)
	(segment
		(start 107.94111 -23.2537)
		(end 108.143294 -23.051516)
		(width 0.127)
		(layer "In3.Cu")
		(net "PCIE_SLOT3_PRSNT2_2_N")
	)
	(segment
		(start 68.326 -23.9776)
		(end 68.3514 -23.9776)
		(width 0.127)
		(layer "In3.Cu")
		(net "PCIE_SLOT3_PRSNT2_2_N")
	)
	(segment
		(start 80.3783 -22.7203)
		(end 80.9117 -23.2537)
		(width 0.127)
		(layer "In3.Cu")
		(net "PCIE_SLOT3_PRSNT2_2_N")
	)
	(segment
		(start 117.3734 -14.097)
		(end 119.507508 -14.097)
		(width 0.1016)
		(layer "F.Cu")
		(net "PCIE_SLOT3_PRSNT2_1_N")
	)
	(segment
		(start 108.6612 -19.901916)
		(end 112.942116 -15.621)
		(width 0.1016)
		(layer "F.Cu")
		(net "PCIE_SLOT3_PRSNT2_1_N")
	)
	(segment
		(start 80.9752 -21.971)
		(end 80.899 -21.8948)
		(width 0.1016)
		(layer "F.Cu")
		(net "PCIE_SLOT3_PRSNT2_1_N")
	)
	(segment
		(start 119.6213 -14.210792)
		(end 119.6213 -14.5542)
		(width 0.1016)
		(layer "F.Cu")
		(net "PCIE_SLOT3_PRSNT2_1_N")
	)
	(segment
		(start 108.6612 -22.360382)
		(end 108.6612 -19.901916)
		(width 0.1016)
		(layer "F.Cu")
		(net "PCIE_SLOT3_PRSNT2_1_N")
	)
	(segment
		(start 119.507508 -14.097)
		(end 119.6213 -14.210792)
		(width 0.1016)
		(layer "F.Cu")
		(net "PCIE_SLOT3_PRSNT2_1_N")
	)
	(segment
		(start 112.942116 -15.621)
		(end 115.8494 -15.621)
		(width 0.1016)
		(layer "F.Cu")
		(net "PCIE_SLOT3_PRSNT2_1_N")
	)
	(segment
		(start 61.8998 -21.8948)
		(end 57.6326 -26.162)
		(width 0.1016)
		(layer "F.Cu")
		(net "PCIE_SLOT3_PRSNT2_1_N")
	)
	(segment
		(start 51.5112 -26.162)
		(end 51.054 -26.6192)
		(width 0.1016)
		(layer "F.Cu")
		(net "PCIE_SLOT3_PRSNT2_1_N")
	)
	(segment
		(start 122.047 -14.92504)
		(end 119.99214 -14.92504)
		(width 0.1016)
		(layer "F.Cu")
		(net "PCIE_SLOT3_PRSNT2_1_N")
	)
	(segment
		(start 125.82144 -8.8138)
		(end 125.82144 -9.384284)
		(width 0.1016)
		(layer "F.Cu")
		(net "PCIE_SLOT3_PRSNT2_1_N")
	)
	(segment
		(start 125.82144 -9.384284)
		(end 123.9012 -11.304524)
		(width 0.1016)
		(layer "F.Cu")
		(net "PCIE_SLOT3_PRSNT2_1_N")
	)
	(segment
		(start 119.99214 -14.92504)
		(end 119.6213 -14.5542)
		(width 0.1016)
		(layer "F.Cu")
		(net "PCIE_SLOT3_PRSNT2_1_N")
	)
	(segment
		(start 123.9012 -11.304524)
		(end 123.9012 -14.45514)
		(width 0.1016)
		(layer "F.Cu")
		(net "PCIE_SLOT3_PRSNT2_1_N")
	)
	(segment
		(start 123.4313 -14.92504)
		(end 122.047 -14.92504)
		(width 0.1016)
		(layer "F.Cu")
		(net "PCIE_SLOT3_PRSNT2_1_N")
	)
	(segment
		(start 123.9012 -14.45514)
		(end 123.4313 -14.92504)
		(width 0.1016)
		(layer "F.Cu")
		(net "PCIE_SLOT3_PRSNT2_1_N")
	)
	(segment
		(start 80.899 -21.8948)
		(end 61.8998 -21.8948)
		(width 0.1016)
		(layer "F.Cu")
		(net "PCIE_SLOT3_PRSNT2_1_N")
	)
	(segment
		(start 115.8494 -15.621)
		(end 117.3734 -14.097)
		(width 0.1016)
		(layer "F.Cu")
		(net "PCIE_SLOT3_PRSNT2_1_N")
	)
	(segment
		(start 49.448974 -29.570426)
		(end 49.079912 -29.570426)
		(width 0.1016)
		(layer "F.Cu")
		(net "PCIE_SLOT3_PRSNT2_1_N")
	)
	(segment
		(start 51.054 -27.9654)
		(end 49.448974 -29.570426)
		(width 0.1016)
		(layer "F.Cu")
		(net "PCIE_SLOT3_PRSNT2_1_N")
	)
	(segment
		(start 57.6326 -26.162)
		(end 51.5112 -26.162)
		(width 0.1016)
		(layer "F.Cu")
		(net "PCIE_SLOT3_PRSNT2_1_N")
	)
	(segment
		(start 51.054 -26.6192)
		(end 51.054 -27.9654)
		(width 0.1016)
		(layer "F.Cu")
		(net "PCIE_SLOT3_PRSNT2_1_N")
	)
	(via
		(at 109.7026 -22.360382)
		(size 0.7112)
		(drill 0.3556)
		(layers "F.Cu" "B.Cu")
		(net "PCIE_SLOT3_PRSNT2_1_N")
	)
	(via
		(at 80.9752 -21.971)
		(size 0.508)
		(drill 0.254)
		(layers "F.Cu" "B.Cu")
		(net "PCIE_SLOT3_PRSNT2_1_N")
	)
	(via
		(at 108.6612 -22.360382)
		(size 0.508)
		(drill 0.254)
		(layers "F.Cu" "B.Cu")
		(net "PCIE_SLOT3_PRSNT2_1_N")
	)
	(segment
		(start 109.7026 -22.360382)
		(end 108.6612 -22.360382)
		(width 0.1016)
		(layer "B.Cu")
		(net "PCIE_SLOT3_PRSNT2_1_N")
	)
	(segment
		(start 81.2165 -22.2123)
		(end 108.513118 -22.2123)
		(width 0.127)
		(layer "In3.Cu")
		(net "PCIE_SLOT3_PRSNT2_1_N")
	)
	(segment
		(start 108.513118 -22.2123)
		(end 108.6612 -22.360382)
		(width 0.127)
		(layer "In3.Cu")
		(net "PCIE_SLOT3_PRSNT2_1_N")
	)
	(segment
		(start 80.9752 -21.971)
		(end 81.2165 -22.2123)
		(width 0.127)
		(layer "In3.Cu")
		(net "PCIE_SLOT3_PRSNT2_1_N")
	)
	(segment
		(start 119.786146 -17.246854)
		(end 119.8118 -17.2212)
		(width 0.1016)
		(layer "F.Cu")
		(net "PCIE_SLOT2_PRSNT2_3_N")
	)
	(segment
		(start 127.12192 -8.8138)
		(end 127.12192 -9.578848)
		(width 0.1016)
		(layer "F.Cu")
		(net "PCIE_SLOT2_PRSNT2_3_N")
	)
	(segment
		(start 118.22176 -16.96974)
		(end 118.498874 -17.246854)
		(width 0.1016)
		(layer "F.Cu")
		(net "PCIE_SLOT2_PRSNT2_3_N")
	)
	(segment
		(start 113.76914 -16.96974)
		(end 118.22176 -16.96974)
		(width 0.1016)
		(layer "F.Cu")
		(net "PCIE_SLOT2_PRSNT2_3_N")
	)
	(segment
		(start 119.8118 -17.2085)
		(end 120.3833 -16.637)
		(width 0.1016)
		(layer "F.Cu")
		(net "PCIE_SLOT2_PRSNT2_3_N")
	)
	(segment
		(start 123.06808 -16.22552)
		(end 122.047 -16.22552)
		(width 0.1016)
		(layer "F.Cu")
		(net "PCIE_SLOT2_PRSNT2_3_N")
	)
	(segment
		(start 113.0046 -16.2052)
		(end 113.76914 -16.96974)
		(width 0.1016)
		(layer "F.Cu")
		(net "PCIE_SLOT2_PRSNT2_3_N")
	)
	(segment
		(start 119.8118 -17.2212)
		(end 119.8118 -17.2085)
		(width 0.1016)
		(layer "F.Cu")
		(net "PCIE_SLOT2_PRSNT2_3_N")
	)
	(segment
		(start 124.5108 -14.7828)
		(end 123.06808 -16.22552)
		(width 0.1016)
		(layer "F.Cu")
		(net "PCIE_SLOT2_PRSNT2_3_N")
	)
	(segment
		(start 127.12192 -9.578848)
		(end 124.5108 -12.189968)
		(width 0.1016)
		(layer "F.Cu")
		(net "PCIE_SLOT2_PRSNT2_3_N")
	)
	(segment
		(start 118.498874 -17.246854)
		(end 119.786146 -17.246854)
		(width 0.1016)
		(layer "F.Cu")
		(net "PCIE_SLOT2_PRSNT2_3_N")
	)
	(segment
		(start 122.047 -16.22552)
		(end 120.79478 -16.22552)
		(width 0.1016)
		(layer "F.Cu")
		(net "PCIE_SLOT2_PRSNT2_3_N")
	)
	(segment
		(start 120.79478 -16.22552)
		(end 120.3833 -16.637)
		(width 0.1016)
		(layer "F.Cu")
		(net "PCIE_SLOT2_PRSNT2_3_N")
	)
	(segment
		(start 124.5108 -12.189968)
		(end 124.5108 -14.7828)
		(width 0.1016)
		(layer "F.Cu")
		(net "PCIE_SLOT2_PRSNT2_3_N")
	)
	(via
		(at 113.0046 -16.2052)
		(size 0.508)
		(drill 0.254)
		(layers "F.Cu" "B.Cu")
		(net "PCIE_SLOT2_PRSNT2_3_N")
	)
	(via
		(at 113.9444 -16.8402)
		(size 0.7112)
		(drill 0.3556)
		(layers "F.Cu" "B.Cu")
		(net "PCIE_SLOT2_PRSNT2_3_N")
	)
	(segment
		(start 113.9444 -16.8402)
		(end 113.6396 -16.8402)
		(width 0.1016)
		(layer "B.Cu")
		(net "PCIE_SLOT2_PRSNT2_3_N")
	)
	(segment
		(start 113.6396 -16.8402)
		(end 113.0046 -16.2052)
		(width 0.1016)
		(layer "B.Cu")
		(net "PCIE_SLOT2_PRSNT2_3_N")
	)
	(segment
		(start 81.1149 -14.2113)
		(end 81.9912 -15.0876)
		(width 0.127)
		(layer "In3.Cu")
		(net "PCIE_SLOT2_PRSNT2_3_N")
	)
	(segment
		(start 81.9912 -15.0876)
		(end 111.887 -15.0876)
		(width 0.127)
		(layer "In3.Cu")
		(net "PCIE_SLOT2_PRSNT2_3_N")
	)
	(segment
		(start 81.1149 -13.2334)
		(end 81.1149 -14.2113)
		(width 0.127)
		(layer "In3.Cu")
		(net "PCIE_SLOT2_PRSNT2_3_N")
	)
	(segment
		(start 80.079342 -7.250176)
		(end 80.079342 -12.197842)
		(width 0.127)
		(layer "In3.Cu")
		(net "PCIE_SLOT2_PRSNT2_3_N")
	)
	(segment
		(start 111.887 -15.0876)
		(end 113.0046 -16.2052)
		(width 0.127)
		(layer "In3.Cu")
		(net "PCIE_SLOT2_PRSNT2_3_N")
	)
	(segment
		(start 80.079342 -12.197842)
		(end 81.1149 -13.2334)
		(width 0.127)
		(layer "In3.Cu")
		(net "PCIE_SLOT2_PRSNT2_3_N")
	)
	(via
		(at 27.7114 -28.7782)
		(size 0.5588)
		(drill 0.3048)
		(layers "F.Cu" "B.Cu")
		(net "P12V_ATX")
	)
	(via
		(at 26.1747 -29.3624)
		(size 0.5588)
		(drill 0.3048)
		(layers "F.Cu" "B.Cu")
		(net "P12V_ATX")
	)
	(via
		(at 27.4955 -29.5783)
		(size 0.5588)
		(drill 0.3048)
		(layers "F.Cu" "B.Cu")
		(net "P12V_ATX")
	)
	(via
		(at 18.6436 -29.7561)
		(size 0.5588)
		(drill 0.3048)
		(layers "F.Cu" "B.Cu")
		(net "P12V_ATX")
	)
	(via
		(at 19.5199 -29.6799)
		(size 0.5588)
		(drill 0.3048)
		(layers "F.Cu" "B.Cu")
		(net "P12V_ATX")
	)
	(via
		(at 20.4851 -29.6545)
		(size 0.5588)
		(drill 0.3048)
		(layers "F.Cu" "B.Cu")
		(net "P12V_ATX")
	)
	(via
		(at 21.3487 -29.6799)
		(size 0.5588)
		(drill 0.3048)
		(layers "F.Cu" "B.Cu")
		(net "P12V_ATX")
	)
	(via
		(at 22.5044 -29.6672)
		(size 0.7112)
		(drill 0.3556)
		(layers "F.Cu" "B.Cu")
		(net "P12V_ATX")
	)
	(segment
		(start 16.82115 -29.26715)
		(end 16.82115 -28.75915)
		(width 0.2032)
		(layer "B.Cu")
		(net "P12V_ATX")
	)
	(segment
		(start 43.399964 -22.200108)
		(end 43.399964 -23.838916)
		(width 0.508)
		(layer "B.Cu")
		(net "P12V_ATX")
	)
	(segment
		(start 43.399964 -17.999964)
		(end 43.399964 -19.638772)
		(width 0.508)
		(layer "B.Cu")
		(net "P12V_ATX")
	)
	(segment
		(start 15.693898 -27.631898)
		(end 15.439898 -27.631898)
		(width 0.2032)
		(layer "B.Cu")
		(net "P12V_ATX")
	)
	(segment
		(start 41.761156 -17.999964)
		(end 43.399964 -17.999964)
		(width 0.508)
		(layer "B.Cu")
		(net "P12V_ATX")
	)
	(segment
		(start 43.399964 -20.5613)
		(end 43.399964 -22.200108)
		(width 0.508)
		(layer "B.Cu")
		(net "P12V_ATX")
	)
	(segment
		(start 43.399964 -16.361156)
		(end 43.399964 -17.999964)
		(width 0.508)
		(layer "B.Cu")
		(net "P12V_ATX")
	)
	(segment
		(start 16.82115 -28.75915)
		(end 15.693898 -27.631898)
		(width 0.2032)
		(layer "B.Cu")
		(net "P12V_ATX")
	)
	(segment
		(start 41.761156 -22.200108)
		(end 43.399964 -22.200108)
		(width 0.508)
		(layer "B.Cu")
		(net "P12V_ATX")
	)
	(segment
		(start 16.246094 -29.842206)
		(end 16.82115 -29.26715)
		(width 0.2032)
		(layer "B.Cu")
		(net "P12V_ATX")
	)
	(segment
		(start 43.399964 -22.200108)
		(end 45.038772 -22.200108)
		(width 0.508)
		(layer "B.Cu")
		(net "P12V_ATX")
	)
	(segment
		(start 43.399964 -17.999964)
		(end 45.038772 -17.999964)
		(width 0.508)
		(layer "B.Cu")
		(net "P12V_ATX")
	)
	(segment
		(start 127.1524 -1.992884)
		(end 126.3904 -1.230884)
		(width 0.1016)
		(layer "F.Cu")
		(net "GPIO_P_IO1_7")
	)
	(segment
		(start 125.9967 -0.568452)
		(end 125.9967 0.1524)
		(width 0.1016)
		(layer "F.Cu")
		(net "GPIO_P_IO1_7")
	)
	(segment
		(start 127.77216 -2.57556)
		(end 127.4572 -2.2606)
		(width 0.1016)
		(layer "F.Cu")
		(net "GPIO_P_IO1_7")
	)
	(segment
		(start 127.4572 -2.2606)
		(end 127.419862 -2.2606)
		(width 0.1016)
		(layer "F.Cu")
		(net "GPIO_P_IO1_7")
	)
	(segment
		(start 126.5682 0.889)
		(end 125.9967 0.3175)
		(width 0.1016)
		(layer "F.Cu")
		(net "GPIO_P_IO1_7")
	)
	(segment
		(start 125.9967 0.3175)
		(end 125.9967 0.1524)
		(width 0.1016)
		(layer "F.Cu")
		(net "GPIO_P_IO1_7")
	)
	(segment
		(start 127.1524 -1.993138)
		(end 127.1524 -1.992884)
		(width 0.1016)
		(layer "F.Cu")
		(net "GPIO_P_IO1_7")
	)
	(segment
		(start 127.419862 -2.2606)
		(end 127.1524 -1.993138)
		(width 0.1016)
		(layer "F.Cu")
		(net "GPIO_P_IO1_7")
	)
	(segment
		(start 126.3904 -0.962152)
		(end 125.9967 -0.568452)
		(width 0.1016)
		(layer "F.Cu")
		(net "GPIO_P_IO1_7")
	)
	(segment
		(start 127.77216 -3.175)
		(end 127.77216 -2.57556)
		(width 0.1016)
		(layer "F.Cu")
		(net "GPIO_P_IO1_7")
	)
	(segment
		(start 126.746 2.1463)
		(end 126.746 1.3208)
		(width 0.1016)
		(layer "F.Cu")
		(net "GPIO_P_IO1_7")
	)
	(segment
		(start 126.5682 1.143)
		(end 126.5682 0.889)
		(width 0.1016)
		(layer "F.Cu")
		(net "GPIO_P_IO1_7")
	)
	(segment
		(start 126.746 1.3208)
		(end 126.5682 1.143)
		(width 0.1016)
		(layer "F.Cu")
		(net "GPIO_P_IO1_7")
	)
	(segment
		(start 126.3904 -1.230884)
		(end 126.3904 -0.962152)
		(width 0.1016)
		(layer "F.Cu")
		(net "GPIO_P_IO1_7")
	)
	(via
		(at 126.5682 1.143)
		(size 0.7112)
		(drill 0.3556)
		(layers "F.Cu" "B.Cu")
		(net "GPIO_P_IO1_7")
	)
	(segment
		(start 125.8062 -1.3462)
		(end 125.5014 -1.0414)
		(width 0.1016)
		(layer "F.Cu")
		(net "GPIO_P_IO1_6")
	)
	(segment
		(start 125.5014 -1.0414)
		(end 125.5014 1.4859)
		(width 0.1016)
		(layer "F.Cu")
		(net "GPIO_P_IO1_6")
	)
	(segment
		(start 126.7714 -2.068068)
		(end 127.12192 -2.418588)
		(width 0.1016)
		(layer "F.Cu")
		(net "GPIO_P_IO1_6")
	)
	(segment
		(start 125.5903 2.6416)
		(end 125.5903 1.5748)
		(width 0.1016)
		(layer "F.Cu")
		(net "GPIO_P_IO1_6")
	)
	(segment
		(start 125.8316 -1.3462)
		(end 125.8062 -1.3462)
		(width 0.1016)
		(layer "F.Cu")
		(net "GPIO_P_IO1_6")
	)
	(segment
		(start 125.5014 1.4859)
		(end 125.5903 1.5748)
		(width 0.1016)
		(layer "F.Cu")
		(net "GPIO_P_IO1_6")
	)
	(segment
		(start 126.731268 -2.068068)
		(end 126.7714 -2.068068)
		(width 0.1016)
		(layer "F.Cu")
		(net "GPIO_P_IO1_6")
	)
	(segment
		(start 126.0094 -1.3462)
		(end 126.731268 -2.068068)
		(width 0.1016)
		(layer "F.Cu")
		(net "GPIO_P_IO1_6")
	)
	(segment
		(start 125.8316 -1.3462)
		(end 126.0094 -1.3462)
		(width 0.1016)
		(layer "F.Cu")
		(net "GPIO_P_IO1_6")
	)
	(segment
		(start 127.12192 -2.418588)
		(end 127.12192 -3.175)
		(width 0.1016)
		(layer "F.Cu")
		(net "GPIO_P_IO1_6")
	)
	(via
		(at 125.8316 -1.3462)
		(size 0.7112)
		(drill 0.3556)
		(layers "F.Cu" "B.Cu")
		(net "GPIO_P_IO1_6")
	)
	(segment
		(start 126.47168 -2.341372)
		(end 126.47168 -3.175)
		(width 0.1016)
		(layer "F.Cu")
		(net "GPIO_P_IO1_5")
	)
	(segment
		(start 124.968 -0.4953)
		(end 123.9266 -0.4953)
		(width 0.1016)
		(layer "F.Cu")
		(net "GPIO_P_IO1_5")
	)
	(segment
		(start 123.076716 -0.926084)
		(end 123.5075 -0.4953)
		(width 0.1016)
		(layer "F.Cu")
		(net "GPIO_P_IO1_5")
	)
	(segment
		(start 125.174248 -1.577848)
		(end 125.2728 -1.577848)
		(width 0.1016)
		(layer "F.Cu")
		(net "GPIO_P_IO1_5")
	)
	(segment
		(start 124.7648 -0.6985)
		(end 124.7648 -1.1684)
		(width 0.1016)
		(layer "F.Cu")
		(net "GPIO_P_IO1_5")
	)
	(segment
		(start 123.5075 -0.4953)
		(end 123.9266 -0.4953)
		(width 0.1016)
		(layer "F.Cu")
		(net "GPIO_P_IO1_5")
	)
	(segment
		(start 126.238508 -2.1082)
		(end 126.47168 -2.341372)
		(width 0.1016)
		(layer "F.Cu")
		(net "GPIO_P_IO1_5")
	)
	(segment
		(start 125.803152 -2.1082)
		(end 126.238508 -2.1082)
		(width 0.1016)
		(layer "F.Cu")
		(net "GPIO_P_IO1_5")
	)
	(segment
		(start 124.7648 -1.1684)
		(end 125.174248 -1.577848)
		(width 0.1016)
		(layer "F.Cu")
		(net "GPIO_P_IO1_5")
	)
	(segment
		(start 123.076716 -1.095756)
		(end 123.076716 -0.926084)
		(width 0.1016)
		(layer "F.Cu")
		(net "GPIO_P_IO1_5")
	)
	(segment
		(start 124.968 -0.4953)
		(end 124.7648 -0.6985)
		(width 0.1016)
		(layer "F.Cu")
		(net "GPIO_P_IO1_5")
	)
	(segment
		(start 125.2728 -1.577848)
		(end 125.803152 -2.1082)
		(width 0.1016)
		(layer "F.Cu")
		(net "GPIO_P_IO1_5")
	)
	(via
		(at 123.076716 -1.095756)
		(size 0.7112)
		(drill 0.3556)
		(layers "F.Cu" "B.Cu")
		(net "GPIO_P_IO1_5")
	)
	(segment
		(start 121.3993 -3.8481)
		(end 121.3993 -2.731008)
		(width 0.1016)
		(layer "F.Cu")
		(net "GPIO_P_IO1_4")
	)
	(segment
		(start 121.1834 -4.064)
		(end 121.3993 -3.8481)
		(width 0.1016)
		(layer "F.Cu")
		(net "GPIO_P_IO1_4")
	)
	(segment
		(start 124.892054 -1.726946)
		(end 125.047756 -1.882648)
		(width 0.1016)
		(layer "F.Cu")
		(net "GPIO_P_IO1_4")
	)
	(segment
		(start 125.123448 -1.882648)
		(end 125.82144 -2.58064)
		(width 0.1016)
		(layer "F.Cu")
		(net "GPIO_P_IO1_4")
	)
	(segment
		(start 120.0277 -5.9944)
		(end 120.0277 -4.953)
		(width 0.1016)
		(layer "F.Cu")
		(net "GPIO_P_IO1_4")
	)
	(segment
		(start 125.047756 -1.882648)
		(end 125.123448 -1.882648)
		(width 0.1016)
		(layer "F.Cu")
		(net "GPIO_P_IO1_4")
	)
	(segment
		(start 120.2944 -4.953)
		(end 121.1834 -4.064)
		(width 0.1016)
		(layer "F.Cu")
		(net "GPIO_P_IO1_4")
	)
	(segment
		(start 125.82144 -2.58064)
		(end 125.82144 -3.175)
		(width 0.1016)
		(layer "F.Cu")
		(net "GPIO_P_IO1_4")
	)
	(segment
		(start 120.0277 -4.953)
		(end 120.2944 -4.953)
		(width 0.1016)
		(layer "F.Cu")
		(net "GPIO_P_IO1_4")
	)
	(segment
		(start 122.403362 -1.726946)
		(end 124.892054 -1.726946)
		(width 0.1016)
		(layer "F.Cu")
		(net "GPIO_P_IO1_4")
	)
	(segment
		(start 121.3993 -2.731008)
		(end 122.403362 -1.726946)
		(width 0.1016)
		(layer "F.Cu")
		(net "GPIO_P_IO1_4")
	)
	(via
		(at 121.1834 -4.064)
		(size 0.7112)
		(drill 0.3556)
		(layers "F.Cu" "B.Cu")
		(net "GPIO_P_IO1_4")
	)
	(segment
		(start 121.2342 -5.588)
		(end 121.1834 -5.6388)
		(width 0.1016)
		(layer "F.Cu")
		(net "GPIO_P_IO1_3")
	)
	(segment
		(start 121.1834 -5.6388)
		(end 121.1834 -5.8801)
		(width 0.1016)
		(layer "F.Cu")
		(net "GPIO_P_IO1_3")
	)
	(segment
		(start 125.1712 -3.175)
		(end 125.1712 -2.437384)
		(width 0.1016)
		(layer "F.Cu")
		(net "GPIO_P_IO1_3")
	)
	(segment
		(start 124.765816 -2.032)
		(end 122.5296 -2.032)
		(width 0.1016)
		(layer "F.Cu")
		(net "GPIO_P_IO1_3")
	)
	(segment
		(start 125.1712 -2.437384)
		(end 124.765816 -2.032)
		(width 0.1016)
		(layer "F.Cu")
		(net "GPIO_P_IO1_3")
	)
	(segment
		(start 121.1834 -5.8801)
		(end 120.0277 -7.0358)
		(width 0.1016)
		(layer "F.Cu")
		(net "GPIO_P_IO1_3")
	)
	(segment
		(start 120.0277 -7.0358)
		(end 120.0277 -8.0772)
		(width 0.1016)
		(layer "F.Cu")
		(net "GPIO_P_IO1_3")
	)
	(segment
		(start 122.5296 -2.032)
		(end 121.9708 -2.5908)
		(width 0.1016)
		(layer "F.Cu")
		(net "GPIO_P_IO1_3")
	)
	(segment
		(start 121.9708 -2.5908)
		(end 121.9708 -4.8514)
		(width 0.1016)
		(layer "F.Cu")
		(net "GPIO_P_IO1_3")
	)
	(segment
		(start 121.9708 -4.8514)
		(end 121.2342 -5.588)
		(width 0.1016)
		(layer "F.Cu")
		(net "GPIO_P_IO1_3")
	)
	(via
		(at 121.2342 -5.588)
		(size 0.7112)
		(drill 0.3556)
		(layers "F.Cu" "B.Cu")
		(net "GPIO_P_IO1_3")
	)
	(segment
		(start 121.3612 -8.0264)
		(end 120.2436 -9.144)
		(width 0.1016)
		(layer "F.Cu")
		(net "GPIO_P_IO1_0")
	)
	(segment
		(start 123.22048 -3.175)
		(end 123.22048 -5.24002)
		(width 0.1016)
		(layer "F.Cu")
		(net "GPIO_P_IO1_0")
	)
	(segment
		(start 120.2436 -9.144)
		(end 120.0277 -9.144)
		(width 0.1016)
		(layer "F.Cu")
		(net "GPIO_P_IO1_0")
	)
	(segment
		(start 123.22048 -5.24002)
		(end 121.3612 -7.0993)
		(width 0.1016)
		(layer "F.Cu")
		(net "GPIO_P_IO1_0")
	)
	(segment
		(start 121.3612 -7.0993)
		(end 121.3612 -8.0264)
		(width 0.1016)
		(layer "F.Cu")
		(net "GPIO_P_IO1_0")
	)
	(segment
		(start 120.0277 -9.144)
		(end 120.0277 -10.1854)
		(width 0.1016)
		(layer "F.Cu")
		(net "GPIO_P_IO1_0")
	)
	(segment
		(start 120.0277 -10.1854)
		(end 120.0531 -10.2108)
		(width 0.1016)
		(layer "F.Cu")
		(net "GPIO_P_IO1_0")
	)
	(via
		(at 121.3612 -7.0993)
		(size 0.7112)
		(drill 0.3556)
		(layers "F.Cu" "B.Cu")
		(net "GPIO_P_IO1_0")
	)
	(segment
		(start 130.37312 -7.77748)
		(end 130.7592 -7.3914)
		(width 0.1016)
		(layer "F.Cu")
		(net "GPIO_P_EXP_INT_N")
	)
	(segment
		(start 130.37312 -8.8138)
		(end 130.37312 -7.77748)
		(width 0.1016)
		(layer "F.Cu")
		(net "GPIO_P_EXP_INT_N")
	)
	(via
		(at 132.1308 -8.7376)
		(size 0.7112)
		(drill 0.3556)
		(layers "F.Cu" "B.Cu")
		(net "GPIO_P_EXP_INT_N")
	)
	(via
		(at 130.7592 -7.3914)
		(size 0.508)
		(drill 0.254)
		(layers "F.Cu" "B.Cu")
		(net "GPIO_P_EXP_INT_N")
	)
	(segment
		(start 131.9276 -8.5344)
		(end 131.9276 -7.9121)
		(width 0.1016)
		(layer "B.Cu")
		(net "GPIO_P_EXP_INT_N")
	)
	(segment
		(start 132.1308 -8.7376)
		(end 131.9276 -8.5344)
		(width 0.1016)
		(layer "B.Cu")
		(net "GPIO_P_EXP_INT_N")
	)
	(segment
		(start 131.9276 -7.9121)
		(end 131.8133 -7.7978)
		(width 0.1016)
		(layer "B.Cu")
		(net "GPIO_P_EXP_INT_N")
	)
	(segment
		(start 131.826 -7.7851)
		(end 131.8133 -7.7978)
		(width 0.1016)
		(layer "B.Cu")
		(net "GPIO_P_EXP_INT_N")
	)
	(segment
		(start 131.8133 -7.7978)
		(end 131.1656 -7.7978)
		(width 0.1016)
		(layer "B.Cu")
		(net "GPIO_P_EXP_INT_N")
	)
	(segment
		(start 131.1656 -7.7978)
		(end 130.7592 -7.3914)
		(width 0.1016)
		(layer "B.Cu")
		(net "GPIO_P_EXP_INT_N")
	)
	(segment
		(start 131.826 -6.7691)
		(end 131.826 -7.7851)
		(width 0.1016)
		(layer "B.Cu")
		(net "GPIO_P_EXP_INT_N")
	)
	(segment
		(start 129.07264 -7.57936)
		(end 130.9116 -5.7404)
		(width 0.1016)
		(layer "F.Cu")
		(net "GPIO_P_EXP_A2")
	)
	(segment
		(start 131.7625 -4.6736)
		(end 131.7625 -5.715)
		(width 0.1016)
		(layer "F.Cu")
		(net "GPIO_P_EXP_A2")
	)
	(segment
		(start 131.7625 -3.7973)
		(end 131.826 -3.7338)
		(width 0.1016)
		(layer "F.Cu")
		(net "GPIO_P_EXP_A2")
	)
	(segment
		(start 130.9116 -5.7404)
		(end 131.7371 -5.7404)
		(width 0.1016)
		(layer "F.Cu")
		(net "GPIO_P_EXP_A2")
	)
	(segment
		(start 131.7625 -4.6736)
		(end 131.7625 -3.7973)
		(width 0.1016)
		(layer "F.Cu")
		(net "GPIO_P_EXP_A2")
	)
	(segment
		(start 129.07264 -8.8138)
		(end 129.07264 -7.57936)
		(width 0.1016)
		(layer "F.Cu")
		(net "GPIO_P_EXP_A2")
	)
	(segment
		(start 131.7371 -5.7404)
		(end 131.7625 -5.715)
		(width 0.1016)
		(layer "F.Cu")
		(net "GPIO_P_EXP_A2")
	)
	(via
		(at 131.826 -3.7338)
		(size 0.7112)
		(drill 0.3556)
		(layers "F.Cu" "B.Cu")
		(net "GPIO_P_EXP_A2")
	)
	(segment
		(start 131.7879 -8.0645)
		(end 132.1308 -8.4074)
		(width 0.1016)
		(layer "F.Cu")
		(net "GPIO_P_EXP_A1")
	)
	(segment
		(start 130.6068 -6.5786)
		(end 129.72288 -7.46252)
		(width 0.1016)
		(layer "F.Cu")
		(net "GPIO_P_EXP_A1")
	)
	(segment
		(start 131.7625 -7.7978)
		(end 131.7879 -7.8232)
		(width 0.1016)
		(layer "F.Cu")
		(net "GPIO_P_EXP_A1")
	)
	(segment
		(start 131.7625 -6.7564)
		(end 131.5847 -6.5786)
		(width 0.1016)
		(layer "F.Cu")
		(net "GPIO_P_EXP_A1")
	)
	(segment
		(start 129.72288 -7.46252)
		(end 129.72288 -8.8138)
		(width 0.1016)
		(layer "F.Cu")
		(net "GPIO_P_EXP_A1")
	)
	(segment
		(start 133.2992 -8.4074)
		(end 133.5024 -8.6106)
		(width 0.1016)
		(layer "F.Cu")
		(net "GPIO_P_EXP_A1")
	)
	(segment
		(start 131.7879 -7.8232)
		(end 131.7879 -8.0645)
		(width 0.1016)
		(layer "F.Cu")
		(net "GPIO_P_EXP_A1")
	)
	(segment
		(start 131.7625 -6.7564)
		(end 131.7625 -7.7978)
		(width 0.1016)
		(layer "F.Cu")
		(net "GPIO_P_EXP_A1")
	)
	(segment
		(start 132.1308 -8.4074)
		(end 133.2992 -8.4074)
		(width 0.1016)
		(layer "F.Cu")
		(net "GPIO_P_EXP_A1")
	)
	(segment
		(start 131.5847 -6.5786)
		(end 130.6068 -6.5786)
		(width 0.1016)
		(layer "F.Cu")
		(net "GPIO_P_EXP_A1")
	)
	(via
		(at 133.5024 -8.6106)
		(size 0.7112)
		(drill 0.3556)
		(layers "F.Cu" "B.Cu")
		(net "GPIO_P_EXP_A1")
	)
	(segment
		(start 128.7272 -1.627124)
		(end 128.7272 -1.9812)
		(width 0.1016)
		(layer "F.Cu")
		(net "GPIO_P_EXP_A0")
	)
	(segment
		(start 128.4605 -1.6002)
		(end 128.700276 -1.6002)
		(width 0.1016)
		(layer "F.Cu")
		(net "GPIO_P_EXP_A0")
	)
	(segment
		(start 127.9144 -0.9779)
		(end 127.8763 -1.016)
		(width 0.1016)
		(layer "F.Cu")
		(net "GPIO_P_EXP_A0")
	)
	(segment
		(start 128.7272 -1.9812)
		(end 128.4224 -2.286)
		(width 0.1016)
		(layer "F.Cu")
		(net "GPIO_P_EXP_A0")
	)
	(segment
		(start 128.700276 -1.6002)
		(end 128.7272 -1.627124)
		(width 0.1016)
		(layer "F.Cu")
		(net "GPIO_P_EXP_A0")
	)
	(segment
		(start 127.8763 -1.016)
		(end 128.4605 -1.6002)
		(width 0.1016)
		(layer "F.Cu")
		(net "GPIO_P_EXP_A0")
	)
	(segment
		(start 127.9144 0.0381)
		(end 127.9144 -0.9779)
		(width 0.1016)
		(layer "F.Cu")
		(net "GPIO_P_EXP_A0")
	)
	(segment
		(start 128.4224 -2.286)
		(end 128.4224 -3.175)
		(width 0.1016)
		(layer "F.Cu")
		(net "GPIO_P_EXP_A0")
	)
	(via
		(at 128.700276 -1.6002)
		(size 0.7112)
		(drill 0.3556)
		(layers "F.Cu" "B.Cu")
		(net "GPIO_P_EXP_A0")
	)
	(segment
		(start 130.222752 -17.786858)
		(end 130.156458 -17.786858)
		(width 0.1016)
		(layer "F.Cu")
		(net "GPIO_B_IO1_7")
	)
	(segment
		(start 130.222752 -17.815052)
		(end 130.222752 -17.786858)
		(width 0.1016)
		(layer "F.Cu")
		(net "GPIO_B_IO1_7")
	)
	(segment
		(start 131.2291 -18.8214)
		(end 130.222752 -17.815052)
		(width 0.1016)
		(layer "F.Cu")
		(net "GPIO_B_IO1_7")
	)
	(segment
		(start 128.64338 -17.16278)
		(end 128.35636 -16.87576)
		(width 0.1016)
		(layer "F.Cu")
		(net "GPIO_B_IO1_7")
	)
	(segment
		(start 130.156458 -17.786858)
		(end 129.53238 -17.16278)
		(width 0.1016)
		(layer "F.Cu")
		(net "GPIO_B_IO1_7")
	)
	(segment
		(start 131.2291 -18.8214)
		(end 131.2291 -19.8882)
		(width 0.1016)
		(layer "F.Cu")
		(net "GPIO_B_IO1_7")
	)
	(segment
		(start 128.35636 -16.87576)
		(end 127.6858 -16.87576)
		(width 0.1016)
		(layer "F.Cu")
		(net "GPIO_B_IO1_7")
	)
	(segment
		(start 129.53238 -17.16278)
		(end 128.64338 -17.16278)
		(width 0.1016)
		(layer "F.Cu")
		(net "GPIO_B_IO1_7")
	)
	(via
		(at 130.222752 -17.786858)
		(size 0.7112)
		(drill 0.3556)
		(layers "F.Cu" "B.Cu")
		(net "GPIO_B_IO1_7")
	)
	(segment
		(start 128.83769 -16.22552)
		(end 129.21615 -16.60398)
		(width 0.1016)
		(layer "F.Cu")
		(net "GPIO_B_IO1_6")
	)
	(segment
		(start 129.37998 -16.60398)
		(end 129.5908 -16.8148)
		(width 0.1016)
		(layer "F.Cu")
		(net "GPIO_B_IO1_6")
	)
	(segment
		(start 127.6858 -16.22552)
		(end 128.83769 -16.22552)
		(width 0.1016)
		(layer "F.Cu")
		(net "GPIO_B_IO1_6")
	)
	(segment
		(start 131.1783 -16.8148)
		(end 131.2545 -16.7386)
		(width 0.1016)
		(layer "F.Cu")
		(net "GPIO_B_IO1_6")
	)
	(segment
		(start 131.2545 -16.7386)
		(end 131.2545 -17.7546)
		(width 0.1016)
		(layer "F.Cu")
		(net "GPIO_B_IO1_6")
	)
	(segment
		(start 129.21615 -16.60398)
		(end 129.37998 -16.60398)
		(width 0.1016)
		(layer "F.Cu")
		(net "GPIO_B_IO1_6")
	)
	(segment
		(start 131.2545 -17.7546)
		(end 131.2291 -17.78)
		(width 0.1016)
		(layer "F.Cu")
		(net "GPIO_B_IO1_6")
	)
	(segment
		(start 129.5908 -16.8148)
		(end 131.1783 -16.8148)
		(width 0.1016)
		(layer "F.Cu")
		(net "GPIO_B_IO1_6")
	)
	(via
		(at 129.21615 -16.60398)
		(size 0.7112)
		(drill 0.3556)
		(layers "F.Cu" "B.Cu")
		(net "GPIO_B_IO1_6")
	)
	(segment
		(start 130.2766 -16.002)
		(end 130.2512 -16.0274)
		(width 0.1016)
		(layer "F.Cu")
		(net "GPIO_B_IO1_5")
	)
	(segment
		(start 128.73228 -15.57528)
		(end 127.6858 -15.57528)
		(width 0.1016)
		(layer "F.Cu")
		(net "GPIO_B_IO1_5")
	)
	(segment
		(start 130.9243 -16.0274)
		(end 130.302 -16.0274)
		(width 0.1016)
		(layer "F.Cu")
		(net "GPIO_B_IO1_5")
	)
	(segment
		(start 130.2512 -16.0274)
		(end 129.1844 -16.0274)
		(width 0.1016)
		(layer "F.Cu")
		(net "GPIO_B_IO1_5")
	)
	(segment
		(start 129.1844 -16.0274)
		(end 128.73228 -15.57528)
		(width 0.1016)
		(layer "F.Cu")
		(net "GPIO_B_IO1_5")
	)
	(segment
		(start 131.2545 -14.6558)
		(end 131.2545 -15.6972)
		(width 0.1016)
		(layer "F.Cu")
		(net "GPIO_B_IO1_5")
	)
	(segment
		(start 130.302 -16.0274)
		(end 130.2766 -16.002)
		(width 0.1016)
		(layer "F.Cu")
		(net "GPIO_B_IO1_5")
	)
	(segment
		(start 131.2545 -15.6972)
		(end 130.9243 -16.0274)
		(width 0.1016)
		(layer "F.Cu")
		(net "GPIO_B_IO1_5")
	)
	(via
		(at 130.2766 -16.002)
		(size 0.7112)
		(drill 0.3556)
		(layers "F.Cu" "B.Cu")
		(net "GPIO_B_IO1_5")
	)
	(segment
		(start 128.651 -14.605)
		(end 128.33096 -14.92504)
		(width 0.1016)
		(layer "F.Cu")
		(net "GPIO_B_IO1_4")
	)
	(segment
		(start 129.91592 -14.605)
		(end 128.651 -14.605)
		(width 0.1016)
		(layer "F.Cu")
		(net "GPIO_B_IO1_4")
	)
	(segment
		(start 128.33096 -14.92504)
		(end 127.6858 -14.92504)
		(width 0.1016)
		(layer "F.Cu")
		(net "GPIO_B_IO1_4")
	)
	(segment
		(start 131.2799 -12.5476)
		(end 131.2799 -13.589)
		(width 0.1016)
		(layer "F.Cu")
		(net "GPIO_B_IO1_4")
	)
	(segment
		(start 130.281426 -14.239494)
		(end 129.91592 -14.605)
		(width 0.1016)
		(layer "F.Cu")
		(net "GPIO_B_IO1_4")
	)
	(segment
		(start 130.281426 -14.239494)
		(end 130.93192 -13.589)
		(width 0.1016)
		(layer "F.Cu")
		(net "GPIO_B_IO1_4")
	)
	(segment
		(start 130.93192 -13.589)
		(end 131.2799 -13.589)
		(width 0.1016)
		(layer "F.Cu")
		(net "GPIO_B_IO1_4")
	)
	(via
		(at 130.281426 -14.239494)
		(size 0.7112)
		(drill 0.3556)
		(layers "F.Cu" "B.Cu")
		(net "GPIO_B_IO1_4")
	)
	(segment
		(start 130.3528 -12.954)
		(end 130.3528 -12.6238)
		(width 0.1016)
		(layer "F.Cu")
		(net "GPIO_B_IO1_3")
	)
	(segment
		(start 128.549908 -14.3002)
		(end 129.286 -14.3002)
		(width 0.1016)
		(layer "F.Cu")
		(net "GPIO_B_IO1_3")
	)
	(segment
		(start 130.8354 -12.19454)
		(end 131.3053 -11.72464)
		(width 0.1016)
		(layer "F.Cu")
		(net "GPIO_B_IO1_3")
	)
	(segment
		(start 131.3053 -10.4394)
		(end 131.3053 -11.4808)
		(width 0.1016)
		(layer "F.Cu")
		(net "GPIO_B_IO1_3")
	)
	(segment
		(start 131.3053 -11.72464)
		(end 131.3053 -11.4808)
		(width 0.1016)
		(layer "F.Cu")
		(net "GPIO_B_IO1_3")
	)
	(segment
		(start 130.0861 -13.2207)
		(end 130.3528 -12.954)
		(width 0.1016)
		(layer "F.Cu")
		(net "GPIO_B_IO1_3")
	)
	(segment
		(start 130.3528 -12.6238)
		(end 130.78206 -12.19454)
		(width 0.1016)
		(layer "F.Cu")
		(net "GPIO_B_IO1_3")
	)
	(segment
		(start 127.6858 -14.2748)
		(end 128.524508 -14.2748)
		(width 0.1016)
		(layer "F.Cu")
		(net "GPIO_B_IO1_3")
	)
	(segment
		(start 129.286 -14.3002)
		(end 130.0861 -13.5001)
		(width 0.1016)
		(layer "F.Cu")
		(net "GPIO_B_IO1_3")
	)
	(segment
		(start 130.0861 -13.5001)
		(end 130.0861 -13.2207)
		(width 0.1016)
		(layer "F.Cu")
		(net "GPIO_B_IO1_3")
	)
	(segment
		(start 128.524508 -14.2748)
		(end 128.549908 -14.3002)
		(width 0.1016)
		(layer "F.Cu")
		(net "GPIO_B_IO1_3")
	)
	(segment
		(start 130.78206 -12.19454)
		(end 130.8354 -12.19454)
		(width 0.1016)
		(layer "F.Cu")
		(net "GPIO_B_IO1_3")
	)
	(via
		(at 130.3528 -12.954)
		(size 0.7112)
		(drill 0.3556)
		(layers "F.Cu" "B.Cu")
		(net "GPIO_B_IO1_3")
	)
	(segment
		(start 130.2512 -11.2141)
		(end 129.2098 -11.2141)
		(width 0.1016)
		(layer "F.Cu")
		(net "GPIO_B_IO1_0")
	)
	(segment
		(start 128.01092 -12.32408)
		(end 127.6858 -12.32408)
		(width 0.1016)
		(layer "F.Cu")
		(net "GPIO_B_IO1_0")
	)
	(segment
		(start 127.127 -11.2268)
		(end 127.127 -11.76528)
		(width 0.1016)
		(layer "F.Cu")
		(net "GPIO_B_IO1_0")
	)
	(segment
		(start 127.127 -11.76528)
		(end 127.6858 -12.32408)
		(width 0.1016)
		(layer "F.Cu")
		(net "GPIO_B_IO1_0")
	)
	(segment
		(start 129.2098 -11.2141)
		(end 129.1209 -11.2141)
		(width 0.1016)
		(layer "F.Cu")
		(net "GPIO_B_IO1_0")
	)
	(segment
		(start 129.1209 -11.2141)
		(end 128.01092 -12.32408)
		(width 0.1016)
		(layer "F.Cu")
		(net "GPIO_B_IO1_0")
	)
	(via
		(at 127.127 -11.2268)
		(size 0.7112)
		(drill 0.3556)
		(layers "F.Cu" "B.Cu")
		(net "GPIO_B_IO1_0")
	)
	(segment
		(start 123.3424 -20.6629)
		(end 122.0597 -20.6629)
		(width 0.1016)
		(layer "F.Cu")
		(net "GPIO_B_EXP_INT_N")
	)
	(segment
		(start 122.0597 -20.6629)
		(end 122.047 -20.6502)
		(width 0.1016)
		(layer "F.Cu")
		(net "GPIO_B_EXP_INT_N")
	)
	(segment
		(start 122.047 -19.47672)
		(end 122.047 -20.6502)
		(width 0.1016)
		(layer "F.Cu")
		(net "GPIO_B_EXP_INT_N")
	)
	(segment
		(start 124.4092 -20.6629)
		(end 123.3424 -20.6629)
		(width 0.1016)
		(layer "F.Cu")
		(net "GPIO_B_EXP_INT_N")
	)
	(via
		(at 122.047 -20.6502)
		(size 0.7112)
		(drill 0.3556)
		(layers "F.Cu" "B.Cu")
		(net "GPIO_B_EXP_INT_N")
	)
	(segment
		(start 117.6528 -18.5801)
		(end 116.586 -18.5801)
		(width 0.1016)
		(layer "F.Cu")
		(net "GPIO_B_EXP_A2")
	)
	(segment
		(start 116.4971 -18.542)
		(end 116.5606 -18.6055)
		(width 0.1016)
		(layer "F.Cu")
		(net "GPIO_B_EXP_A2")
	)
	(segment
		(start 116.586 -18.5801)
		(end 116.5606 -18.6055)
		(width 0.1016)
		(layer "F.Cu")
		(net "GPIO_B_EXP_A2")
	)
	(segment
		(start 122.047 -18.17624)
		(end 118.05666 -18.17624)
		(width 0.1016)
		(layer "F.Cu")
		(net "GPIO_B_EXP_A2")
	)
	(segment
		(start 118.05666 -18.17624)
		(end 117.6528 -18.5801)
		(width 0.1016)
		(layer "F.Cu")
		(net "GPIO_B_EXP_A2")
	)
	(segment
		(start 115.443 -18.5674)
		(end 115.4684 -18.542)
		(width 0.1016)
		(layer "F.Cu")
		(net "GPIO_B_EXP_A2")
	)
	(segment
		(start 115.4684 -18.542)
		(end 116.4971 -18.542)
		(width 0.1016)
		(layer "F.Cu")
		(net "GPIO_B_EXP_A2")
	)
	(via
		(at 115.443 -18.5674)
		(size 0.7112)
		(drill 0.3556)
		(layers "F.Cu" "B.Cu")
		(net "GPIO_B_EXP_A2")
	)
	(segment
		(start 119.5959 -20.193)
		(end 119.5959 -19.1516)
		(width 0.1016)
		(layer "F.Cu")
		(net "GPIO_B_EXP_A1")
	)
	(segment
		(start 119.5959 -20.193)
		(end 119.5959 -20.3581)
		(width 0.1016)
		(layer "F.Cu")
		(net "GPIO_B_EXP_A1")
	)
	(segment
		(start 119.5959 -19.1516)
		(end 119.92102 -18.82648)
		(width 0.1016)
		(layer "F.Cu")
		(net "GPIO_B_EXP_A1")
	)
	(segment
		(start 119.5959 -20.3581)
		(end 118.6688 -21.2852)
		(width 0.1016)
		(layer "F.Cu")
		(net "GPIO_B_EXP_A1")
	)
	(segment
		(start 119.92102 -18.82648)
		(end 122.047 -18.82648)
		(width 0.1016)
		(layer "F.Cu")
		(net "GPIO_B_EXP_A1")
	)
	(via
		(at 118.6688 -21.2852)
		(size 0.7112)
		(drill 0.3556)
		(layers "F.Cu" "B.Cu")
		(net "GPIO_B_EXP_A1")
	)
	(segment
		(start 129.1082 -17.526)
		(end 130.7846 -19.2024)
		(width 0.1016)
		(layer "F.Cu")
		(net "GPIO_B_EXP_A0")
	)
	(segment
		(start 130.7846 -20.4597)
		(end 131.2545 -20.9296)
		(width 0.1016)
		(layer "F.Cu")
		(net "GPIO_B_EXP_A0")
	)
	(segment
		(start 127.6858 -17.526)
		(end 129.1082 -17.526)
		(width 0.1016)
		(layer "F.Cu")
		(net "GPIO_B_EXP_A0")
	)
	(segment
		(start 130.937 -22.2885)
		(end 130.937 -23.0632)
		(width 0.1016)
		(layer "F.Cu")
		(net "GPIO_B_EXP_A0")
	)
	(segment
		(start 131.2545 -20.9296)
		(end 131.2545 -21.971)
		(width 0.1016)
		(layer "F.Cu")
		(net "GPIO_B_EXP_A0")
	)
	(segment
		(start 131.2545 -21.971)
		(end 130.937 -22.2885)
		(width 0.1016)
		(layer "F.Cu")
		(net "GPIO_B_EXP_A0")
	)
	(segment
		(start 130.7846 -19.2024)
		(end 130.7846 -20.4597)
		(width 0.1016)
		(layer "F.Cu")
		(net "GPIO_B_EXP_A0")
	)
	(via
		(at 130.937 -23.0632)
		(size 0.7112)
		(drill 0.3556)
		(layers "F.Cu" "B.Cu")
		(net "GPIO_B_EXP_A0")
	)
	(via
		(at 23.801324 -27.0129)
		(size 0.7112)
		(drill 0.3556)
		(layers "F.Cu" "B.Cu")
		(net "ATX_VMONITOR_A1")
	)
	(segment
		(start 24.4221 -27.0891)
		(end 23.877524 -27.0891)
		(width 0.1016)
		(layer "B.Cu")
		(net "ATX_VMONITOR_A1")
	)
	(segment
		(start 23.877524 -27.0891)
		(end 23.801324 -27.0129)
		(width 0.1016)
		(layer "B.Cu")
		(net "ATX_VMONITOR_A1")
	)
	(segment
		(start 26.3652 -26.0477)
		(end 25.3238 -26.0477)
		(width 0.1016)
		(layer "B.Cu")
		(net "ATX_VMONITOR_A1")
	)
	(segment
		(start 25.3238 -26.1874)
		(end 24.4221 -27.0891)
		(width 0.1016)
		(layer "B.Cu")
		(net "ATX_VMONITOR_A1")
	)
	(segment
		(start 25.3238 -26.0477)
		(end 25.3238 -26.1874)
		(width 0.1016)
		(layer "B.Cu")
		(net "ATX_VMONITOR_A1")
	)
	(segment
		(start 23.801324 -24.651462)
		(end 23.801324 -27.0129)
		(width 0.1016)
		(layer "B.Cu")
		(net "ATX_VMONITOR_A1")
	)
	(via
		(at 27.3558 -23.241)
		(size 0.7112)
		(drill 0.3556)
		(layers "F.Cu" "B.Cu")
		(net "ATX_VMONITOR_A0")
	)
	(segment
		(start 26.3652 -23.2029)
		(end 25.3238 -23.2029)
		(width 0.1016)
		(layer "B.Cu")
		(net "ATX_VMONITOR_A0")
	)
	(segment
		(start 25.3238 -23.2029)
		(end 25.2984 -23.2283)
		(width 0.1016)
		(layer "B.Cu")
		(net "ATX_VMONITOR_A0")
	)
	(segment
		(start 27.3177 -23.2029)
		(end 27.3558 -23.241)
		(width 0.1016)
		(layer "B.Cu")
		(net "ATX_VMONITOR_A0")
	)
	(segment
		(start 25.2984 -23.2283)
		(end 25.2984 -23.240492)
		(width 0.1016)
		(layer "B.Cu")
		(net "ATX_VMONITOR_A0")
	)
	(segment
		(start 25.2984 -23.240492)
		(end 24.387556 -24.151336)
		(width 0.1016)
		(layer "B.Cu")
		(net "ATX_VMONITOR_A0")
	)
	(segment
		(start 24.387556 -24.151336)
		(end 23.801324 -24.151336)
		(width 0.1016)
		(layer "B.Cu")
		(net "ATX_VMONITOR_A0")
	)
	(segment
		(start 26.3652 -23.2029)
		(end 27.3177 -23.2029)
		(width 0.1016)
		(layer "B.Cu")
		(net "ATX_VMONITOR_A0")
	)
	(via
		(at 15.9893 -24.2951)
		(size 0.7112)
		(drill 0.3556)
		(layers "F.Cu" "B.Cu")
		(net "ATX_P12V_SENSE_VP_R")
	)
	(segment
		(start 15.9893 -24.2951)
		(end 15.9893 -23.9776)
		(width 0.2032)
		(layer "B.Cu")
		(net "ATX_P12V_SENSE_VP_R")
	)
	(segment
		(start 14.351 -25.465024)
		(end 14.351 -25.054306)
		(width 0.2032)
		(layer "B.Cu")
		(net "ATX_P12V_SENSE_VP_R")
	)
	(segment
		(start 14.855698 -25.606502)
		(end 14.855698 -25.955498)
		(width 0.2032)
		(layer "B.Cu")
		(net "ATX_P12V_SENSE_VP_R")
	)
	(segment
		(start 14.855698 -25.955498)
		(end 15.167102 -26.266902)
		(width 0.2032)
		(layer "B.Cu")
		(net "ATX_P12V_SENSE_VP_R")
	)
	(segment
		(start 21.007324 -25.452324)
		(end 21.500338 -25.452324)
		(width 0.2032)
		(layer "B.Cu")
		(net "ATX_P12V_SENSE_VP_R")
	)
	(segment
		(start 20.701 -25.146)
		(end 21.007324 -25.452324)
		(width 0.2032)
		(layer "B.Cu")
		(net "ATX_P12V_SENSE_VP_R")
	)
	(segment
		(start 15.167102 -26.266902)
		(end 15.548102 -26.266902)
		(width 0.2032)
		(layer "B.Cu")
		(net "ATX_P12V_SENSE_VP_R")
	)
	(segment
		(start 14.492478 -25.606502)
		(end 14.351 -25.465024)
		(width 0.2032)
		(layer "B.Cu")
		(net "ATX_P12V_SENSE_VP_R")
	)
	(segment
		(start 14.351 -25.054306)
		(end 15.427706 -23.9776)
		(width 0.2032)
		(layer "B.Cu")
		(net "ATX_P12V_SENSE_VP_R")
	)
	(segment
		(start 18.669 -23.9776)
		(end 19.8374 -25.146)
		(width 0.2032)
		(layer "B.Cu")
		(net "ATX_P12V_SENSE_VP_R")
	)
	(segment
		(start 15.9893 -23.9776)
		(end 18.669 -23.9776)
		(width 0.2032)
		(layer "B.Cu")
		(net "ATX_P12V_SENSE_VP_R")
	)
	(segment
		(start 19.8374 -25.146)
		(end 20.701 -25.146)
		(width 0.2032)
		(layer "B.Cu")
		(net "ATX_P12V_SENSE_VP_R")
	)
	(segment
		(start 15.427706 -23.9776)
		(end 15.9893 -23.9776)
		(width 0.2032)
		(layer "B.Cu")
		(net "ATX_P12V_SENSE_VP_R")
	)
	(segment
		(start 14.855698 -25.606502)
		(end 14.492478 -25.606502)
		(width 0.2032)
		(layer "B.Cu")
		(net "ATX_P12V_SENSE_VP_R")
	)
	(via
		(at 14.3383 -24.1173)
		(size 0.7112)
		(drill 0.3556)
		(layers "F.Cu" "B.Cu")
		(net "ATX_P12V_SENSE_VN_R")
	)
	(segment
		(start 15.2908 -23.6474)
		(end 14.5796 -24.3586)
		(width 0.2032)
		(layer "B.Cu")
		(net "ATX_P12V_SENSE_VN_R")
	)
	(segment
		(start 14.811502 -26.597102)
		(end 14.811502 -27.003502)
		(width 0.2032)
		(layer "B.Cu")
		(net "ATX_P12V_SENSE_VN_R")
	)
	(segment
		(start 14.227302 -26.234898)
		(end 14.449298 -26.234898)
		(width 0.2032)
		(layer "B.Cu")
		(net "ATX_P12V_SENSE_VN_R")
	)
	(segment
		(start 14.0208 -26.028396)
		(end 14.227302 -26.234898)
		(width 0.2032)
		(layer "B.Cu")
		(net "ATX_P12V_SENSE_VN_R")
	)
	(segment
		(start 14.0208 -24.9174)
		(end 14.0208 -26.028396)
		(width 0.2032)
		(layer "B.Cu")
		(net "ATX_P12V_SENSE_VN_R")
	)
	(segment
		(start 14.449298 -26.234898)
		(end 14.811502 -26.597102)
		(width 0.2032)
		(layer "B.Cu")
		(net "ATX_P12V_SENSE_VN_R")
	)
	(segment
		(start 14.3383 -24.1173)
		(end 14.5796 -24.3586)
		(width 0.2032)
		(layer "B.Cu")
		(net "ATX_P12V_SENSE_VN_R")
	)
	(segment
		(start 14.5796 -24.3586)
		(end 14.0208 -24.9174)
		(width 0.2032)
		(layer "B.Cu")
		(net "ATX_P12V_SENSE_VN_R")
	)
	(segment
		(start 18.805906 -23.6474)
		(end 15.2908 -23.6474)
		(width 0.2032)
		(layer "B.Cu")
		(net "ATX_P12V_SENSE_VN_R")
	)
	(segment
		(start 19.809968 -24.651462)
		(end 18.805906 -23.6474)
		(width 0.2032)
		(layer "B.Cu")
		(net "ATX_P12V_SENSE_VN_R")
	)
	(segment
		(start 20.699476 -24.651462)
		(end 19.809968 -24.651462)
		(width 0.2032)
		(layer "B.Cu")
		(net "ATX_P12V_SENSE_VN_R")
	)
	(segment
		(start 121.562114 -25.4)
		(end 121.639584 -25.47747)
		(width 0.1016)
		(layer "F.Cu")
		(net "TP_USB_OCS_N3")
	)
	(segment
		(start 121.3358 -25.4)
		(end 121.562114 -25.4)
		(width 0.1016)
		(layer "F.Cu")
		(net "TP_USB_OCS_N3")
	)
	(segment
		(start 121.639584 -25.47747)
		(end 121.992644 -25.47747)
		(width 0.1016)
		(layer "F.Cu")
		(net "TP_USB_OCS_N3")
	)
	(segment
		(start 121.992644 -25.47747)
		(end 122.274584 -25.19553)
		(width 0.1016)
		(layer "F.Cu")
		(net "TP_USB_OCS_N3")
	)
	(via
		(at 121.3358 -25.4)
		(size 0.508)
		(drill 0.254)
		(layers "F.Cu" "B.Cu")
		(net "TP_USB_OCS_N3")
	)
	(segment
		(start 121.9962 -26.3017)
		(end 121.9962 -26.0604)
		(width 0.1016)
		(layer "B.Cu")
		(net "TP_USB_OCS_N3")
	)
	(segment
		(start 121.9962 -26.0604)
		(end 121.3358 -25.4)
		(width 0.1016)
		(layer "B.Cu")
		(net "TP_USB_OCS_N3")
	)
	(segment
		(start 121.42978 -26.616406)
		(end 120.647206 -26.616406)
		(width 0.1016)
		(layer "F.Cu")
		(net "TP_USB_OCS_N2")
	)
	(segment
		(start 120.647206 -26.616406)
		(end 119.5832 -25.5524)
		(width 0.1016)
		(layer "F.Cu")
		(net "TP_USB_OCS_N2")
	)
	(via
		(at 119.5832 -25.5524)
		(size 0.508)
		(drill 0.254)
		(layers "F.Cu" "B.Cu")
		(net "TP_USB_OCS_N2")
	)
	(segment
		(start 120.3579 -26.3271)
		(end 120.3579 -26.4795)
		(width 0.1016)
		(layer "B.Cu")
		(net "TP_USB_OCS_N2")
	)
	(segment
		(start 119.5832 -25.5524)
		(end 120.3579 -26.3271)
		(width 0.1016)
		(layer "B.Cu")
		(net "TP_USB_OCS_N2")
	)
	(segment
		(start 120.506744 -28.616656)
		(end 121.42978 -28.616656)
		(width 0.1016)
		(layer "F.Cu")
		(net "TP_USB_OCS_N1")
	)
	(segment
		(start 120.2944 -28.829)
		(end 120.506744 -28.616656)
		(width 0.1016)
		(layer "F.Cu")
		(net "TP_USB_OCS_N1")
	)
	(segment
		(start 120.2436 -28.829)
		(end 120.2944 -28.829)
		(width 0.1016)
		(layer "F.Cu")
		(net "TP_USB_OCS_N1")
	)
	(via
		(at 120.2436 -28.829)
		(size 0.508)
		(drill 0.254)
		(layers "F.Cu" "B.Cu")
		(net "TP_USB_OCS_N1")
	)
	(segment
		(start 120.2944 -28.7782)
		(end 120.2436 -28.829)
		(width 0.1016)
		(layer "B.Cu")
		(net "TP_USB_OCS_N1")
	)
	(segment
		(start 121.2596 -28.7782)
		(end 120.2944 -28.7782)
		(width 0.1016)
		(layer "B.Cu")
		(net "TP_USB_OCS_N1")
	)
	(segment
		(start 124.27458 -24.09698)
		(end 124.206 -24.0284)
		(width 0.3048)
		(layer "F.Cu")
		(net "P3V3_USB_HUB")
	)
	(segment
		(start 128.0795 -24.4475)
		(end 127.4064 -25.1206)
		(width 0.4572)
		(layer "F.Cu")
		(net "P3V3_USB_HUB")
	)
	(segment
		(start 118.3767 -30.2006)
		(end 118.3767 -31.2674)
		(width 0.508)
		(layer "F.Cu")
		(net "P3V3_USB_HUB")
	)
	(segment
		(start 118.3513 -32.3596)
		(end 118.3513 -33.4264)
		(width 0.508)
		(layer "F.Cu")
		(net "P3V3_USB_HUB")
	)
	(segment
		(start 127.11938 -26.616406)
		(end 128.254506 -26.616406)
		(width 0.3048)
		(layer "F.Cu")
		(net "P3V3_USB_HUB")
	)
	(segment
		(start 130.8481 -25.527)
		(end 131.8768 -25.527)
		(width 0.4572)
		(layer "F.Cu")
		(net "P3V3_USB_HUB")
	)
	(segment
		(start 121.4628 -30.6578)
		(end 121.1834 -30.9372)
		(width 0.3048)
		(layer "F.Cu")
		(net "P3V3_USB_HUB")
	)
	(segment
		(start 121.4628 -30.225746)
		(end 121.4628 -30.6578)
		(width 0.3048)
		(layer "F.Cu")
		(net "P3V3_USB_HUB")
	)
	(segment
		(start 118.3767 -31.2674)
		(end 118.3767 -32.3342)
		(width 0.508)
		(layer "F.Cu")
		(net "P3V3_USB_HUB")
	)
	(segment
		(start 127.4572 -30.8356)
		(end 127.19558 -30.57398)
		(width 0.3048)
		(layer "F.Cu")
		(net "P3V3_USB_HUB")
	)
	(segment
		(start 121.35358 -30.116526)
		(end 121.4628 -30.225746)
		(width 0.3048)
		(layer "F.Cu")
		(net "P3V3_USB_HUB")
	)
	(segment
		(start 118.3767 -28.6639)
		(end 118.3386 -28.6258)
		(width 0.4572)
		(layer "F.Cu")
		(net "P3V3_USB_HUB")
	)
	(segment
		(start 124.27458 -25.27173)
		(end 124.27458 -24.09698)
		(width 0.3048)
		(layer "F.Cu")
		(net "P3V3_USB_HUB")
	)
	(segment
		(start 127.19558 -30.57398)
		(end 127.19558 -30.116526)
		(width 0.3048)
		(layer "F.Cu")
		(net "P3V3_USB_HUB")
	)
	(segment
		(start 118.3767 -30.2006)
		(end 118.3767 -28.6639)
		(width 0.4572)
		(layer "F.Cu")
		(net "P3V3_USB_HUB")
	)
	(segment
		(start 118.3767 -32.3342)
		(end 118.3513 -32.3596)
		(width 0.508)
		(layer "F.Cu")
		(net "P3V3_USB_HUB")
	)
	(segment
		(start 128.0795 -23.5458)
		(end 128.0795 -24.4475)
		(width 0.4572)
		(layer "F.Cu")
		(net "P3V3_USB_HUB")
	)
	(segment
		(start 124.27458 -30.96133)
		(end 124.27458 -32.1183)
		(width 0.3048)
		(layer "F.Cu")
		(net "P3V3_USB_HUB")
	)
	(segment
		(start 128.254506 -26.616406)
		(end 128.28778 -26.64968)
		(width 0.3048)
		(layer "F.Cu")
		(net "P3V3_USB_HUB")
	)
	(segment
		(start 121.42978 -27.616404)
		(end 120.2436 -27.616404)
		(width 0.3048)
		(layer "F.Cu")
		(net "P3V3_USB_HUB")
	)
	(via
		(at 115.7986 -20.7264)
		(size 0.508)
		(drill 0.254)
		(layers "F.Cu" "B.Cu")
		(net "P3V3_USB_HUB")
	)
	(via
		(at 124.206 -24.0284)
		(size 0.508)
		(drill 0.254)
		(layers "F.Cu" "B.Cu")
		(net "P3V3_USB_HUB")
	)
	(via
		(at 120.9548 -20.0914)
		(size 0.508)
		(drill 0.254)
		(layers "F.Cu" "B.Cu")
		(net "P3V3_USB_HUB")
	)
	(via
		(at 118.3386 -28.6258)
		(size 0.508)
		(drill 0.254)
		(layers "F.Cu" "B.Cu")
		(net "P3V3_USB_HUB")
	)
	(via
		(at 120.2436 -27.616404)
		(size 0.508)
		(drill 0.254)
		(layers "F.Cu" "B.Cu")
		(net "P3V3_USB_HUB")
	)
	(via
		(at 127.4572 -30.8356)
		(size 0.508)
		(drill 0.254)
		(layers "F.Cu" "B.Cu")
		(net "P3V3_USB_HUB")
	)
	(via
		(at 124.27458 -32.1183)
		(size 0.508)
		(drill 0.254)
		(layers "F.Cu" "B.Cu")
		(net "P3V3_USB_HUB")
	)
	(via
		(at 128.28778 -26.64968)
		(size 0.508)
		(drill 0.254)
		(layers "F.Cu" "B.Cu")
		(net "P3V3_USB_HUB")
	)
	(via
		(at 125.9713 -31.9786)
		(size 0.7112)
		(drill 0.3556)
		(layers "F.Cu" "B.Cu")
		(net "P3V3_USB_HUB")
	)
	(via
		(at 121.1834 -30.9372)
		(size 0.508)
		(drill 0.254)
		(layers "F.Cu" "B.Cu")
		(net "P3V3_USB_HUB")
	)
	(via
		(at 131.8768 -25.527)
		(size 0.508)
		(drill 0.254)
		(layers "F.Cu" "B.Cu")
		(net "P3V3_USB_HUB")
	)
	(via
		(at 127.4064 -25.1206)
		(size 0.508)
		(drill 0.254)
		(layers "F.Cu" "B.Cu")
		(net "P3V3_USB_HUB")
	)
	(segment
		(start 122.48134 -18.55216)
		(end 122.4661 -18.5674)
		(width 0.3048)
		(layer "B.Cu")
		(net "P3V3_USB_HUB")
	)
	(segment
		(start 117.7417 -18.796)
		(end 117.729 -18.796)
		(width 0.4064)
		(layer "B.Cu")
		(net "P3V3_USB_HUB")
	)
	(segment
		(start 117.729 -18.796)
		(end 115.7986 -20.7264)
		(width 0.4064)
		(layer "B.Cu")
		(net "P3V3_USB_HUB")
	)
	(segment
		(start 120.250204 -27.6098)
		(end 120.2436 -27.616404)
		(width 0.508)
		(layer "B.Cu")
		(net "P3V3_USB_HUB")
	)
	(segment
		(start 117.7036 -15.5956)
		(end 118.6688 -14.6304)
		(width 0.4572)
		(layer "B.Cu")
		(net "P3V3_USB_HUB")
	)
	(segment
		(start 124.3965 -25.146)
		(end 124.2822 -25.2603)
		(width 0.4572)
		(layer "B.Cu")
		(net "P3V3_USB_HUB")
	)
	(segment
		(start 120.5357 -19.6723)
		(end 120.5357 -18.796)
		(width 0.508)
		(layer "B.Cu")
		(net "P3V3_USB_HUB")
	)
	(segment
		(start 120.5357 -18.796)
		(end 122.2375 -18.796)
		(width 0.508)
		(layer "B.Cu")
		(net "P3V3_USB_HUB")
	)
	(segment
		(start 121.1199 -27.6098)
		(end 120.250204 -27.6098)
		(width 0.508)
		(layer "B.Cu")
		(net "P3V3_USB_HUB")
	)
	(segment
		(start 120.9548 -20.0914)
		(end 120.5357 -19.6723)
		(width 0.508)
		(layer "B.Cu")
		(net "P3V3_USB_HUB")
	)
	(segment
		(start 118.6688 -14.6304)
		(end 119.4943 -14.6304)
		(width 0.4572)
		(layer "B.Cu")
		(net "P3V3_USB_HUB")
	)
	(segment
		(start 122.2375 -18.796)
		(end 122.4661 -18.5674)
		(width 0.508)
		(layer "B.Cu")
		(net "P3V3_USB_HUB")
	)
	(segment
		(start 117.7417 -18.796)
		(end 117.7036 -18.7579)
		(width 0.4572)
		(layer "B.Cu")
		(net "P3V3_USB_HUB")
	)
	(segment
		(start 124.2822 -24.1046)
		(end 124.206 -24.0284)
		(width 0.4572)
		(layer "B.Cu")
		(net "P3V3_USB_HUB")
	)
	(segment
		(start 124.2822 -25.2603)
		(end 124.2822 -24.1046)
		(width 0.4572)
		(layer "B.Cu")
		(net "P3V3_USB_HUB")
	)
	(segment
		(start 122.48134 -16.90116)
		(end 122.48134 -18.55216)
		(width 0.3048)
		(layer "B.Cu")
		(net "P3V3_USB_HUB")
	)
	(segment
		(start 117.7036 -18.7579)
		(end 117.7036 -15.5956)
		(width 0.4572)
		(layer "B.Cu")
		(net "P3V3_USB_HUB")
	)
	(segment
		(start 125.3109 -25.146)
		(end 124.3965 -25.146)
		(width 0.4572)
		(layer "B.Cu")
		(net "P3V3_USB_HUB")
	)
	(segment
		(start 120.9548 -20.1676)
		(end 123.5964 -22.8092)
		(width 0.508)
		(layer "In2.Cu")
		(net "P3V3_USB_HUB")
	)
	(segment
		(start 120.9548 -20.0914)
		(end 120.9548 -20.1676)
		(width 0.508)
		(layer "In2.Cu")
		(net "P3V3_USB_HUB")
	)
	(segment
		(start 123.5964 -23.4188)
		(end 124.206 -24.0284)
		(width 0.508)
		(layer "In2.Cu")
		(net "P3V3_USB_HUB")
	)
	(segment
		(start 123.5964 -22.8092)
		(end 123.5964 -23.4188)
		(width 0.508)
		(layer "In2.Cu")
		(net "P3V3_USB_HUB")
	)
	(segment
		(start 128.84658 -25.527)
		(end 128.359662 -26.013918)
		(width 0.635)
		(layer "In3.Cu")
		(net "P3V3_USB_HUB")
	)
	(segment
		(start 128.359662 -26.013918)
		(end 128.359662 -26.577798)
		(width 0.635)
		(layer "In3.Cu")
		(net "P3V3_USB_HUB")
	)
	(segment
		(start 131.8768 -25.527)
		(end 128.84658 -25.527)
		(width 0.635)
		(layer "In3.Cu")
		(net "P3V3_USB_HUB")
	)
	(segment
		(start 117.2718 -19.2532)
		(end 115.7986 -20.7264)
		(width 0.508)
		(layer "In3.Cu")
		(net "P3V3_USB_HUB")
	)
	(segment
		(start 128.359662 -26.577798)
		(end 128.28778 -26.64968)
		(width 0.635)
		(layer "In3.Cu")
		(net "P3V3_USB_HUB")
	)
	(segment
		(start 120.9548 -20.0914)
		(end 120.1166 -19.2532)
		(width 0.508)
		(layer "In3.Cu")
		(net "P3V3_USB_HUB")
	)
	(segment
		(start 120.1166 -19.2532)
		(end 117.2718 -19.2532)
		(width 0.508)
		(layer "In3.Cu")
		(net "P3V3_USB_HUB")
	)
	(segment
		(start 123.032012 -24.047958)
		(end 123.274582 -24.290528)
		(width 0.1016)
		(layer "F.Cu")
		(net "TP_USB_OCS_N4")
	)
	(segment
		(start 122.372374 -24.047958)
		(end 123.032012 -24.047958)
		(width 0.1016)
		(layer "F.Cu")
		(net "TP_USB_OCS_N4")
	)
	(segment
		(start 123.274582 -24.290528)
		(end 123.274582 -25.27173)
		(width 0.1016)
		(layer "F.Cu")
		(net "TP_USB_OCS_N4")
	)
	(via
		(at 122.372374 -24.047958)
		(size 0.508)
		(drill 0.254)
		(layers "F.Cu" "B.Cu")
		(net "TP_USB_OCS_N4")
	)
	(segment
		(start 122.9614 -24.6126)
		(end 122.442732 -24.093932)
		(width 0.1016)
		(layer "B.Cu")
		(net "TP_USB_OCS_N4")
	)
	(segment
		(start 122.418348 -24.093932)
		(end 122.372374 -24.047958)
		(width 0.1016)
		(layer "B.Cu")
		(net "TP_USB_OCS_N4")
	)
	(segment
		(start 122.442732 -24.093932)
		(end 122.418348 -24.093932)
		(width 0.1016)
		(layer "B.Cu")
		(net "TP_USB_OCS_N4")
	)
	(segment
		(start 122.9614 -25.0825)
		(end 122.9614 -24.6126)
		(width 0.1016)
		(layer "B.Cu")
		(net "TP_USB_OCS_N4")
	)
	(segment
		(start 119.2657 -28.9687)
		(end 119.3038 -28.9306)
		(width 0.1016)
		(layer "F.Cu")
		(net "TP_USB_DP3")
	)
	(segment
		(start 119.2657 -30.2006)
		(end 120.7135 -31.6484)
		(width 0.1016)
		(layer "F.Cu")
		(net "TP_USB_DP3")
	)
	(segment
		(start 121.9454 -31.6484)
		(end 122.274584 -31.319216)
		(width 0.1016)
		(layer "F.Cu")
		(net "TP_USB_DP3")
	)
	(segment
		(start 122.274584 -31.319216)
		(end 122.274584 -31.03753)
		(width 0.1016)
		(layer "F.Cu")
		(net "TP_USB_DP3")
	)
	(segment
		(start 120.7135 -31.6484)
		(end 121.9454 -31.6484)
		(width 0.1016)
		(layer "F.Cu")
		(net "TP_USB_DP3")
	)
	(segment
		(start 119.2657 -30.2006)
		(end 119.2657 -28.9687)
		(width 0.1016)
		(layer "F.Cu")
		(net "TP_USB_DP3")
	)
	(via
		(at 119.3038 -28.9306)
		(size 0.7112)
		(drill 0.3556)
		(layers "F.Cu" "B.Cu")
		(net "TP_USB_DP3")
	)
	(segment
		(start 122.774456 -31.809944)
		(end 121.9962 -32.5882)
		(width 0.1016)
		(layer "F.Cu")
		(net "TP_USB_DN3")
	)
	(segment
		(start 120.6119 -32.6136)
		(end 119.2657 -31.2674)
		(width 0.1016)
		(layer "F.Cu")
		(net "TP_USB_DN3")
	)
	(segment
		(start 121.6406 -32.6136)
		(end 120.6119 -32.6136)
		(width 0.1016)
		(layer "F.Cu")
		(net "TP_USB_DN3")
	)
	(segment
		(start 121.666 -32.5882)
		(end 121.6406 -32.6136)
		(width 0.1016)
		(layer "F.Cu")
		(net "TP_USB_DN3")
	)
	(segment
		(start 121.9962 -32.5882)
		(end 121.666 -32.5882)
		(width 0.1016)
		(layer "F.Cu")
		(net "TP_USB_DN3")
	)
	(segment
		(start 122.774456 -30.96133)
		(end 122.774456 -31.809944)
		(width 0.1016)
		(layer "F.Cu")
		(net "TP_USB_DN3")
	)
	(via
		(at 121.6406 -32.6136)
		(size 0.7112)
		(drill 0.3556)
		(layers "F.Cu" "B.Cu")
		(net "TP_USB_DN3")
	)
	(segment
		(start 121.49836 -13.62456)
		(end 122.047 -13.62456)
		(width 0.1016)
		(layer "F.Cu")
		(net "PCIE_SLOT3_PRSNT2_3_N")
	)
	(segment
		(start 123.2916 -10.8712)
		(end 123.2916 -13.3096)
		(width 0.1016)
		(layer "F.Cu")
		(net "PCIE_SLOT3_PRSNT2_3_N")
	)
	(segment
		(start 79.2734 -24.4602)
		(end 79.0194 -24.2062)
		(width 0.1016)
		(layer "F.Cu")
		(net "PCIE_SLOT3_PRSNT2_3_N")
	)
	(segment
		(start 116.2812 -13.4874)
		(end 121.3612 -13.4874)
		(width 0.1016)
		(layer "F.Cu")
		(net "PCIE_SLOT3_PRSNT2_3_N")
	)
	(segment
		(start 122.97664 -13.62456)
		(end 122.047 -13.62456)
		(width 0.1016)
		(layer "F.Cu")
		(net "PCIE_SLOT3_PRSNT2_3_N")
	)
	(segment
		(start 80.3275 -27.322018)
		(end 80.079342 -27.570176)
		(width 0.1016)
		(layer "F.Cu")
		(net "PCIE_SLOT3_PRSNT2_3_N")
	)
	(segment
		(start 124.52096 -8.8138)
		(end 124.52096 -9.64184)
		(width 0.1016)
		(layer "F.Cu")
		(net "PCIE_SLOT3_PRSNT2_3_N")
	)
	(segment
		(start 107.4928 -20.207732)
		(end 112.689132 -15.0114)
		(width 0.1016)
		(layer "F.Cu")
		(net "PCIE_SLOT3_PRSNT2_3_N")
	)
	(segment
		(start 123.2916 -13.3096)
		(end 122.97664 -13.62456)
		(width 0.1016)
		(layer "F.Cu")
		(net "PCIE_SLOT3_PRSNT2_3_N")
	)
	(segment
		(start 124.52096 -9.64184)
		(end 123.2916 -10.8712)
		(width 0.1016)
		(layer "F.Cu")
		(net "PCIE_SLOT3_PRSNT2_3_N")
	)
	(segment
		(start 80.3275 -24.4602)
		(end 80.3275 -27.322018)
		(width 0.1016)
		(layer "F.Cu")
		(net "PCIE_SLOT3_PRSNT2_3_N")
	)
	(segment
		(start 112.689132 -15.0114)
		(end 114.7572 -15.0114)
		(width 0.1016)
		(layer "F.Cu")
		(net "PCIE_SLOT3_PRSNT2_3_N")
	)
	(segment
		(start 107.4928 -23.5966)
		(end 107.4928 -20.207732)
		(width 0.1016)
		(layer "F.Cu")
		(net "PCIE_SLOT3_PRSNT2_3_N")
	)
	(segment
		(start 80.3275 -24.4602)
		(end 79.2734 -24.4602)
		(width 0.1016)
		(layer "F.Cu")
		(net "PCIE_SLOT3_PRSNT2_3_N")
	)
	(segment
		(start 114.7572 -15.0114)
		(end 116.2812 -13.4874)
		(width 0.1016)
		(layer "F.Cu")
		(net "PCIE_SLOT3_PRSNT2_3_N")
	)
	(segment
		(start 107.6706 -23.7744)
		(end 107.4928 -23.5966)
		(width 0.1016)
		(layer "F.Cu")
		(net "PCIE_SLOT3_PRSNT2_3_N")
	)
	(segment
		(start 121.3612 -13.4874)
		(end 121.49836 -13.62456)
		(width 0.1016)
		(layer "F.Cu")
		(net "PCIE_SLOT3_PRSNT2_3_N")
	)
	(via
		(at 107.6706 -23.7744)
		(size 0.508)
		(drill 0.254)
		(layers "F.Cu" "B.Cu")
		(net "PCIE_SLOT3_PRSNT2_3_N")
	)
	(via
		(at 108.5977 -24.1046)
		(size 0.7112)
		(drill 0.3556)
		(layers "F.Cu" "B.Cu")
		(net "PCIE_SLOT3_PRSNT2_3_N")
	)
	(via
		(at 79.0194 -24.2062)
		(size 0.508)
		(drill 0.254)
		(layers "F.Cu" "B.Cu")
		(net "PCIE_SLOT3_PRSNT2_3_N")
	)
	(segment
		(start 108.0008 -24.1046)
		(end 107.6706 -23.7744)
		(width 0.1016)
		(layer "B.Cu")
		(net "PCIE_SLOT3_PRSNT2_3_N")
	)
	(segment
		(start 108.5977 -24.1046)
		(end 108.0008 -24.1046)
		(width 0.1016)
		(layer "B.Cu")
		(net "PCIE_SLOT3_PRSNT2_3_N")
	)
	(segment
		(start 79.0194 -24.2062)
		(end 79.4512 -23.7744)
		(width 0.127)
		(layer "In3.Cu")
		(net "PCIE_SLOT3_PRSNT2_3_N")
	)
	(segment
		(start 79.4512 -23.7744)
		(end 107.6706 -23.7744)
		(width 0.127)
		(layer "In3.Cu")
		(net "PCIE_SLOT3_PRSNT2_3_N")
	)
	(segment
		(start 63.881 -15.7226)
		(end 63.4238 -16.1798)
		(width 0.1016)
		(layer "F.Cu")
		(net "PCIE_SLOT2_PRSNT2_2_N")
	)
	(segment
		(start 63.0936 -13.208)
		(end 63.0936 -15.8623)
		(width 0.1016)
		(layer "F.Cu")
		(net "PCIE_SLOT2_PRSNT2_2_N")
	)
	(segment
		(start 118.095268 -17.27454)
		(end 112.869726 -17.27454)
		(width 0.1016)
		(layer "F.Cu")
		(net "PCIE_SLOT2_PRSNT2_2_N")
	)
	(segment
		(start 63.080392 -9.250426)
		(end 62.1665 -10.164318)
		(width 0.1016)
		(layer "F.Cu")
		(net "PCIE_SLOT2_PRSNT2_2_N")
	)
	(segment
		(start 126.746508 -10.414)
		(end 126.71806 -10.414)
		(width 0.1016)
		(layer "F.Cu")
		(net "PCIE_SLOT2_PRSNT2_2_N")
	)
	(segment
		(start 127.77216 -9.388348)
		(end 126.746508 -10.414)
		(width 0.1016)
		(layer "F.Cu")
		(net "PCIE_SLOT2_PRSNT2_2_N")
	)
	(segment
		(start 124.8156 -12.31646)
		(end 124.8156 -14.961108)
		(width 0.1016)
		(layer "F.Cu")
		(net "PCIE_SLOT2_PRSNT2_2_N")
	)
	(segment
		(start 62.1665 -12.2809)
		(end 63.0936 -13.208)
		(width 0.1016)
		(layer "F.Cu")
		(net "PCIE_SLOT2_PRSNT2_2_N")
	)
	(segment
		(start 62.1665 -10.164318)
		(end 62.1665 -12.2809)
		(width 0.1016)
		(layer "F.Cu")
		(net "PCIE_SLOT2_PRSNT2_2_N")
	)
	(segment
		(start 127.77216 -8.8138)
		(end 127.77216 -9.388348)
		(width 0.1016)
		(layer "F.Cu")
		(net "PCIE_SLOT2_PRSNT2_2_N")
	)
	(segment
		(start 121.27484 -16.87576)
		(end 120.598946 -17.551654)
		(width 0.1016)
		(layer "F.Cu")
		(net "PCIE_SLOT2_PRSNT2_2_N")
	)
	(segment
		(start 122.900948 -16.87576)
		(end 122.047 -16.87576)
		(width 0.1016)
		(layer "F.Cu")
		(net "PCIE_SLOT2_PRSNT2_2_N")
	)
	(segment
		(start 112.869726 -17.27454)
		(end 112.505236 -16.91005)
		(width 0.1016)
		(layer "F.Cu")
		(net "PCIE_SLOT2_PRSNT2_2_N")
	)
	(segment
		(start 122.047 -16.87576)
		(end 121.27484 -16.87576)
		(width 0.1016)
		(layer "F.Cu")
		(net "PCIE_SLOT2_PRSNT2_2_N")
	)
	(segment
		(start 124.8156 -14.961108)
		(end 122.900948 -16.87576)
		(width 0.1016)
		(layer "F.Cu")
		(net "PCIE_SLOT2_PRSNT2_2_N")
	)
	(segment
		(start 63.4238 -16.1798)
		(end 63.4111 -16.1798)
		(width 0.1016)
		(layer "F.Cu")
		(net "PCIE_SLOT2_PRSNT2_2_N")
	)
	(segment
		(start 63.881 -15.3162)
		(end 63.881 -15.7226)
		(width 0.1016)
		(layer "F.Cu")
		(net "PCIE_SLOT2_PRSNT2_2_N")
	)
	(segment
		(start 118.372382 -17.551654)
		(end 118.095268 -17.27454)
		(width 0.1016)
		(layer "F.Cu")
		(net "PCIE_SLOT2_PRSNT2_2_N")
	)
	(segment
		(start 63.0936 -15.8623)
		(end 63.4111 -16.1798)
		(width 0.1016)
		(layer "F.Cu")
		(net "PCIE_SLOT2_PRSNT2_2_N")
	)
	(segment
		(start 126.71806 -10.414)
		(end 124.8156 -12.31646)
		(width 0.1016)
		(layer "F.Cu")
		(net "PCIE_SLOT2_PRSNT2_2_N")
	)
	(segment
		(start 120.598946 -17.551654)
		(end 118.372382 -17.551654)
		(width 0.1016)
		(layer "F.Cu")
		(net "PCIE_SLOT2_PRSNT2_2_N")
	)
	(via
		(at 113.284 -18.1864)
		(size 0.7112)
		(drill 0.3556)
		(layers "F.Cu" "B.Cu")
		(net "PCIE_SLOT2_PRSNT2_2_N")
	)
	(via
		(at 63.881 -15.3162)
		(size 0.508)
		(drill 0.254)
		(layers "F.Cu" "B.Cu")
		(net "PCIE_SLOT2_PRSNT2_2_N")
	)
	(via
		(at 112.505236 -16.91005)
		(size 0.508)
		(drill 0.254)
		(layers "F.Cu" "B.Cu")
		(net "PCIE_SLOT2_PRSNT2_2_N")
	)
	(segment
		(start 113.284 -18.1864)
		(end 113.284 -17.688814)
		(width 0.1016)
		(layer "B.Cu")
		(net "PCIE_SLOT2_PRSNT2_2_N")
	)
	(segment
		(start 113.284 -17.688814)
		(end 112.505236 -16.91005)
		(width 0.1016)
		(layer "B.Cu")
		(net "PCIE_SLOT2_PRSNT2_2_N")
	)
	(segment
		(start 110.26394 -16.129)
		(end 109.70514 -15.5702)
		(width 0.127)
		(layer "In3.Cu")
		(net "PCIE_SLOT2_PRSNT2_2_N")
	)
	(segment
		(start 77.216 -15.5702)
		(end 76.962 -15.3162)
		(width 0.127)
		(layer "In3.Cu")
		(net "PCIE_SLOT2_PRSNT2_2_N")
	)
	(segment
		(start 111.724186 -16.129)
		(end 110.26394 -16.129)
		(width 0.127)
		(layer "In3.Cu")
		(net "PCIE_SLOT2_PRSNT2_2_N")
	)
	(segment
		(start 112.505236 -16.91005)
		(end 111.724186 -16.129)
		(width 0.127)
		(layer "In3.Cu")
		(net "PCIE_SLOT2_PRSNT2_2_N")
	)
	(segment
		(start 109.70514 -15.5702)
		(end 77.216 -15.5702)
		(width 0.127)
		(layer "In3.Cu")
		(net "PCIE_SLOT2_PRSNT2_2_N")
	)
	(segment
		(start 76.962 -15.3162)
		(end 63.881 -15.3162)
		(width 0.127)
		(layer "In3.Cu")
		(net "PCIE_SLOT2_PRSNT2_2_N")
	)
	(segment
		(start 121.055892 -17.526)
		(end 122.047 -17.526)
		(width 0.1016)
		(layer "F.Cu")
		(net "PCIE_SLOT2_PRSNT2_1_N")
	)
	(segment
		(start 126.873 -10.7188)
		(end 127.50419 -10.08761)
		(width 0.1016)
		(layer "F.Cu")
		(net "PCIE_SLOT2_PRSNT2_1_N")
	)
	(segment
		(start 51.1175 -14.2113)
		(end 51.1175 -13.3731)
		(width 0.1016)
		(layer "F.Cu")
		(net "PCIE_SLOT2_PRSNT2_1_N")
	)
	(segment
		(start 51.9176 -15.0114)
		(end 51.1175 -14.2113)
		(width 0.1016)
		(layer "F.Cu")
		(net "PCIE_SLOT2_PRSNT2_1_N")
	)
	(segment
		(start 55.8419 -15.1765)
		(end 55.6768 -15.0114)
		(width 0.1016)
		(layer "F.Cu")
		(net "PCIE_SLOT2_PRSNT2_1_N")
	)
	(segment
		(start 117.968776 -17.57934)
		(end 118.24589 -17.856454)
		(width 0.1016)
		(layer "F.Cu")
		(net "PCIE_SLOT2_PRSNT2_1_N")
	)
	(segment
		(start 120.725438 -17.856454)
		(end 121.055892 -17.526)
		(width 0.1016)
		(layer "F.Cu")
		(net "PCIE_SLOT2_PRSNT2_1_N")
	)
	(segment
		(start 50.1396 -10.414)
		(end 49.079912 -9.354312)
		(width 0.1016)
		(layer "F.Cu")
		(net "PCIE_SLOT2_PRSNT2_1_N")
	)
	(segment
		(start 49.079912 -9.354312)
		(end 49.079912 -9.250426)
		(width 0.1016)
		(layer "F.Cu")
		(net "PCIE_SLOT2_PRSNT2_1_N")
	)
	(segment
		(start 126.844552 -10.7188)
		(end 126.873 -10.7188)
		(width 0.1016)
		(layer "F.Cu")
		(net "PCIE_SLOT2_PRSNT2_1_N")
	)
	(segment
		(start 125.1458 -12.417552)
		(end 126.844552 -10.7188)
		(width 0.1016)
		(layer "F.Cu")
		(net "PCIE_SLOT2_PRSNT2_1_N")
	)
	(segment
		(start 122.047 -17.526)
		(end 123.760484 -17.526)
		(width 0.1016)
		(layer "F.Cu")
		(net "PCIE_SLOT2_PRSNT2_1_N")
	)
	(segment
		(start 127.50419 -10.08761)
		(end 127.68961 -10.08761)
		(width 0.1016)
		(layer "F.Cu")
		(net "PCIE_SLOT2_PRSNT2_1_N")
	)
	(segment
		(start 54.9529 -15.0114)
		(end 51.9176 -15.0114)
		(width 0.1016)
		(layer "F.Cu")
		(net "PCIE_SLOT2_PRSNT2_1_N")
	)
	(segment
		(start 50.1396 -12.3952)
		(end 50.1396 -10.414)
		(width 0.1016)
		(layer "F.Cu")
		(net "PCIE_SLOT2_PRSNT2_1_N")
	)
	(segment
		(start 125.1458 -16.140684)
		(end 125.1458 -12.417552)
		(width 0.1016)
		(layer "F.Cu")
		(net "PCIE_SLOT2_PRSNT2_1_N")
	)
	(segment
		(start 128.4224 -9.35482)
		(end 128.4224 -8.8138)
		(width 0.1016)
		(layer "F.Cu")
		(net "PCIE_SLOT2_PRSNT2_1_N")
	)
	(segment
		(start 123.760484 -17.526)
		(end 125.1458 -16.140684)
		(width 0.1016)
		(layer "F.Cu")
		(net "PCIE_SLOT2_PRSNT2_1_N")
	)
	(segment
		(start 127.68961 -10.08761)
		(end 128.4224 -9.35482)
		(width 0.1016)
		(layer "F.Cu")
		(net "PCIE_SLOT2_PRSNT2_1_N")
	)
	(segment
		(start 111.959136 -17.57934)
		(end 117.968776 -17.57934)
		(width 0.1016)
		(layer "F.Cu")
		(net "PCIE_SLOT2_PRSNT2_1_N")
	)
	(segment
		(start 55.8419 -15.9004)
		(end 54.9529 -15.0114)
		(width 0.1016)
		(layer "F.Cu")
		(net "PCIE_SLOT2_PRSNT2_1_N")
	)
	(segment
		(start 55.8419 -15.9004)
		(end 55.8419 -15.1765)
		(width 0.1016)
		(layer "F.Cu")
		(net "PCIE_SLOT2_PRSNT2_1_N")
	)
	(segment
		(start 51.1175 -13.3731)
		(end 50.1396 -12.3952)
		(width 0.1016)
		(layer "F.Cu")
		(net "PCIE_SLOT2_PRSNT2_1_N")
	)
	(segment
		(start 118.24589 -17.856454)
		(end 120.725438 -17.856454)
		(width 0.1016)
		(layer "F.Cu")
		(net "PCIE_SLOT2_PRSNT2_1_N")
	)
	(via
		(at 55.6768 -15.0114)
		(size 0.508)
		(drill 0.254)
		(layers "F.Cu" "B.Cu")
		(net "PCIE_SLOT2_PRSNT2_1_N")
	)
	(via
		(at 112.4204 -19.1262)
		(size 0.7112)
		(drill 0.3556)
		(layers "F.Cu" "B.Cu")
		(net "PCIE_SLOT2_PRSNT2_1_N")
	)
	(via
		(at 111.959136 -17.57934)
		(size 0.508)
		(drill 0.254)
		(layers "F.Cu" "B.Cu")
		(net "PCIE_SLOT2_PRSNT2_1_N")
	)
	(segment
		(start 112.4458 -19.1008)
		(end 112.4458 -18.066004)
		(width 0.1016)
		(layer "B.Cu")
		(net "PCIE_SLOT2_PRSNT2_1_N")
	)
	(segment
		(start 112.4458 -18.066004)
		(end 111.959136 -17.57934)
		(width 0.1016)
		(layer "B.Cu")
		(net "PCIE_SLOT2_PRSNT2_1_N")
	)
	(segment
		(start 112.4204 -19.1262)
		(end 112.4458 -19.1008)
		(width 0.1016)
		(layer "B.Cu")
		(net "PCIE_SLOT2_PRSNT2_1_N")
	)
	(segment
		(start 61.5823 -15.0368)
		(end 55.7022 -15.0368)
		(width 0.127)
		(layer "In3.Cu")
		(net "PCIE_SLOT2_PRSNT2_1_N")
	)
	(segment
		(start 76.964794 -15.7861)
		(end 62.3316 -15.7861)
		(width 0.127)
		(layer "In3.Cu")
		(net "PCIE_SLOT2_PRSNT2_1_N")
	)
	(segment
		(start 111.247174 -17.57934)
		(end 109.568234 -15.9004)
		(width 0.127)
		(layer "In3.Cu")
		(net "PCIE_SLOT2_PRSNT2_1_N")
	)
	(segment
		(start 109.568234 -15.9004)
		(end 77.079094 -15.9004)
		(width 0.127)
		(layer "In3.Cu")
		(net "PCIE_SLOT2_PRSNT2_1_N")
	)
	(segment
		(start 111.959136 -17.57934)
		(end 111.247174 -17.57934)
		(width 0.127)
		(layer "In3.Cu")
		(net "PCIE_SLOT2_PRSNT2_1_N")
	)
	(segment
		(start 62.3316 -15.7861)
		(end 61.5823 -15.0368)
		(width 0.127)
		(layer "In3.Cu")
		(net "PCIE_SLOT2_PRSNT2_1_N")
	)
	(segment
		(start 55.7022 -15.0368)
		(end 55.6768 -15.0114)
		(width 0.127)
		(layer "In3.Cu")
		(net "PCIE_SLOT2_PRSNT2_1_N")
	)
	(segment
		(start 77.079094 -15.9004)
		(end 76.964794 -15.7861)
		(width 0.127)
		(layer "In3.Cu")
		(net "PCIE_SLOT2_PRSNT2_1_N")
	)
	(segment
		(start 126.274576 -24.880824)
		(end 126.274576 -25.19553)
		(width 0.1016)
		(layer "F.Cu")
		(net "VBUS_DET")
	)
	(segment
		(start 127.2159 -22.5679)
		(end 127.2159 -23.5204)
		(width 0.1016)
		(layer "F.Cu")
		(net "VBUS_DET")
	)
	(segment
		(start 127.1905 -23.5458)
		(end 127.0508 -23.6855)
		(width 0.1016)
		(layer "F.Cu")
		(net "VBUS_DET")
	)
	(segment
		(start 127.0508 -23.6855)
		(end 127.0508 -24.1046)
		(width 0.1016)
		(layer "F.Cu")
		(net "VBUS_DET")
	)
	(segment
		(start 127.2159 -23.5204)
		(end 127.1905 -23.5458)
		(width 0.1016)
		(layer "F.Cu")
		(net "VBUS_DET")
	)
	(segment
		(start 127.3048 -22.479)
		(end 127.2286 -22.5552)
		(width 0.1016)
		(layer "F.Cu")
		(net "VBUS_DET")
	)
	(segment
		(start 127.0508 -24.1046)
		(end 126.274576 -24.880824)
		(width 0.1016)
		(layer "F.Cu")
		(net "VBUS_DET")
	)
	(segment
		(start 127.2286 -22.5552)
		(end 127.2159 -22.5679)
		(width 0.1016)
		(layer "F.Cu")
		(net "VBUS_DET")
	)
	(segment
		(start 128.2573 -22.479)
		(end 127.3048 -22.479)
		(width 0.1016)
		(layer "F.Cu")
		(net "VBUS_DET")
	)
	(via
		(at 127.2286 -22.5552)
		(size 0.7112)
		(drill 0.3556)
		(layers "F.Cu" "B.Cu")
		(net "VBUS_DET")
	)
	(segment
		(start 105.9942 -17.7038)
		(end 104.394 -16.1036)
		(width 0.1016)
		(layer "F.Cu")
		(net "USB_RESET_N")
	)
	(segment
		(start 125.476 -22.6568)
		(end 125.476 -22.739096)
		(width 0.1016)
		(layer "F.Cu")
		(net "USB_RESET_N")
	)
	(segment
		(start 96.9645 -16.1036)
		(end 96.647 -16.4211)
		(width 0.1016)
		(layer "F.Cu")
		(net "USB_RESET_N")
	)
	(segment
		(start 125.774704 -23.0378)
		(end 125.774704 -25.27173)
		(width 0.1016)
		(layer "F.Cu")
		(net "USB_RESET_N")
	)
	(segment
		(start 125.476 -22.739096)
		(end 125.774704 -23.0378)
		(width 0.1016)
		(layer "F.Cu")
		(net "USB_RESET_N")
	)
	(segment
		(start 104.394 -16.1036)
		(end 96.9645 -16.1036)
		(width 0.1016)
		(layer "F.Cu")
		(net "USB_RESET_N")
	)
	(via
		(at 116.3066 -23.6728)
		(size 0.508)
		(drill 0.254)
		(layers "F.Cu" "B.Cu")
		(net "USB_RESET_N")
	)
	(via
		(at 115.1128 -23.5458)
		(size 0.7112)
		(drill 0.3556)
		(layers "F.Cu" "B.Cu")
		(net "USB_RESET_N")
	)
	(via
		(at 105.9942 -17.7038)
		(size 0.508)
		(drill 0.254)
		(layers "F.Cu" "B.Cu")
		(net "USB_RESET_N")
	)
	(via
		(at 125.476 -22.6568)
		(size 0.508)
		(drill 0.254)
		(layers "F.Cu" "B.Cu")
		(net "USB_RESET_N")
	)
	(segment
		(start 113.1443 -23.5458)
		(end 107.061 -17.4625)
		(width 0.1016)
		(layer "B.Cu")
		(net "USB_RESET_N")
	)
	(segment
		(start 116.3066 -23.6728)
		(end 116.1796 -23.5458)
		(width 0.1016)
		(layer "B.Cu")
		(net "USB_RESET_N")
	)
	(segment
		(start 116.1796 -23.5458)
		(end 115.1128 -23.5458)
		(width 0.1016)
		(layer "B.Cu")
		(net "USB_RESET_N")
	)
	(segment
		(start 106.2355 -17.4625)
		(end 105.9942 -17.7038)
		(width 0.1016)
		(layer "B.Cu")
		(net "USB_RESET_N")
	)
	(segment
		(start 107.061 -17.4625)
		(end 106.2355 -17.4625)
		(width 0.1016)
		(layer "B.Cu")
		(net "USB_RESET_N")
	)
	(segment
		(start 115.1128 -23.5458)
		(end 113.1443 -23.5458)
		(width 0.1016)
		(layer "B.Cu")
		(net "USB_RESET_N")
	)
	(segment
		(start 123.897898 -23.244302)
		(end 122.624342 -24.517858)
		(width 0.127)
		(layer "In3.Cu")
		(net "USB_RESET_N")
	)
	(segment
		(start 122.624342 -24.517858)
		(end 117.151658 -24.517858)
		(width 0.127)
		(layer "In3.Cu")
		(net "USB_RESET_N")
	)
	(segment
		(start 124.405898 -23.244302)
		(end 123.897898 -23.244302)
		(width 0.127)
		(layer "In3.Cu")
		(net "USB_RESET_N")
	)
	(segment
		(start 124.9934 -22.6568)
		(end 124.405898 -23.244302)
		(width 0.127)
		(layer "In3.Cu")
		(net "USB_RESET_N")
	)
	(segment
		(start 125.476 -22.6568)
		(end 124.9934 -22.6568)
		(width 0.127)
		(layer "In3.Cu")
		(net "USB_RESET_N")
	)
	(segment
		(start 117.151658 -24.517858)
		(end 116.3066 -23.6728)
		(width 0.127)
		(layer "In3.Cu")
		(net "USB_RESET_N")
	)
	(segment
		(start 132.4864 -30.099)
		(end 132.4864 -31.512764)
		(width 0.1016)
		(layer "F.Cu")
		(net "USB_HUB_XTAL_OUT")
	)
	(segment
		(start 128.220724 -28.245054)
		(end 128.0922 -28.11653)
		(width 0.1016)
		(layer "F.Cu")
		(net "USB_HUB_XTAL_OUT")
	)
	(segment
		(start 128.0922 -28.11653)
		(end 127.11938 -28.11653)
		(width 0.1016)
		(layer "F.Cu")
		(net "USB_HUB_XTAL_OUT")
	)
	(segment
		(start 132.4864 -31.512764)
		(end 133.505448 -32.531812)
		(width 0.1016)
		(layer "F.Cu")
		(net "USB_HUB_XTAL_OUT")
	)
	(segment
		(start 132.7277 -29.8577)
		(end 132.4864 -30.099)
		(width 0.1016)
		(layer "F.Cu")
		(net "USB_HUB_XTAL_OUT")
	)
	(segment
		(start 132.7277 -29.5148)
		(end 131.457954 -28.245054)
		(width 0.1016)
		(layer "F.Cu")
		(net "USB_HUB_XTAL_OUT")
	)
	(segment
		(start 132.7277 -29.5148)
		(end 132.7277 -29.8577)
		(width 0.1016)
		(layer "F.Cu")
		(net "USB_HUB_XTAL_OUT")
	)
	(segment
		(start 131.457954 -28.245054)
		(end 128.220724 -28.245054)
		(width 0.1016)
		(layer "F.Cu")
		(net "USB_HUB_XTAL_OUT")
	)
	(segment
		(start 131.6863 -29.5148)
		(end 131.6863 -30.49524)
		(width 0.1016)
		(layer "F.Cu")
		(net "USB_HUB_XTAL_IN")
	)
	(segment
		(start 127.11938 -28.616656)
		(end 131.156456 -28.616656)
		(width 0.1016)
		(layer "F.Cu")
		(net "USB_HUB_XTAL_IN")
	)
	(segment
		(start 131.156456 -28.616656)
		(end 131.6863 -29.1465)
		(width 0.1016)
		(layer "F.Cu")
		(net "USB_HUB_XTAL_IN")
	)
	(segment
		(start 131.6863 -29.1465)
		(end 131.6863 -29.5148)
		(width 0.1016)
		(layer "F.Cu")
		(net "USB_HUB_XTAL_IN")
	)
	(segment
		(start 131.6863 -30.49524)
		(end 131.162552 -31.018988)
		(width 0.1016)
		(layer "F.Cu")
		(net "USB_HUB_XTAL_IN")
	)
	(segment
		(start 116.3955 -33.914842)
		(end 116.3955 -33.692084)
		(width 0.1143)
		(layer "F.Cu")
		(net "USB_HUB_PCIE_DP1")
	)
	(segment
		(start 124.774706 -30.96133)
		(end 124.774706 -31.78302)
		(width 0.1143)
		(layer "F.Cu")
		(net "USB_HUB_PCIE_DP1")
	)
	(segment
		(start 124.878592 -32.51835)
		(end 123.322842 -34.0741)
		(width 0.1143)
		(layer "F.Cu")
		(net "USB_HUB_PCIE_DP1")
	)
	(segment
		(start 123.322842 -34.0741)
		(end 116.554758 -34.0741)
		(width 0.1143)
		(layer "F.Cu")
		(net "USB_HUB_PCIE_DP1")
	)
	(segment
		(start 124.878592 -31.886906)
		(end 124.878592 -32.51835)
		(width 0.1143)
		(layer "F.Cu")
		(net "USB_HUB_PCIE_DP1")
	)
	(segment
		(start 124.774706 -31.78302)
		(end 124.878592 -31.886906)
		(width 0.1143)
		(layer "F.Cu")
		(net "USB_HUB_PCIE_DP1")
	)
	(segment
		(start 116.554758 -34.0741)
		(end 116.3955 -33.914842)
		(width 0.1143)
		(layer "F.Cu")
		(net "USB_HUB_PCIE_DP1")
	)
	(segment
		(start 116.3955 -33.692084)
		(end 116.661692 -33.425892)
		(width 0.1143)
		(layer "F.Cu")
		(net "USB_HUB_PCIE_DP1")
	)
	(via
		(at 116.661692 -33.425892)
		(size 0.508)
		(drill 0.254)
		(layers "F.Cu" "B.Cu")
		(net "USB_HUB_PCIE_DP1")
	)
	(segment
		(start 115.087654 -32.410654)
		(end 113.3475 -30.6705)
		(width 0.1143)
		(layer "B.Cu")
		(net "USB_HUB_PCIE_DP1")
	)
	(segment
		(start 116.3447 -32.766)
		(end 115.989354 -32.410654)
		(width 0.1143)
		(layer "B.Cu")
		(net "USB_HUB_PCIE_DP1")
	)
	(segment
		(start 64.412114 -33.149286)
		(end 64.412368 -33.14954)
		(width 0.1143)
		(layer "B.Cu")
		(net "USB_HUB_PCIE_DP1")
	)
	(segment
		(start 64.463422 -33.302702)
		(end 64.079882 -34.070036)
		(width 0.1143)
		(layer "B.Cu")
		(net "USB_HUB_PCIE_DP1")
	)
	(segment
		(start 116.3447 -33.1089)
		(end 116.3447 -32.766)
		(width 0.1143)
		(layer "B.Cu")
		(net "USB_HUB_PCIE_DP1")
	)
	(segment
		(start 64.309752 -33.098232)
		(end 64.412114 -33.149286)
		(width 0.1143)
		(layer "B.Cu")
		(net "USB_HUB_PCIE_DP1")
	)
	(segment
		(start 64.748156 -30.6705)
		(end 64.132714 -31.285942)
		(width 0.1143)
		(layer "B.Cu")
		(net "USB_HUB_PCIE_DP1")
	)
	(segment
		(start 115.989354 -32.410654)
		(end 115.087654 -32.410654)
		(width 0.1143)
		(layer "B.Cu")
		(net "USB_HUB_PCIE_DP1")
	)
	(segment
		(start 113.3475 -30.6705)
		(end 64.748156 -30.6705)
		(width 0.1143)
		(layer "B.Cu")
		(net "USB_HUB_PCIE_DP1")
	)
	(segment
		(start 116.661692 -33.425892)
		(end 116.3447 -33.1089)
		(width 0.1143)
		(layer "B.Cu")
		(net "USB_HUB_PCIE_DP1")
	)
	(arc
		(start 64.132714 -31.285942)
		(mid 63.949633 -31.788539)
		(end 63.86322 -32.31642)
		(width 0.1143)
		(layer "B.Cu")
		(net "USB_HUB_PCIE_DP1")
	)
	(arc
		(start 63.86322 -32.31642)
		(mid 63.968173 -32.774891)
		(end 64.309752 -33.098232)
		(width 0.1143)
		(layer "B.Cu")
		(net "USB_HUB_PCIE_DP1")
	)
	(arc
		(start 64.412368 -33.14954)
		(mid 64.469488 -33.215565)
		(end 64.463422 -33.302702)
		(width 0.1143)
		(layer "B.Cu")
		(net "USB_HUB_PCIE_DP1")
	)
	(segment
		(start 125.8951 -33.610042)
		(end 125.8951 -31.75)
		(width 0.1143)
		(layer "F.Cu")
		(net "USB_HUB_PCIE_DP0")
	)
	(segment
		(start 125.8951 -31.75)
		(end 125.774704 -31.629604)
		(width 0.1143)
		(layer "F.Cu")
		(net "USB_HUB_PCIE_DP0")
	)
	(segment
		(start 125.639576 -33.865566)
		(end 125.8951 -33.610042)
		(width 0.1143)
		(layer "F.Cu")
		(net "USB_HUB_PCIE_DP0")
	)
	(segment
		(start 125.774704 -31.629604)
		(end 125.774704 -30.96133)
		(width 0.1143)
		(layer "F.Cu")
		(net "USB_HUB_PCIE_DP0")
	)
	(via
		(at 125.639576 -33.865566)
		(size 0.508)
		(drill 0.254)
		(layers "F.Cu" "B.Cu")
		(net "USB_HUB_PCIE_DP0")
	)
	(segment
		(start 125.916944 -33.391602)
		(end 125.732794 -33.207452)
		(width 0.1143)
		(layer "B.Cu")
		(net "USB_HUB_PCIE_DP0")
	)
	(segment
		(start 64.616838 -12.931902)
		(end 64.463422 -12.982702)
		(width 0.1143)
		(layer "B.Cu")
		(net "USB_HUB_PCIE_DP0")
	)
	(segment
		(start 124.032772 -33.207452)
		(end 123.857512 -33.382712)
		(width 0.1143)
		(layer "B.Cu")
		(net "USB_HUB_PCIE_DP0")
	)
	(segment
		(start 125.732794 -33.207452)
		(end 125.069092 -33.207452)
		(width 0.1143)
		(layer "B.Cu")
		(net "USB_HUB_PCIE_DP0")
	)
	(segment
		(start 124.893832 -33.382712)
		(end 124.550932 -33.382712)
		(width 0.1143)
		(layer "B.Cu")
		(net "USB_HUB_PCIE_DP0")
	)
	(segment
		(start 64.463422 -12.982702)
		(end 64.079882 -13.750036)
		(width 0.1143)
		(layer "B.Cu")
		(net "USB_HUB_PCIE_DP0")
	)
	(segment
		(start 121.516394 -33.207452)
		(end 114.559842 -26.2509)
		(width 0.1143)
		(layer "B.Cu")
		(net "USB_HUB_PCIE_DP0")
	)
	(segment
		(start 64.9351 -13.219938)
		(end 64.677036 -12.961874)
		(width 0.1143)
		(layer "B.Cu")
		(net "USB_HUB_PCIE_DP0")
	)
	(segment
		(start 64.9351 -14.751558)
		(end 64.9351 -13.219938)
		(width 0.1143)
		(layer "B.Cu")
		(net "USB_HUB_PCIE_DP0")
	)
	(segment
		(start 65.196212 -15.01267)
		(end 64.9351 -14.751558)
		(width 0.1143)
		(layer "B.Cu")
		(net "USB_HUB_PCIE_DP0")
	)
	(segment
		(start 108.540042 -26.2509)
		(end 97.491042 -15.2019)
		(width 0.1143)
		(layer "B.Cu")
		(net "USB_HUB_PCIE_DP0")
	)
	(segment
		(start 79.816452 -15.01267)
		(end 65.196212 -15.01267)
		(width 0.1143)
		(layer "B.Cu")
		(net "USB_HUB_PCIE_DP0")
	)
	(segment
		(start 125.916944 -33.588198)
		(end 125.916944 -33.391602)
		(width 0.1143)
		(layer "B.Cu")
		(net "USB_HUB_PCIE_DP0")
	)
	(segment
		(start 114.559842 -26.2509)
		(end 108.540042 -26.2509)
		(width 0.1143)
		(layer "B.Cu")
		(net "USB_HUB_PCIE_DP0")
	)
	(segment
		(start 123.857512 -33.382712)
		(end 123.514612 -33.382712)
		(width 0.1143)
		(layer "B.Cu")
		(net "USB_HUB_PCIE_DP0")
	)
	(segment
		(start 125.069092 -33.207452)
		(end 124.893832 -33.382712)
		(width 0.1143)
		(layer "B.Cu")
		(net "USB_HUB_PCIE_DP0")
	)
	(segment
		(start 97.491042 -15.2019)
		(end 80.005682 -15.2019)
		(width 0.1143)
		(layer "B.Cu")
		(net "USB_HUB_PCIE_DP0")
	)
	(segment
		(start 123.339352 -33.207452)
		(end 121.516394 -33.207452)
		(width 0.1143)
		(layer "B.Cu")
		(net "USB_HUB_PCIE_DP0")
	)
	(segment
		(start 123.514612 -33.382712)
		(end 123.339352 -33.207452)
		(width 0.1143)
		(layer "B.Cu")
		(net "USB_HUB_PCIE_DP0")
	)
	(segment
		(start 125.639576 -33.865566)
		(end 125.916944 -33.588198)
		(width 0.1143)
		(layer "B.Cu")
		(net "USB_HUB_PCIE_DP0")
	)
	(segment
		(start 124.375672 -33.207452)
		(end 124.032772 -33.207452)
		(width 0.1143)
		(layer "B.Cu")
		(net "USB_HUB_PCIE_DP0")
	)
	(segment
		(start 80.005682 -15.2019)
		(end 79.816452 -15.01267)
		(width 0.1143)
		(layer "B.Cu")
		(net "USB_HUB_PCIE_DP0")
	)
	(segment
		(start 124.550932 -33.382712)
		(end 124.375672 -33.207452)
		(width 0.1143)
		(layer "B.Cu")
		(net "USB_HUB_PCIE_DP0")
	)
	(segment
		(start 64.677036 -12.961874)
		(end 64.616838 -12.931902)
		(width 0.1143)
		(layer "B.Cu")
		(net "USB_HUB_PCIE_DP0")
	)
	(segment
		(start 116.1034 -33.7185)
		(end 115.831874 -33.446974)
		(width 0.1143)
		(layer "F.Cu")
		(net "USB_HUB_PCIE_DN1")
	)
	(segment
		(start 115.831874 -33.446974)
		(end 115.798346 -33.446974)
		(width 0.1143)
		(layer "F.Cu")
		(net "USB_HUB_PCIE_DN1")
	)
	(segment
		(start 125.170692 -31.886906)
		(end 125.170692 -32.639508)
		(width 0.1143)
		(layer "F.Cu")
		(net "USB_HUB_PCIE_DN1")
	)
	(segment
		(start 123.444 -34.3662)
		(end 116.4336 -34.3662)
		(width 0.1143)
		(layer "F.Cu")
		(net "USB_HUB_PCIE_DN1")
	)
	(segment
		(start 116.1034 -34.036)
		(end 116.1034 -33.7185)
		(width 0.1143)
		(layer "F.Cu")
		(net "USB_HUB_PCIE_DN1")
	)
	(segment
		(start 125.274578 -30.96133)
		(end 125.274578 -31.78302)
		(width 0.1143)
		(layer "F.Cu")
		(net "USB_HUB_PCIE_DN1")
	)
	(segment
		(start 125.170692 -32.639508)
		(end 123.444 -34.3662)
		(width 0.1143)
		(layer "F.Cu")
		(net "USB_HUB_PCIE_DN1")
	)
	(segment
		(start 116.4336 -34.3662)
		(end 116.1034 -34.036)
		(width 0.1143)
		(layer "F.Cu")
		(net "USB_HUB_PCIE_DN1")
	)
	(segment
		(start 125.274578 -31.78302)
		(end 125.170692 -31.886906)
		(width 0.1143)
		(layer "F.Cu")
		(net "USB_HUB_PCIE_DN1")
	)
	(via
		(at 115.798346 -33.446974)
		(size 0.508)
		(drill 0.254)
		(layers "F.Cu" "B.Cu")
		(net "USB_HUB_PCIE_DN1")
	)
	(segment
		(start 65.905634 -30.9626)
		(end 65.730374 -31.13786)
		(width 0.1143)
		(layer "B.Cu")
		(net "USB_HUB_PCIE_DN1")
	)
	(segment
		(start 65.730374 -31.13786)
		(end 65.387474 -31.13786)
		(width 0.1143)
		(layer "B.Cu")
		(net "USB_HUB_PCIE_DN1")
	)
	(segment
		(start 115.798346 -33.446974)
		(end 116.0526 -33.19272)
		(width 0.1143)
		(layer "B.Cu")
		(net "USB_HUB_PCIE_DN1")
	)
	(segment
		(start 64.695832 -32.836612)
		(end 65.079372 -32.069786)
		(width 0.1143)
		(layer "B.Cu")
		(net "USB_HUB_PCIE_DN1")
	)
	(segment
		(start 66.766694 -31.13786)
		(end 66.423794 -31.13786)
		(width 0.1143)
		(layer "B.Cu")
		(net "USB_HUB_PCIE_DN1")
	)
	(segment
		(start 66.423794 -31.13786)
		(end 66.248534 -30.9626)
		(width 0.1143)
		(layer "B.Cu")
		(net "USB_HUB_PCIE_DN1")
	)
	(segment
		(start 65.212214 -30.9626)
		(end 64.869314 -30.9626)
		(width 0.1143)
		(layer "B.Cu")
		(net "USB_HUB_PCIE_DN1")
	)
	(segment
		(start 66.941954 -30.9626)
		(end 66.766694 -31.13786)
		(width 0.1143)
		(layer "B.Cu")
		(net "USB_HUB_PCIE_DN1")
	)
	(segment
		(start 114.966496 -32.702754)
		(end 113.226342 -30.9626)
		(width 0.1143)
		(layer "B.Cu")
		(net "USB_HUB_PCIE_DN1")
	)
	(segment
		(start 116.0526 -32.887158)
		(end 115.868196 -32.702754)
		(width 0.1143)
		(layer "B.Cu")
		(net "USB_HUB_PCIE_DN1")
	)
	(segment
		(start 116.0526 -33.19272)
		(end 116.0526 -32.887158)
		(width 0.1143)
		(layer "B.Cu")
		(net "USB_HUB_PCIE_DN1")
	)
	(segment
		(start 115.868196 -32.702754)
		(end 114.966496 -32.702754)
		(width 0.1143)
		(layer "B.Cu")
		(net "USB_HUB_PCIE_DN1")
	)
	(segment
		(start 113.226342 -30.9626)
		(end 66.941954 -30.9626)
		(width 0.1143)
		(layer "B.Cu")
		(net "USB_HUB_PCIE_DN1")
	)
	(segment
		(start 66.248534 -30.9626)
		(end 65.905634 -30.9626)
		(width 0.1143)
		(layer "B.Cu")
		(net "USB_HUB_PCIE_DN1")
	)
	(segment
		(start 64.154812 -32.336232)
		(end 64.154812 -32.336486)
		(width 0.1143)
		(layer "B.Cu")
		(net "USB_HUB_PCIE_DN1")
	)
	(segment
		(start 64.440308 -32.836866)
		(end 64.542416 -32.887666)
		(width 0.1143)
		(layer "B.Cu")
		(net "USB_HUB_PCIE_DN1")
	)
	(segment
		(start 64.869314 -30.9626)
		(end 64.376046 -31.455868)
		(width 0.1143)
		(layer "B.Cu")
		(net "USB_HUB_PCIE_DN1")
	)
	(segment
		(start 65.387474 -31.13786)
		(end 65.212214 -30.9626)
		(width 0.1143)
		(layer "B.Cu")
		(net "USB_HUB_PCIE_DN1")
	)
	(arc
		(start 64.154812 -32.336486)
		(mid 64.221888 -32.629845)
		(end 64.440308 -32.836866)
		(width 0.1143)
		(layer "B.Cu")
		(net "USB_HUB_PCIE_DN1")
	)
	(arc
		(start 64.376046 -31.455868)
		(mid 64.22626 -31.886207)
		(end 64.154812 -32.336232)
		(width 0.1143)
		(layer "B.Cu")
		(net "USB_HUB_PCIE_DN1")
	)
	(arc
		(start 64.542416 -32.887666)
		(mid 64.629753 -32.894004)
		(end 64.695832 -32.836612)
		(width 0.1143)
		(layer "B.Cu")
		(net "USB_HUB_PCIE_DN1")
	)
	(segment
		(start 126.511304 -33.865566)
		(end 126.1872 -33.541462)
		(width 0.1143)
		(layer "F.Cu")
		(net "USB_HUB_PCIE_DN0")
	)
	(segment
		(start 126.1872 -31.811976)
		(end 126.274576 -31.7246)
		(width 0.1143)
		(layer "F.Cu")
		(net "USB_HUB_PCIE_DN0")
	)
	(segment
		(start 126.1872 -33.541462)
		(end 126.1872 -31.811976)
		(width 0.1143)
		(layer "F.Cu")
		(net "USB_HUB_PCIE_DN0")
	)
	(segment
		(start 126.274576 -31.7246)
		(end 126.274576 -31.03753)
		(width 0.1143)
		(layer "F.Cu")
		(net "USB_HUB_PCIE_DN0")
	)
	(via
		(at 126.511304 -33.865566)
		(size 0.508)
		(drill 0.254)
		(layers "F.Cu" "B.Cu")
		(net "USB_HUB_PCIE_DN0")
	)
	(segment
		(start 121.637552 -32.915352)
		(end 114.681 -25.9588)
		(width 0.1143)
		(layer "B.Cu")
		(net "USB_HUB_PCIE_DN0")
	)
	(segment
		(start 126.238 -33.59277)
		(end 126.238 -33.2994)
		(width 0.1143)
		(layer "B.Cu")
		(net "USB_HUB_PCIE_DN0")
	)
	(segment
		(start 64.85001 -12.72159)
		(end 64.74714 -12.670282)
		(width 0.1143)
		(layer "B.Cu")
		(net "USB_HUB_PCIE_DN0")
	)
	(segment
		(start 80.12684 -14.9098)
		(end 79.93761 -14.72057)
		(width 0.1143)
		(layer "B.Cu")
		(net "USB_HUB_PCIE_DN0")
	)
	(segment
		(start 64.74714 -12.670282)
		(end 64.695832 -12.516866)
		(width 0.1143)
		(layer "B.Cu")
		(net "USB_HUB_PCIE_DN0")
	)
	(segment
		(start 97.6122 -14.9098)
		(end 80.12684 -14.9098)
		(width 0.1143)
		(layer "B.Cu")
		(net "USB_HUB_PCIE_DN0")
	)
	(segment
		(start 65.31737 -14.72057)
		(end 65.2272 -14.6304)
		(width 0.1143)
		(layer "B.Cu")
		(net "USB_HUB_PCIE_DN0")
	)
	(segment
		(start 126.511304 -33.865566)
		(end 126.510796 -33.865566)
		(width 0.1143)
		(layer "B.Cu")
		(net "USB_HUB_PCIE_DN0")
	)
	(segment
		(start 79.93761 -14.72057)
		(end 65.31737 -14.72057)
		(width 0.1143)
		(layer "B.Cu")
		(net "USB_HUB_PCIE_DN0")
	)
	(segment
		(start 114.681 -25.9588)
		(end 108.6612 -25.9588)
		(width 0.1143)
		(layer "B.Cu")
		(net "USB_HUB_PCIE_DN0")
	)
	(segment
		(start 108.6612 -25.9588)
		(end 97.6122 -14.9098)
		(width 0.1143)
		(layer "B.Cu")
		(net "USB_HUB_PCIE_DN0")
	)
	(segment
		(start 65.2272 -14.6304)
		(end 65.2272 -13.09878)
		(width 0.1143)
		(layer "B.Cu")
		(net "USB_HUB_PCIE_DN0")
	)
	(segment
		(start 64.695832 -12.516866)
		(end 65.079372 -11.749786)
		(width 0.1143)
		(layer "B.Cu")
		(net "USB_HUB_PCIE_DN0")
	)
	(segment
		(start 125.853952 -32.915352)
		(end 121.637552 -32.915352)
		(width 0.1143)
		(layer "B.Cu")
		(net "USB_HUB_PCIE_DN0")
	)
	(segment
		(start 126.238 -33.2994)
		(end 125.853952 -32.915352)
		(width 0.1143)
		(layer "B.Cu")
		(net "USB_HUB_PCIE_DN0")
	)
	(segment
		(start 65.2272 -13.09878)
		(end 64.85001 -12.72159)
		(width 0.1143)
		(layer "B.Cu")
		(net "USB_HUB_PCIE_DN0")
	)
	(segment
		(start 126.510796 -33.865566)
		(end 126.238 -33.59277)
		(width 0.1143)
		(layer "B.Cu")
		(net "USB_HUB_PCIE_DN0")
	)
	(segment
		(start 123.378468 -31.886906)
		(end 123.274582 -31.78302)
		(width 0.1143)
		(layer "F.Cu")
		(net "USB_DP2")
	)
	(segment
		(start 119.2403 -32.3596)
		(end 119.3419 -32.3596)
		(width 0.1143)
		(layer "F.Cu")
		(net "USB_DP2")
	)
	(segment
		(start 120.085358 -32.69615)
		(end 120.548908 -33.1597)
		(width 0.1143)
		(layer "F.Cu")
		(net "USB_DP2")
	)
	(segment
		(start 119.3419 -32.3596)
		(end 119.67845 -32.69615)
		(width 0.1143)
		(layer "F.Cu")
		(net "USB_DP2")
	)
	(segment
		(start 122.219974 -33.1597)
		(end 123.378468 -32.001206)
		(width 0.1143)
		(layer "F.Cu")
		(net "USB_DP2")
	)
	(segment
		(start 120.548908 -33.1597)
		(end 122.219974 -33.1597)
		(width 0.1143)
		(layer "F.Cu")
		(net "USB_DP2")
	)
	(segment
		(start 123.274582 -31.78302)
		(end 123.274582 -30.96133)
		(width 0.1143)
		(layer "F.Cu")
		(net "USB_DP2")
	)
	(segment
		(start 123.378468 -32.001206)
		(end 123.378468 -31.886906)
		(width 0.1143)
		(layer "F.Cu")
		(net "USB_DP2")
	)
	(segment
		(start 119.67845 -32.69615)
		(end 120.085358 -32.69615)
		(width 0.1143)
		(layer "F.Cu")
		(net "USB_DP2")
	)
	(segment
		(start 122.341132 -33.4518)
		(end 123.670568 -32.122364)
		(width 0.1143)
		(layer "F.Cu")
		(net "USB_DN2")
	)
	(segment
		(start 119.67845 -32.98825)
		(end 119.9642 -32.98825)
		(width 0.1143)
		(layer "F.Cu")
		(net "USB_DN2")
	)
	(segment
		(start 123.774454 -31.78302)
		(end 123.774454 -30.96133)
		(width 0.1143)
		(layer "F.Cu")
		(net "USB_DN2")
	)
	(segment
		(start 119.9642 -32.98825)
		(end 120.42775 -33.4518)
		(width 0.1143)
		(layer "F.Cu")
		(net "USB_DN2")
	)
	(segment
		(start 123.670568 -31.886906)
		(end 123.774454 -31.78302)
		(width 0.1143)
		(layer "F.Cu")
		(net "USB_DN2")
	)
	(segment
		(start 120.42775 -33.4518)
		(end 122.341132 -33.4518)
		(width 0.1143)
		(layer "F.Cu")
		(net "USB_DN2")
	)
	(segment
		(start 119.2403 -33.4264)
		(end 119.67845 -32.98825)
		(width 0.1143)
		(layer "F.Cu")
		(net "USB_DN2")
	)
	(segment
		(start 123.670568 -32.122364)
		(end 123.670568 -31.886906)
		(width 0.1143)
		(layer "F.Cu")
		(net "USB_DN2")
	)
	(segment
		(start 24.5872 -28.3083)
		(end 24.029162 -27.750262)
		(width 0.1016)
		(layer "F.Cu")
		(net "SMB_VMONITOR_SLOT3_MUX_SDA")
	)
	(segment
		(start 24.5872 -28.321)
		(end 24.5872 -28.3083)
		(width 0.1016)
		(layer "F.Cu")
		(net "SMB_VMONITOR_SLOT3_MUX_SDA")
	)
	(segment
		(start 24.029162 -27.750262)
		(end 23.801324 -27.750262)
		(width 0.1016)
		(layer "F.Cu")
		(net "SMB_VMONITOR_SLOT3_MUX_SDA")
	)
	(via
		(at 24.5872 -28.321)
		(size 0.508)
		(drill 0.254)
		(layers "F.Cu" "B.Cu")
		(net "SMB_VMONITOR_SLOT3_MUX_SDA")
	)
	(via
		(at 25.4254 -18.882614)
		(size 0.508)
		(drill 0.254)
		(layers "F.Cu" "B.Cu")
		(net "SMB_VMONITOR_SLOT3_MUX_SDA")
	)
	(via
		(at 25.972516 -17.927574)
		(size 0.7112)
		(drill 0.3556)
		(layers "F.Cu" "B.Cu")
		(net "SMB_VMONITOR_SLOT3_MUX_SDA")
	)
	(segment
		(start 25.417018 -18.321782)
		(end 25.811226 -17.927574)
		(width 0.1016)
		(layer "B.Cu")
		(net "SMB_VMONITOR_SLOT3_MUX_SDA")
	)
	(segment
		(start 25.4254 -18.882614)
		(end 25.417018 -18.874232)
		(width 0.1016)
		(layer "B.Cu")
		(net "SMB_VMONITOR_SLOT3_MUX_SDA")
	)
	(segment
		(start 25.972516 -17.927574)
		(end 25.977342 -17.9324)
		(width 0.1016)
		(layer "B.Cu")
		(net "SMB_VMONITOR_SLOT3_MUX_SDA")
	)
	(segment
		(start 25.977342 -17.9324)
		(end 26.3906 -17.9324)
		(width 0.1016)
		(layer "B.Cu")
		(net "SMB_VMONITOR_SLOT3_MUX_SDA")
	)
	(segment
		(start 25.811226 -17.927574)
		(end 25.972516 -17.927574)
		(width 0.1016)
		(layer "B.Cu")
		(net "SMB_VMONITOR_SLOT3_MUX_SDA")
	)
	(segment
		(start 25.417018 -18.874232)
		(end 25.417018 -18.321782)
		(width 0.1016)
		(layer "B.Cu")
		(net "SMB_VMONITOR_SLOT3_MUX_SDA")
	)
	(segment
		(start 26.6446 -18.1864)
		(end 26.6446 -18.9611)
		(width 0.1016)
		(layer "B.Cu")
		(net "SMB_VMONITOR_SLOT3_MUX_SDA")
	)
	(segment
		(start 26.3906 -17.9324)
		(end 26.6446 -18.1864)
		(width 0.1016)
		(layer "B.Cu")
		(net "SMB_VMONITOR_SLOT3_MUX_SDA")
	)
	(segment
		(start 24.003 -20.6248)
		(end 24.003 -27.686)
		(width 0.127)
		(layer "In2.Cu")
		(net "SMB_VMONITOR_SLOT3_MUX_SDA")
	)
	(segment
		(start 25.4 -19.2278)
		(end 24.003 -20.6248)
		(width 0.127)
		(layer "In2.Cu")
		(net "SMB_VMONITOR_SLOT3_MUX_SDA")
	)
	(segment
		(start 24.5872 -28.2702)
		(end 24.5872 -28.321)
		(width 0.127)
		(layer "In2.Cu")
		(net "SMB_VMONITOR_SLOT3_MUX_SDA")
	)
	(segment
		(start 24.003 -27.686)
		(end 24.5872 -28.2702)
		(width 0.127)
		(layer "In2.Cu")
		(net "SMB_VMONITOR_SLOT3_MUX_SDA")
	)
	(segment
		(start 25.4 -18.908014)
		(end 25.4 -19.2278)
		(width 0.127)
		(layer "In2.Cu")
		(net "SMB_VMONITOR_SLOT3_MUX_SDA")
	)
	(segment
		(start 25.4254 -18.882614)
		(end 25.4 -18.908014)
		(width 0.127)
		(layer "In2.Cu")
		(net "SMB_VMONITOR_SLOT3_MUX_SDA")
	)
	(segment
		(start 23.000462 -28.551124)
		(end 23.471124 -28.551124)
		(width 0.1016)
		(layer "F.Cu")
		(net "SMB_VMONITOR_SLOT3_MUX_SCL")
	)
	(segment
		(start 23.471124 -28.551124)
		(end 23.6982 -28.7782)
		(width 0.1016)
		(layer "F.Cu")
		(net "SMB_VMONITOR_SLOT3_MUX_SCL")
	)
	(via
		(at 24.0538 -18.3896)
		(size 0.508)
		(drill 0.254)
		(layers "F.Cu" "B.Cu")
		(net "SMB_VMONITOR_SLOT3_MUX_SCL")
	)
	(via
		(at 23.6982 -28.7782)
		(size 0.508)
		(drill 0.254)
		(layers "F.Cu" "B.Cu")
		(net "SMB_VMONITOR_SLOT3_MUX_SCL")
	)
	(via
		(at 24.2697 -17.4244)
		(size 0.7112)
		(drill 0.3556)
		(layers "F.Cu" "B.Cu")
		(net "SMB_VMONITOR_SLOT3_MUX_SCL")
	)
	(segment
		(start 23.1394 -17.6149)
		(end 23.3807 -17.3736)
		(width 0.1016)
		(layer "B.Cu")
		(net "SMB_VMONITOR_SLOT3_MUX_SCL")
	)
	(segment
		(start 24.2697 -17.4244)
		(end 24.2697 -18.1737)
		(width 0.1016)
		(layer "B.Cu")
		(net "SMB_VMONITOR_SLOT3_MUX_SCL")
	)
	(segment
		(start 24.2697 -18.1737)
		(end 24.0538 -18.3896)
		(width 0.1016)
		(layer "B.Cu")
		(net "SMB_VMONITOR_SLOT3_MUX_SCL")
	)
	(segment
		(start 24.2189 -17.3736)
		(end 24.2697 -17.4244)
		(width 0.1016)
		(layer "B.Cu")
		(net "SMB_VMONITOR_SLOT3_MUX_SCL")
	)
	(segment
		(start 23.3807 -17.3736)
		(end 24.2189 -17.3736)
		(width 0.1016)
		(layer "B.Cu")
		(net "SMB_VMONITOR_SLOT3_MUX_SCL")
	)
	(segment
		(start 23.495 -18.9738)
		(end 24.0538 -18.415)
		(width 0.127)
		(layer "In2.Cu")
		(net "SMB_VMONITOR_SLOT3_MUX_SCL")
	)
	(segment
		(start 23.495 -28.575)
		(end 23.495 -18.9738)
		(width 0.127)
		(layer "In2.Cu")
		(net "SMB_VMONITOR_SLOT3_MUX_SCL")
	)
	(segment
		(start 23.6982 -28.7782)
		(end 23.495 -28.575)
		(width 0.127)
		(layer "In2.Cu")
		(net "SMB_VMONITOR_SLOT3_MUX_SCL")
	)
	(segment
		(start 24.0538 -18.415)
		(end 24.0538 -18.3896)
		(width 0.127)
		(layer "In2.Cu")
		(net "SMB_VMONITOR_SLOT3_MUX_SCL")
	)
	(segment
		(start 24.712676 -17.727676)
		(end 24.9682 -17.9832)
		(width 0.1016)
		(layer "F.Cu")
		(net "SMB_VMONITOR_SLOT2_MUX_SDA")
	)
	(segment
		(start 22.314662 -17.727676)
		(end 24.712676 -17.727676)
		(width 0.1016)
		(layer "F.Cu")
		(net "SMB_VMONITOR_SLOT2_MUX_SDA")
	)
	(segment
		(start 25.9588 -17.9578)
		(end 26.2128 -18.2118)
		(width 0.1016)
		(layer "F.Cu")
		(net "SMB_VMONITOR_SLOT2_MUX_SDA")
	)
	(segment
		(start 24.9682 -17.9832)
		(end 24.9936 -17.9578)
		(width 0.1016)
		(layer "F.Cu")
		(net "SMB_VMONITOR_SLOT2_MUX_SDA")
	)
	(segment
		(start 24.9936 -17.9578)
		(end 25.9588 -17.9578)
		(width 0.1016)
		(layer "F.Cu")
		(net "SMB_VMONITOR_SLOT2_MUX_SDA")
	)
	(via
		(at 24.9682 -17.9832)
		(size 0.7112)
		(drill 0.3556)
		(layers "F.Cu" "B.Cu")
		(net "SMB_VMONITOR_SLOT2_MUX_SDA")
	)
	(segment
		(start 23.9014 -19.1008)
		(end 23.9014 -18.8976)
		(width 0.1016)
		(layer "F.Cu")
		(net "SMB_VMONITOR_SLOT2_MUX_SCL")
	)
	(segment
		(start 23.9014 -18.8976)
		(end 23.532338 -18.528538)
		(width 0.1016)
		(layer "F.Cu")
		(net "SMB_VMONITOR_SLOT2_MUX_SCL")
	)
	(segment
		(start 23.532338 -18.528538)
		(end 23.115524 -18.528538)
		(width 0.1016)
		(layer "F.Cu")
		(net "SMB_VMONITOR_SLOT2_MUX_SCL")
	)
	(segment
		(start 24.716232 -19.949922)
		(end 24.716232 -19.915632)
		(width 0.1016)
		(layer "F.Cu")
		(net "SMB_VMONITOR_SLOT2_MUX_SCL")
	)
	(segment
		(start 24.8285 -20.066)
		(end 24.716232 -19.953732)
		(width 0.1016)
		(layer "F.Cu")
		(net "SMB_VMONITOR_SLOT2_MUX_SCL")
	)
	(segment
		(start 24.716232 -19.915632)
		(end 23.9014 -19.1008)
		(width 0.1016)
		(layer "F.Cu")
		(net "SMB_VMONITOR_SLOT2_MUX_SCL")
	)
	(segment
		(start 24.716232 -19.953732)
		(end 24.716232 -19.949922)
		(width 0.1016)
		(layer "F.Cu")
		(net "SMB_VMONITOR_SLOT2_MUX_SCL")
	)
	(segment
		(start 24.8285 -20.9296)
		(end 24.8285 -20.066)
		(width 0.1016)
		(layer "F.Cu")
		(net "SMB_VMONITOR_SLOT2_MUX_SCL")
	)
	(via
		(at 24.716232 -19.949922)
		(size 0.7112)
		(drill 0.3556)
		(layers "F.Cu" "B.Cu")
		(net "SMB_VMONITOR_SLOT2_MUX_SCL")
	)
	(segment
		(start 44.079922 -27.570176)
		(end 45.411898 -26.2382)
		(width 0.1016)
		(layer "F.Cu")
		(net "SMB_ALERT_S3_B12_N")
	)
	(segment
		(start 54.9529 -21.4376)
		(end 53.7464 -22.6441)
		(width 0.1016)
		(layer "F.Cu")
		(net "SMB_ALERT_S3_B12_N")
	)
	(segment
		(start 53.0098 -25.4762)
		(end 53.7464 -24.7396)
		(width 0.1016)
		(layer "F.Cu")
		(net "SMB_ALERT_S3_B12_N")
	)
	(segment
		(start 49.657 -26.2382)
		(end 50.419 -25.4762)
		(width 0.1016)
		(layer "F.Cu")
		(net "SMB_ALERT_S3_B12_N")
	)
	(segment
		(start 50.419 -25.4762)
		(end 53.0098 -25.4762)
		(width 0.1016)
		(layer "F.Cu")
		(net "SMB_ALERT_S3_B12_N")
	)
	(segment
		(start 53.7464 -24.7396)
		(end 53.7464 -22.6441)
		(width 0.1016)
		(layer "F.Cu")
		(net "SMB_ALERT_S3_B12_N")
	)
	(segment
		(start 55.1942 -21.4376)
		(end 54.9529 -21.4376)
		(width 0.1016)
		(layer "F.Cu")
		(net "SMB_ALERT_S3_B12_N")
	)
	(segment
		(start 45.411898 -26.2382)
		(end 49.657 -26.2382)
		(width 0.1016)
		(layer "F.Cu")
		(net "SMB_ALERT_S3_B12_N")
	)
	(via
		(at 55.1942 -21.4376)
		(size 0.7112)
		(drill 0.3556)
		(layers "F.Cu" "B.Cu")
		(net "SMB_ALERT_S3_B12_N")
	)
	(segment
		(start 45.6819 -8.5471)
		(end 45.6819 -8.7884)
		(width 0.1016)
		(layer "F.Cu")
		(net "SMB_ALERT_S2_B12_N")
	)
	(segment
		(start 47.0662 -13.1826)
		(end 47.0662 -14.1986)
		(width 0.1016)
		(layer "F.Cu")
		(net "SMB_ALERT_S2_B12_N")
	)
	(segment
		(start 44.384976 -7.250176)
		(end 45.6819 -8.5471)
		(width 0.1016)
		(layer "F.Cu")
		(net "SMB_ALERT_S2_B12_N")
	)
	(segment
		(start 47.9044 -11.3792)
		(end 47.9044 -12.3444)
		(width 0.1016)
		(layer "F.Cu")
		(net "SMB_ALERT_S2_B12_N")
	)
	(segment
		(start 45.6819 -8.7884)
		(end 45.9359 -9.0424)
		(width 0.1016)
		(layer "F.Cu")
		(net "SMB_ALERT_S2_B12_N")
	)
	(segment
		(start 47.9044 -12.3444)
		(end 47.0662 -13.1826)
		(width 0.1016)
		(layer "F.Cu")
		(net "SMB_ALERT_S2_B12_N")
	)
	(segment
		(start 47.7012 -14.8336)
		(end 50.3428 -14.8336)
		(width 0.1016)
		(layer "F.Cu")
		(net "SMB_ALERT_S2_B12_N")
	)
	(segment
		(start 45.9359 -9.4107)
		(end 47.9044 -11.3792)
		(width 0.1016)
		(layer "F.Cu")
		(net "SMB_ALERT_S2_B12_N")
	)
	(segment
		(start 44.079922 -7.250176)
		(end 44.384976 -7.250176)
		(width 0.1016)
		(layer "F.Cu")
		(net "SMB_ALERT_S2_B12_N")
	)
	(segment
		(start 47.0662 -14.1986)
		(end 47.7012 -14.8336)
		(width 0.1016)
		(layer "F.Cu")
		(net "SMB_ALERT_S2_B12_N")
	)
	(segment
		(start 52.7177 -15.5194)
		(end 53.0987 -15.9004)
		(width 0.1016)
		(layer "F.Cu")
		(net "SMB_ALERT_S2_B12_N")
	)
	(segment
		(start 50.3428 -14.8336)
		(end 51.0286 -15.5194)
		(width 0.1016)
		(layer "F.Cu")
		(net "SMB_ALERT_S2_B12_N")
	)
	(segment
		(start 51.0286 -15.5194)
		(end 52.7177 -15.5194)
		(width 0.1016)
		(layer "F.Cu")
		(net "SMB_ALERT_S2_B12_N")
	)
	(segment
		(start 45.9359 -9.0424)
		(end 45.9359 -9.4107)
		(width 0.1016)
		(layer "F.Cu")
		(net "SMB_ALERT_S2_B12_N")
	)
	(segment
		(start 25.4508 -23.9268)
		(end 25.2984 -24.0792)
		(width 0.1016)
		(layer "F.Cu")
		(net "SLOT3_VMONITOR_A1")
	)
	(segment
		(start 25.426162 -26.250138)
		(end 26.0731 -25.6032)
		(width 0.1016)
		(layer "F.Cu")
		(net "SLOT3_VMONITOR_A1")
	)
	(segment
		(start 26.2382 -24.1935)
		(end 25.9715 -23.9268)
		(width 0.1016)
		(layer "F.Cu")
		(net "SLOT3_VMONITOR_A1")
	)
	(segment
		(start 23.801324 -26.250138)
		(end 25.426162 -26.250138)
		(width 0.1016)
		(layer "F.Cu")
		(net "SLOT3_VMONITOR_A1")
	)
	(segment
		(start 26.0731 -25.3111)
		(end 25.2984 -24.5364)
		(width 0.1016)
		(layer "F.Cu")
		(net "SLOT3_VMONITOR_A1")
	)
	(segment
		(start 25.2984 -24.5364)
		(end 25.2984 -24.0792)
		(width 0.1016)
		(layer "F.Cu")
		(net "SLOT3_VMONITOR_A1")
	)
	(segment
		(start 25.9715 -23.9268)
		(end 25.4508 -23.9268)
		(width 0.1016)
		(layer "F.Cu")
		(net "SLOT3_VMONITOR_A1")
	)
	(segment
		(start 26.0731 -25.6032)
		(end 26.0731 -25.3111)
		(width 0.1016)
		(layer "F.Cu")
		(net "SLOT3_VMONITOR_A1")
	)
	(via
		(at 25.2984 -24.0792)
		(size 0.7112)
		(drill 0.3556)
		(layers "F.Cu" "B.Cu")
		(net "SLOT3_VMONITOR_A1")
	)
	(segment
		(start 25.01138 -26.6446)
		(end 24.4348 -26.6446)
		(width 0.1016)
		(layer "F.Cu")
		(net "SLOT3_VMONITOR_A0")
	)
	(segment
		(start 25.441148 -26.6446)
		(end 25.415748 -26.6192)
		(width 0.1016)
		(layer "F.Cu")
		(net "SLOT3_VMONITOR_A0")
	)
	(segment
		(start 25.4762 -28.4226)
		(end 25.527 -28.4226)
		(width 0.1016)
		(layer "F.Cu")
		(net "SLOT3_VMONITOR_A0")
	)
	(segment
		(start 26.0731 -26.6446)
		(end 25.441148 -26.6446)
		(width 0.1016)
		(layer "F.Cu")
		(net "SLOT3_VMONITOR_A0")
	)
	(segment
		(start 25.415748 -26.6192)
		(end 25.03678 -26.6192)
		(width 0.1016)
		(layer "F.Cu")
		(net "SLOT3_VMONITOR_A0")
	)
	(segment
		(start 24.329136 -26.750264)
		(end 23.801324 -26.750264)
		(width 0.1016)
		(layer "F.Cu")
		(net "SLOT3_VMONITOR_A0")
	)
	(segment
		(start 26.0731 -26.6446)
		(end 26.0731 -27.686)
		(width 0.1016)
		(layer "F.Cu")
		(net "SLOT3_VMONITOR_A0")
	)
	(segment
		(start 25.527 -28.4226)
		(end 26.0731 -27.8765)
		(width 0.1016)
		(layer "F.Cu")
		(net "SLOT3_VMONITOR_A0")
	)
	(segment
		(start 24.4348 -26.6446)
		(end 24.329136 -26.750264)
		(width 0.1016)
		(layer "F.Cu")
		(net "SLOT3_VMONITOR_A0")
	)
	(segment
		(start 25.03678 -26.6192)
		(end 25.01138 -26.6446)
		(width 0.1016)
		(layer "F.Cu")
		(net "SLOT3_VMONITOR_A0")
	)
	(segment
		(start 26.0731 -27.8765)
		(end 26.0731 -27.686)
		(width 0.1016)
		(layer "F.Cu")
		(net "SLOT3_VMONITOR_A0")
	)
	(via
		(at 25.4762 -28.4226)
		(size 0.508)
		(drill 0.254)
		(layers "F.Cu" "B.Cu")
		(net "SLOT3_VMONITOR_A0")
	)
	(via
		(at 25.8318 -27.4066)
		(size 0.7112)
		(drill 0.3556)
		(layers "F.Cu" "B.Cu")
		(net "SLOT3_VMONITOR_A0")
	)
	(segment
		(start 25.8318 -28.067)
		(end 25.4762 -28.4226)
		(width 0.1016)
		(layer "B.Cu")
		(net "SLOT3_VMONITOR_A0")
	)
	(segment
		(start 25.8318 -27.4066)
		(end 25.8318 -28.067)
		(width 0.1016)
		(layer "B.Cu")
		(net "SLOT3_VMONITOR_A0")
	)
	(segment
		(start 18.5928 -23.0251)
		(end 18.8849 -23.3172)
		(width 0.2032)
		(layer "F.Cu")
		(net "SLOT3_P12V_SENSE_VP_R")
	)
	(segment
		(start 19.7612 -23.4188)
		(end 19.5453 -23.6347)
		(width 0.2032)
		(layer "F.Cu")
		(net "SLOT3_P12V_SENSE_VP_R")
	)
	(segment
		(start 17.9959 -23.3172)
		(end 17.6403 -22.9616)
		(width 0.2032)
		(layer "F.Cu")
		(net "SLOT3_P12V_SENSE_VP_R")
	)
	(segment
		(start 20.1168 -24.2062)
		(end 20.1168 -24.638)
		(width 0.2032)
		(layer "F.Cu")
		(net "SLOT3_P12V_SENSE_VP_R")
	)
	(segment
		(start 19.5453 -23.6347)
		(end 20.1168 -24.2062)
		(width 0.2032)
		(layer "F.Cu")
		(net "SLOT3_P12V_SENSE_VP_R")
	)
	(segment
		(start 18.5928 -23.0251)
		(end 18.3007 -23.3172)
		(width 0.2032)
		(layer "F.Cu")
		(net "SLOT3_P12V_SENSE_VP_R")
	)
	(segment
		(start 18.8849 -23.3172)
		(end 19.2278 -23.3172)
		(width 0.2032)
		(layer "F.Cu")
		(net "SLOT3_P12V_SENSE_VP_R")
	)
	(segment
		(start 19.2278 -23.3172)
		(end 19.5453 -23.6347)
		(width 0.2032)
		(layer "F.Cu")
		(net "SLOT3_P12V_SENSE_VP_R")
	)
	(segment
		(start 18.3007 -23.3172)
		(end 17.9959 -23.3172)
		(width 0.2032)
		(layer "F.Cu")
		(net "SLOT3_P12V_SENSE_VP_R")
	)
	(segment
		(start 20.1168 -24.638)
		(end 20.928076 -25.449276)
		(width 0.2032)
		(layer "F.Cu")
		(net "SLOT3_P12V_SENSE_VP_R")
	)
	(segment
		(start 20.928076 -25.449276)
		(end 21.500338 -25.449276)
		(width 0.2032)
		(layer "F.Cu")
		(net "SLOT3_P12V_SENSE_VP_R")
	)
	(via
		(at 19.7612 -23.4188)
		(size 0.7112)
		(drill 0.3556)
		(layers "F.Cu" "B.Cu")
		(net "SLOT3_P12V_SENSE_VP_R")
	)
	(segment
		(start 18.3896 -23.7109)
		(end 17.9324 -23.7109)
		(width 0.2032)
		(layer "F.Cu")
		(net "SLOT3_P12V_SENSE_VN_R")
	)
	(segment
		(start 18.8595 -23.6474)
		(end 19.090894 -23.6474)
		(width 0.2032)
		(layer "F.Cu")
		(net "SLOT3_P12V_SENSE_VN_R")
	)
	(segment
		(start 18.5928 -23.9141)
		(end 18.8595 -23.6474)
		(width 0.2032)
		(layer "F.Cu")
		(net "SLOT3_P12V_SENSE_VN_R")
	)
	(segment
		(start 19.7866 -24.774906)
		(end 20.699476 -25.687782)
		(width 0.2032)
		(layer "F.Cu")
		(net "SLOT3_P12V_SENSE_VN_R")
	)
	(segment
		(start 19.7866 -24.343106)
		(end 19.7866 -24.774906)
		(width 0.2032)
		(layer "F.Cu")
		(net "SLOT3_P12V_SENSE_VN_R")
	)
	(segment
		(start 18.5928 -23.9141)
		(end 18.3896 -23.7109)
		(width 0.2032)
		(layer "F.Cu")
		(net "SLOT3_P12V_SENSE_VN_R")
	)
	(segment
		(start 20.699476 -25.687782)
		(end 20.699476 -26.250138)
		(width 0.2032)
		(layer "F.Cu")
		(net "SLOT3_P12V_SENSE_VN_R")
	)
	(segment
		(start 17.9324 -23.7109)
		(end 17.6403 -24.003)
		(width 0.2032)
		(layer "F.Cu")
		(net "SLOT3_P12V_SENSE_VN_R")
	)
	(segment
		(start 19.090894 -23.6474)
		(end 19.7866 -24.343106)
		(width 0.2032)
		(layer "F.Cu")
		(net "SLOT3_P12V_SENSE_VN_R")
	)
	(segment
		(start 19.318478 -16.203422)
		(end 19.4056 -16.203422)
		(width 0.1016)
		(layer "F.Cu")
		(net "SLOT2_VMONITOR_A1")
	)
	(segment
		(start 20.814538 -16.542512)
		(end 20.814538 -17.727676)
		(width 0.1016)
		(layer "F.Cu")
		(net "SLOT2_VMONITOR_A1")
	)
	(segment
		(start 20.467066 -16.19504)
		(end 20.814538 -16.542512)
		(width 0.1016)
		(layer "F.Cu")
		(net "SLOT2_VMONITOR_A1")
	)
	(segment
		(start 18.5674 -16.9545)
		(end 19.318478 -16.203422)
		(width 0.1016)
		(layer "F.Cu")
		(net "SLOT2_VMONITOR_A1")
	)
	(segment
		(start 18.5674 -17.041622)
		(end 18.5674 -16.9545)
		(width 0.1016)
		(layer "F.Cu")
		(net "SLOT2_VMONITOR_A1")
	)
	(segment
		(start 20.467066 -16.19504)
		(end 19.413982 -16.19504)
		(width 0.1016)
		(layer "F.Cu")
		(net "SLOT2_VMONITOR_A1")
	)
	(segment
		(start 19.413982 -16.19504)
		(end 19.4056 -16.203422)
		(width 0.1016)
		(layer "F.Cu")
		(net "SLOT2_VMONITOR_A1")
	)
	(via
		(at 18.5674 -17.041622)
		(size 0.7112)
		(drill 0.3556)
		(layers "F.Cu" "B.Cu")
		(net "SLOT2_VMONITOR_A1")
	)
	(segment
		(start 22.5679 -16.1798)
		(end 22.5679 -16.0147)
		(width 0.1016)
		(layer "F.Cu")
		(net "SLOT2_VMONITOR_A0")
	)
	(segment
		(start 22.5679 -16.0147)
		(end 23.3172 -15.2654)
		(width 0.1016)
		(layer "F.Cu")
		(net "SLOT2_VMONITOR_A0")
	)
	(segment
		(start 21.5265 -16.1798)
		(end 21.5138 -16.1925)
		(width 0.1016)
		(layer "F.Cu")
		(net "SLOT2_VMONITOR_A0")
	)
	(segment
		(start 21.314664 -16.391636)
		(end 21.5138 -16.1925)
		(width 0.1016)
		(layer "F.Cu")
		(net "SLOT2_VMONITOR_A0")
	)
	(segment
		(start 22.5679 -16.1798)
		(end 21.5265 -16.1798)
		(width 0.1016)
		(layer "F.Cu")
		(net "SLOT2_VMONITOR_A0")
	)
	(segment
		(start 21.314664 -17.727676)
		(end 21.314664 -16.391636)
		(width 0.1016)
		(layer "F.Cu")
		(net "SLOT2_VMONITOR_A0")
	)
	(via
		(at 23.3172 -15.2654)
		(size 0.7112)
		(drill 0.3556)
		(layers "F.Cu" "B.Cu")
		(net "SLOT2_VMONITOR_A0")
	)
	(segment
		(start 18.6436 -20.9677)
		(end 19.700494 -20.9677)
		(width 0.2032)
		(layer "F.Cu")
		(net "SLOT2_P12V_SENSE_VP_R")
	)
	(segment
		(start 17.414748 -19.205448)
		(end 17.414748 -18.932652)
		(width 0.2032)
		(layer "F.Cu")
		(net "SLOT2_P12V_SENSE_VP_R")
	)
	(segment
		(start 17.414748 -19.726148)
		(end 17.414748 -19.205448)
		(width 0.2032)
		(layer "F.Cu")
		(net "SLOT2_P12V_SENSE_VP_R")
	)
	(segment
		(start 19.700494 -20.9677)
		(end 20.013676 -20.654518)
		(width 0.2032)
		(layer "F.Cu")
		(net "SLOT2_P12V_SENSE_VP_R")
	)
	(segment
		(start 20.013676 -20.654518)
		(end 20.013676 -20.028662)
		(width 0.2032)
		(layer "F.Cu")
		(net "SLOT2_P12V_SENSE_VP_R")
	)
	(segment
		(start 17.989296 -20.313396)
		(end 18.6436 -20.9677)
		(width 0.2032)
		(layer "F.Cu")
		(net "SLOT2_P12V_SENSE_VP_R")
	)
	(segment
		(start 17.989296 -19.973544)
		(end 17.662144 -19.973544)
		(width 0.2032)
		(layer "F.Cu")
		(net "SLOT2_P12V_SENSE_VP_R")
	)
	(segment
		(start 17.989296 -19.973544)
		(end 17.989296 -20.313396)
		(width 0.2032)
		(layer "F.Cu")
		(net "SLOT2_P12V_SENSE_VP_R")
	)
	(segment
		(start 17.414748 -18.932652)
		(end 17.9832 -18.3642)
		(width 0.2032)
		(layer "F.Cu")
		(net "SLOT2_P12V_SENSE_VP_R")
	)
	(segment
		(start 17.662144 -19.973544)
		(end 17.414748 -19.726148)
		(width 0.2032)
		(layer "F.Cu")
		(net "SLOT2_P12V_SENSE_VP_R")
	)
	(via
		(at 17.9832 -18.3642)
		(size 0.7112)
		(drill 0.3556)
		(layers "F.Cu" "B.Cu")
		(net "SLOT2_P12V_SENSE_VP_R")
	)
	(segment
		(start 18.0975 -21.424646)
		(end 18.36547 -21.156676)
		(width 0.2032)
		(layer "F.Cu")
		(net "SLOT2_P12V_SENSE_VN_R")
	)
	(segment
		(start 17.3609 -20.60194)
		(end 17.3609 -20.1803)
		(width 0.2032)
		(layer "F.Cu")
		(net "SLOT2_P12V_SENSE_VN_R")
	)
	(segment
		(start 18.36547 -21.156676)
		(end 18.506694 -21.2979)
		(width 0.2032)
		(layer "F.Cu")
		(net "SLOT2_P12V_SENSE_VN_R")
	)
	(segment
		(start 20.305776 -20.829524)
		(end 20.814538 -20.829524)
		(width 0.2032)
		(layer "F.Cu")
		(net "SLOT2_P12V_SENSE_VN_R")
	)
	(segment
		(start 17.132808 -19.952208)
		(end 16.667734 -19.952208)
		(width 0.2032)
		(layer "F.Cu")
		(net "SLOT2_P12V_SENSE_VN_R")
	)
	(segment
		(start 19.8374 -21.2979)
		(end 20.305776 -20.829524)
		(width 0.2032)
		(layer "F.Cu")
		(net "SLOT2_P12V_SENSE_VN_R")
	)
	(segment
		(start 17.810734 -20.60194)
		(end 18.36547 -21.156676)
		(width 0.2032)
		(layer "F.Cu")
		(net "SLOT2_P12V_SENSE_VN_R")
	)
	(segment
		(start 17.3609 -20.1803)
		(end 17.132808 -19.952208)
		(width 0.2032)
		(layer "F.Cu")
		(net "SLOT2_P12V_SENSE_VN_R")
	)
	(segment
		(start 17.3609 -20.60194)
		(end 17.810734 -20.60194)
		(width 0.2032)
		(layer "F.Cu")
		(net "SLOT2_P12V_SENSE_VN_R")
	)
	(segment
		(start 18.506694 -21.2979)
		(end 19.8374 -21.2979)
		(width 0.2032)
		(layer "F.Cu")
		(net "SLOT2_P12V_SENSE_VN_R")
	)
	(via
		(at 18.0975 -21.424646)
		(size 0.7112)
		(drill 0.3556)
		(layers "F.Cu" "B.Cu")
		(net "SLOT2_P12V_SENSE_VN_R")
	)
	(segment
		(start 87.122 -18.4658)
		(end 87.1728 -18.4658)
		(width 0.1016)
		(layer "F.Cu")
		(net "RESET_O_1")
	)
	(segment
		(start 88.12276 -19.41576)
		(end 88.12276 -19.779488)
		(width 0.1016)
		(layer "F.Cu")
		(net "RESET_O_1")
	)
	(segment
		(start 88.12276 -19.779488)
		(end 88.12276 -23.44166)
		(width 0.1016)
		(layer "F.Cu")
		(net "RESET_O_1")
	)
	(segment
		(start 88.0999 -17.272)
		(end 88.0999 -18.2372)
		(width 0.1016)
		(layer "F.Cu")
		(net "RESET_O_1")
	)
	(segment
		(start 88.12276 -23.44166)
		(end 88.138 -23.4569)
		(width 0.1016)
		(layer "F.Cu")
		(net "RESET_O_1")
	)
	(segment
		(start 88.2015 -18.3388)
		(end 87.249 -18.3388)
		(width 0.1016)
		(layer "F.Cu")
		(net "RESET_O_1")
	)
	(segment
		(start 87.1728 -18.4658)
		(end 88.12276 -19.41576)
		(width 0.1016)
		(layer "F.Cu")
		(net "RESET_O_1")
	)
	(segment
		(start 88.0999 -18.2372)
		(end 88.2015 -18.3388)
		(width 0.1016)
		(layer "F.Cu")
		(net "RESET_O_1")
	)
	(segment
		(start 87.249 -18.3388)
		(end 87.122 -18.4658)
		(width 0.1016)
		(layer "F.Cu")
		(net "RESET_O_1")
	)
	(via
		(at 87.122 -18.4658)
		(size 0.7112)
		(drill 0.3556)
		(layers "F.Cu" "B.Cu")
		(net "RESET_O_1")
	)
	(segment
		(start 87.10676 -22.014688)
		(end 86.618572 -21.5265)
		(width 0.1016)
		(layer "F.Cu")
		(net "RESET_IN")
	)
	(segment
		(start 83.3628 -21.9456)
		(end 83.8962 -22.479)
		(width 0.1016)
		(layer "F.Cu")
		(net "RESET_IN")
	)
	(segment
		(start 83.3628 -21.5773)
		(end 83.3628 -21.9456)
		(width 0.1016)
		(layer "F.Cu")
		(net "RESET_IN")
	)
	(segment
		(start 82.3976 -21.5773)
		(end 82.1436 -21.3233)
		(width 0.1016)
		(layer "F.Cu")
		(net "RESET_IN")
	)
	(segment
		(start 83.3628 -21.5773)
		(end 82.3976 -21.5773)
		(width 0.1016)
		(layer "F.Cu")
		(net "RESET_IN")
	)
	(segment
		(start 84.4804 -21.8948)
		(end 83.8962 -22.479)
		(width 0.1016)
		(layer "F.Cu")
		(net "RESET_IN")
	)
	(segment
		(start 84.4804 -21.5265)
		(end 84.4804 -21.8948)
		(width 0.1016)
		(layer "F.Cu")
		(net "RESET_IN")
	)
	(segment
		(start 86.618572 -21.5265)
		(end 84.4804 -21.5265)
		(width 0.1016)
		(layer "F.Cu")
		(net "RESET_IN")
	)
	(via
		(at 83.8962 -22.479)
		(size 0.7112)
		(drill 0.3556)
		(layers "F.Cu" "B.Cu")
		(net "RESET_IN")
	)
	(segment
		(start 82.2071 -15.621)
		(end 93.7133 -15.621)
		(width 0.1016)
		(layer "F.Cu")
		(net "RESET_BUF_N_SLOT3")
	)
	(segment
		(start 58.2422 -17.8308)
		(end 56.6674 -17.8308)
		(width 0.1016)
		(layer "F.Cu")
		(net "RESET_BUF_N_SLOT3")
	)
	(segment
		(start 79.5147 -18.3134)
		(end 82.2071 -15.621)
		(width 0.1016)
		(layer "F.Cu")
		(net "RESET_BUF_N_SLOT3")
	)
	(segment
		(start 62.357 -17.907)
		(end 62.3316 -17.8816)
		(width 0.1016)
		(layer "F.Cu")
		(net "RESET_BUF_N_SLOT3")
	)
	(segment
		(start 55.118 -18.161)
		(end 54.6354 -18.6436)
		(width 0.1016)
		(layer "F.Cu")
		(net "RESET_BUF_N_SLOT3")
	)
	(segment
		(start 75.7428 -17.907)
		(end 76.1492 -18.3134)
		(width 0.1016)
		(layer "F.Cu")
		(net "RESET_BUF_N_SLOT3")
	)
	(segment
		(start 56.6674 -17.8308)
		(end 56.3372 -18.161)
		(width 0.1016)
		(layer "F.Cu")
		(net "RESET_BUF_N_SLOT3")
	)
	(segment
		(start 58.293 -17.8816)
		(end 58.2422 -17.8308)
		(width 0.1016)
		(layer "F.Cu")
		(net "RESET_BUF_N_SLOT3")
	)
	(segment
		(start 93.7133 -15.621)
		(end 94.5134 -16.4211)
		(width 0.1016)
		(layer "F.Cu")
		(net "RESET_BUF_N_SLOT3")
	)
	(segment
		(start 54.6354 -18.6436)
		(end 54.6354 -18.7452)
		(width 0.1016)
		(layer "F.Cu")
		(net "RESET_BUF_N_SLOT3")
	)
	(segment
		(start 75.7428 -17.907)
		(end 62.357 -17.907)
		(width 0.1016)
		(layer "F.Cu")
		(net "RESET_BUF_N_SLOT3")
	)
	(segment
		(start 62.3316 -17.8816)
		(end 58.293 -17.8816)
		(width 0.1016)
		(layer "F.Cu")
		(net "RESET_BUF_N_SLOT3")
	)
	(segment
		(start 76.1492 -18.3134)
		(end 79.5147 -18.3134)
		(width 0.1016)
		(layer "F.Cu")
		(net "RESET_BUF_N_SLOT3")
	)
	(segment
		(start 56.3372 -18.161)
		(end 55.118 -18.161)
		(width 0.1016)
		(layer "F.Cu")
		(net "RESET_BUF_N_SLOT3")
	)
	(via
		(at 75.7428 -17.907)
		(size 0.7112)
		(drill 0.3556)
		(layers "F.Cu" "B.Cu")
		(net "RESET_BUF_N_SLOT3")
	)
	(via
		(at 54.6354 -18.7452)
		(size 0.508)
		(drill 0.254)
		(layers "F.Cu" "B.Cu")
		(net "RESET_BUF_N_SLOT3")
	)
	(segment
		(start 41.573196 -32.5628)
		(end 43.307 -32.5628)
		(width 0.127)
		(layer "In2.Cu")
		(net "RESET_BUF_N_SLOT3")
	)
	(segment
		(start 53.5178 -20.1676)
		(end 54.6354 -19.05)
		(width 0.127)
		(layer "In2.Cu")
		(net "RESET_BUF_N_SLOT3")
	)
	(segment
		(start 44.458128 -30.770068)
		(end 44.0944 -29.72435)
		(width 0.127)
		(layer "In2.Cu")
		(net "RESET_BUF_N_SLOT3")
	)
	(segment
		(start 45.1358 -23.241)
		(end 48.2092 -20.1676)
		(width 0.127)
		(layer "In2.Cu")
		(net "RESET_BUF_N_SLOT3")
	)
	(segment
		(start 48.2092 -20.1676)
		(end 53.5178 -20.1676)
		(width 0.127)
		(layer "In2.Cu")
		(net "RESET_BUF_N_SLOT3")
	)
	(segment
		(start 44.3865 -31.4833)
		(end 44.458128 -30.770068)
		(width 0.127)
		(layer "In2.Cu")
		(net "RESET_BUF_N_SLOT3")
	)
	(segment
		(start 43.307 -32.5628)
		(end 44.3865 -31.4833)
		(width 0.127)
		(layer "In2.Cu")
		(net "RESET_BUF_N_SLOT3")
	)
	(segment
		(start 54.6354 -19.05)
		(end 54.6354 -18.7452)
		(width 0.127)
		(layer "In2.Cu")
		(net "RESET_BUF_N_SLOT3")
	)
	(segment
		(start 41.080182 -32.069786)
		(end 41.573196 -32.5628)
		(width 0.127)
		(layer "In2.Cu")
		(net "RESET_BUF_N_SLOT3")
	)
	(segment
		(start 44.0944 -29.72435)
		(end 44.0944 -28.956)
		(width 0.127)
		(layer "In2.Cu")
		(net "RESET_BUF_N_SLOT3")
	)
	(segment
		(start 44.0944 -28.956)
		(end 45.1358 -27.9146)
		(width 0.127)
		(layer "In2.Cu")
		(net "RESET_BUF_N_SLOT3")
	)
	(segment
		(start 45.1358 -27.9146)
		(end 45.1358 -23.241)
		(width 0.127)
		(layer "In2.Cu")
		(net "RESET_BUF_N_SLOT3")
	)
	(segment
		(start 94.8944 -15.3162)
		(end 80.264 -15.3162)
		(width 0.1016)
		(layer "F.Cu")
		(net "RESET_BUF_N_SLOT2")
	)
	(segment
		(start 41.080182 -11.749786)
		(end 41.649396 -12.319)
		(width 0.1016)
		(layer "F.Cu")
		(net "RESET_BUF_N_SLOT2")
	)
	(segment
		(start 41.649396 -12.319)
		(end 42.291 -12.319)
		(width 0.1016)
		(layer "F.Cu")
		(net "RESET_BUF_N_SLOT2")
	)
	(segment
		(start 58.4454 -17.3736)
		(end 58.6994 -17.1196)
		(width 0.1016)
		(layer "F.Cu")
		(net "RESET_BUF_N_SLOT2")
	)
	(segment
		(start 58.6994 -17.1196)
		(end 58.9026 -17.3228)
		(width 0.1016)
		(layer "F.Cu")
		(net "RESET_BUF_N_SLOT2")
	)
	(segment
		(start 62.204092 -17.3228)
		(end 62.483492 -17.6022)
		(width 0.1016)
		(layer "F.Cu")
		(net "RESET_BUF_N_SLOT2")
	)
	(segment
		(start 76.581 -16.5608)
		(end 77.7748 -17.7546)
		(width 0.1016)
		(layer "F.Cu")
		(net "RESET_BUF_N_SLOT2")
	)
	(segment
		(start 51.6382 -17.3736)
		(end 58.4454 -17.3736)
		(width 0.1016)
		(layer "F.Cu")
		(net "RESET_BUF_N_SLOT2")
	)
	(segment
		(start 58.9026 -17.3228)
		(end 62.204092 -17.3228)
		(width 0.1016)
		(layer "F.Cu")
		(net "RESET_BUF_N_SLOT2")
	)
	(segment
		(start 43.18 -14.3256)
		(end 44.4246 -15.5702)
		(width 0.1016)
		(layer "F.Cu")
		(net "RESET_BUF_N_SLOT2")
	)
	(segment
		(start 62.483492 -17.6022)
		(end 68.4784 -17.6022)
		(width 0.1016)
		(layer "F.Cu")
		(net "RESET_BUF_N_SLOT2")
	)
	(segment
		(start 49.8348 -15.5702)
		(end 51.6382 -17.3736)
		(width 0.1016)
		(layer "F.Cu")
		(net "RESET_BUF_N_SLOT2")
	)
	(segment
		(start 42.291 -12.319)
		(end 43.18 -13.208)
		(width 0.1016)
		(layer "F.Cu")
		(net "RESET_BUF_N_SLOT2")
	)
	(segment
		(start 44.4246 -15.5702)
		(end 49.8348 -15.5702)
		(width 0.1016)
		(layer "F.Cu")
		(net "RESET_BUF_N_SLOT2")
	)
	(segment
		(start 95.5802 -16.002)
		(end 94.8944 -15.3162)
		(width 0.1016)
		(layer "F.Cu")
		(net "RESET_BUF_N_SLOT2")
	)
	(segment
		(start 95.5802 -16.4211)
		(end 95.5802 -16.002)
		(width 0.1016)
		(layer "F.Cu")
		(net "RESET_BUF_N_SLOT2")
	)
	(segment
		(start 69.5198 -16.5608)
		(end 76.581 -16.5608)
		(width 0.1016)
		(layer "F.Cu")
		(net "RESET_BUF_N_SLOT2")
	)
	(segment
		(start 43.18 -13.208)
		(end 43.18 -14.3256)
		(width 0.1016)
		(layer "F.Cu")
		(net "RESET_BUF_N_SLOT2")
	)
	(segment
		(start 80.264 -15.3162)
		(end 77.8256 -17.7546)
		(width 0.1016)
		(layer "F.Cu")
		(net "RESET_BUF_N_SLOT2")
	)
	(segment
		(start 77.8256 -17.7546)
		(end 77.7748 -17.7546)
		(width 0.1016)
		(layer "F.Cu")
		(net "RESET_BUF_N_SLOT2")
	)
	(segment
		(start 68.4784 -17.6022)
		(end 69.5198 -16.5608)
		(width 0.1016)
		(layer "F.Cu")
		(net "RESET_BUF_N_SLOT2")
	)
	(via
		(at 58.6994 -17.1196)
		(size 0.7112)
		(drill 0.3556)
		(layers "F.Cu" "B.Cu")
		(net "RESET_BUF_N_SLOT2")
	)
	(via
		(at 77.7748 -17.7546)
		(size 0.7112)
		(drill 0.3556)
		(layers "F.Cu" "B.Cu")
		(net "RESET_BUF_N_SLOT2")
	)
	(segment
		(start 128.079754 -29.616654)
		(end 128.8796 -30.4165)
		(width 0.254)
		(layer "F.Cu")
		(net "RBIAS")
	)
	(segment
		(start 127.11938 -29.616654)
		(end 128.079754 -29.616654)
		(width 0.254)
		(layer "F.Cu")
		(net "RBIAS")
	)
	(segment
		(start 127.11938 -29.116528)
		(end 128.595628 -29.116528)
		(width 0.254)
		(layer "F.Cu")
		(net "PLLFILT")
	)
	(segment
		(start 128.595628 -29.116528)
		(end 128.8415 -29.3624)
		(width 0.254)
		(layer "F.Cu")
		(net "PLLFILT")
	)
	(segment
		(start 95.5802 -17.3101)
		(end 94.5134 -17.3101)
		(width 0.1016)
		(layer "F.Cu")
		(net "PERST_SLOT_N")
	)
	(segment
		(start 94.5134 -18.7198)
		(end 94.2594 -18.9738)
		(width 0.1016)
		(layer "F.Cu")
		(net "PERST_SLOT_N")
	)
	(segment
		(start 92.6211 -17.18056)
		(end 94.38386 -17.18056)
		(width 0.1016)
		(layer "F.Cu")
		(net "PERST_SLOT_N")
	)
	(segment
		(start 94.38386 -17.18056)
		(end 94.5134 -17.3101)
		(width 0.1016)
		(layer "F.Cu")
		(net "PERST_SLOT_N")
	)
	(segment
		(start 96.647 -17.3101)
		(end 95.5802 -17.3101)
		(width 0.1016)
		(layer "F.Cu")
		(net "PERST_SLOT_N")
	)
	(segment
		(start 94.5134 -17.3101)
		(end 94.5134 -18.7198)
		(width 0.1016)
		(layer "F.Cu")
		(net "PERST_SLOT_N")
	)
	(via
		(at 94.2594 -18.9738)
		(size 0.7112)
		(drill 0.3556)
		(layers "F.Cu" "B.Cu")
		(net "PERST_SLOT_N")
	)
	(segment
		(start 95.4786 -19.8374)
		(end 95.4786 -20.2946)
		(width 0.1016)
		(layer "F.Cu")
		(net "PERST_O_1_R")
	)
	(segment
		(start 96.6978 -19.304)
		(end 96.012 -19.304)
		(width 0.1016)
		(layer "F.Cu")
		(net "PERST_O_1_R")
	)
	(segment
		(start 86.6902 -17.272)
		(end 87.2109 -17.272)
		(width 0.1016)
		(layer "F.Cu")
		(net "PERST_O_1_R")
	)
	(segment
		(start 95.4786 -20.3454)
		(end 95.4532 -20.32)
		(width 0.1016)
		(layer "F.Cu")
		(net "PERST_O_1_R")
	)
	(segment
		(start 95.4786 -20.5994)
		(end 95.4786 -20.3454)
		(width 0.1016)
		(layer "F.Cu")
		(net "PERST_O_1_R")
	)
	(segment
		(start 95.4786 -20.2946)
		(end 95.4532 -20.32)
		(width 0.1016)
		(layer "F.Cu")
		(net "PERST_O_1_R")
	)
	(segment
		(start 85.4456 -18.5166)
		(end 86.6902 -17.272)
		(width 0.1016)
		(layer "F.Cu")
		(net "PERST_O_1_R")
	)
	(segment
		(start 96.012 -19.304)
		(end 95.4786 -19.8374)
		(width 0.1016)
		(layer "F.Cu")
		(net "PERST_O_1_R")
	)
	(segment
		(start 96.062546 -21.183346)
		(end 95.4786 -20.5994)
		(width 0.1016)
		(layer "F.Cu")
		(net "PERST_O_1_R")
	)
	(segment
		(start 96.874838 -21.183346)
		(end 96.062546 -21.183346)
		(width 0.1016)
		(layer "F.Cu")
		(net "PERST_O_1_R")
	)
	(via
		(at 96.6978 -19.304)
		(size 0.508)
		(drill 0.254)
		(layers "F.Cu" "B.Cu")
		(net "PERST_O_1_R")
	)
	(via
		(at 85.4456 -18.5166)
		(size 0.508)
		(drill 0.254)
		(layers "F.Cu" "B.Cu")
		(net "PERST_O_1_R")
	)
	(via
		(at 95.4532 -20.32)
		(size 0.7112)
		(drill 0.3556)
		(layers "F.Cu" "B.Cu")
		(net "PERST_O_1_R")
	)
	(segment
		(start 95.9104 -18.5166)
		(end 96.6978 -19.304)
		(width 0.1016)
		(layer "B.Cu")
		(net "PERST_O_1_R")
	)
	(segment
		(start 85.4456 -18.5166)
		(end 95.9104 -18.5166)
		(width 0.1016)
		(layer "B.Cu")
		(net "PERST_O_1_R")
	)
	(segment
		(start 90.9701 -17.8308)
		(end 89.5985 -17.8308)
		(width 0.1016)
		(layer "F.Cu")
		(net "PERST_N_1_R")
	)
	(segment
		(start 89.5985 -17.8308)
		(end 89.0905 -18.3388)
		(width 0.1016)
		(layer "F.Cu")
		(net "PERST_N_1_R")
	)
	(segment
		(start 89.5858 -20.6629)
		(end 89.5858 -19.9136)
		(width 0.1016)
		(layer "F.Cu")
		(net "PERST_N_1_R")
	)
	(segment
		(start 89.0905 -19.4183)
		(end 89.3318 -19.6596)
		(width 0.1016)
		(layer "F.Cu")
		(net "PERST_N_1_R")
	)
	(segment
		(start 89.5858 -19.9136)
		(end 89.3318 -19.6596)
		(width 0.1016)
		(layer "F.Cu")
		(net "PERST_N_1_R")
	)
	(segment
		(start 89.0905 -18.3388)
		(end 89.0905 -19.4183)
		(width 0.1016)
		(layer "F.Cu")
		(net "PERST_N_1_R")
	)
	(via
		(at 89.3318 -19.6596)
		(size 0.7112)
		(drill 0.3556)
		(layers "F.Cu" "B.Cu")
		(net "PERST_N_1_R")
	)
	(segment
		(start 90.5256 -20.3962)
		(end 90.5256 -20.828)
		(width 0.1016)
		(layer "F.Cu")
		(net "PERST_N_1")
	)
	(segment
		(start 89.5858 -21.5519)
		(end 88.7984 -22.3393)
		(width 0.1016)
		(layer "F.Cu")
		(net "PERST_N_1")
	)
	(segment
		(start 98.175318 -23.490682)
		(end 97.2312 -24.4348)
		(width 0.1016)
		(layer "F.Cu")
		(net "PERST_N_1")
	)
	(segment
		(start 90.5256 -20.828)
		(end 89.8017 -21.5519)
		(width 0.1016)
		(layer "F.Cu")
		(net "PERST_N_1")
	)
	(segment
		(start 98.175318 -22.834346)
		(end 98.175318 -23.490682)
		(width 0.1016)
		(layer "F.Cu")
		(net "PERST_N_1")
	)
	(segment
		(start 88.7984 -22.3393)
		(end 88.7984 -22.6822)
		(width 0.1016)
		(layer "F.Cu")
		(net "PERST_N_1")
	)
	(segment
		(start 89.8017 -21.5519)
		(end 89.5858 -21.5519)
		(width 0.1016)
		(layer "F.Cu")
		(net "PERST_N_1")
	)
	(via
		(at 97.2312 -24.4348)
		(size 0.508)
		(drill 0.254)
		(layers "F.Cu" "B.Cu")
		(net "PERST_N_1")
	)
	(via
		(at 88.7984 -22.6822)
		(size 0.508)
		(drill 0.254)
		(layers "F.Cu" "B.Cu")
		(net "PERST_N_1")
	)
	(via
		(at 90.5256 -20.3962)
		(size 0.7112)
		(drill 0.3556)
		(layers "F.Cu" "B.Cu")
		(net "PERST_N_1")
	)
	(segment
		(start 95.4786 -22.6822)
		(end 97.2312 -24.4348)
		(width 0.1016)
		(layer "B.Cu")
		(net "PERST_N_1")
	)
	(segment
		(start 88.7984 -22.6822)
		(end 95.4786 -22.6822)
		(width 0.1016)
		(layer "B.Cu")
		(net "PERST_N_1")
	)
	(segment
		(start 28.1305 8.4582)
		(end 27.5082 9.0805)
		(width 0.1016)
		(layer "F.Cu")
		(net "PERST_N")
	)
	(segment
		(start 28.5623 8.4582)
		(end 28.1305 8.4582)
		(width 0.1016)
		(layer "F.Cu")
		(net "PERST_N")
	)
	(segment
		(start 26.779982 10.380218)
		(end 26.779982 12.133072)
		(width 0.1016)
		(layer "F.Cu")
		(net "PERST_N")
	)
	(segment
		(start 27.5082 9.0805)
		(end 27.5082 9.652)
		(width 0.1016)
		(layer "F.Cu")
		(net "PERST_N")
	)
	(segment
		(start 55.5752 -18.8976)
		(end 79.8576 -18.8976)
		(width 0.1016)
		(layer "F.Cu")
		(net "PERST_N")
	)
	(segment
		(start 80.9498 -17.8054)
		(end 83.3628 -17.8054)
		(width 0.1016)
		(layer "F.Cu")
		(net "PERST_N")
	)
	(segment
		(start 83.3628 -17.8054)
		(end 85.2424 -15.9258)
		(width 0.1016)
		(layer "F.Cu")
		(net "PERST_N")
	)
	(segment
		(start 79.8576 -18.8976)
		(end 80.9498 -17.8054)
		(width 0.1016)
		(layer "F.Cu")
		(net "PERST_N")
	)
	(segment
		(start 27.5082 9.652)
		(end 26.779982 10.380218)
		(width 0.1016)
		(layer "F.Cu")
		(net "PERST_N")
	)
	(segment
		(start 85.2424 -15.9258)
		(end 91.2114 -15.9258)
		(width 0.1016)
		(layer "F.Cu")
		(net "PERST_N")
	)
	(segment
		(start 91.50096 -18.48104)
		(end 90.9701 -18.48104)
		(width 0.1016)
		(layer "F.Cu")
		(net "PERST_N")
	)
	(segment
		(start 91.7575 -18.2245)
		(end 91.50096 -18.48104)
		(width 0.1016)
		(layer "F.Cu")
		(net "PERST_N")
	)
	(segment
		(start 91.7575 -16.4719)
		(end 91.7575 -18.2245)
		(width 0.1016)
		(layer "F.Cu")
		(net "PERST_N")
	)
	(segment
		(start 91.2114 -15.9258)
		(end 91.7575 -16.4719)
		(width 0.1016)
		(layer "F.Cu")
		(net "PERST_N")
	)
	(via
		(at 55.5752 -18.8976)
		(size 0.508)
		(drill 0.254)
		(layers "F.Cu" "B.Cu")
		(net "PERST_N")
	)
	(via
		(at 29.7688 7.5946)
		(size 0.7112)
		(drill 0.3556)
		(layers "F.Cu" "B.Cu")
		(net "PERST_N")
	)
	(via
		(at 51.6382 5.7658)
		(size 0.508)
		(drill 0.254)
		(layers "F.Cu" "B.Cu")
		(net "PERST_N")
	)
	(via
		(at 28.5623 8.4582)
		(size 0.508)
		(drill 0.254)
		(layers "F.Cu" "B.Cu")
		(net "PERST_N")
	)
	(segment
		(start 28.5623 8.4582)
		(end 28.9052 8.4582)
		(width 0.1016)
		(layer "B.Cu")
		(net "PERST_N")
	)
	(segment
		(start 28.9052 8.4582)
		(end 29.7688 7.5946)
		(width 0.1016)
		(layer "B.Cu")
		(net "PERST_N")
	)
	(segment
		(start 57.5564 0.423418)
		(end 57.5564 -2.2352)
		(width 0.127)
		(layer "In2.Cu")
		(net "PERST_N")
	)
	(segment
		(start 52.0954 -12.1158)
		(end 52.8066 -12.827)
		(width 0.127)
		(layer "In2.Cu")
		(net "PERST_N")
	)
	(segment
		(start 54.099206 -17.3863)
		(end 55.0291 -18.316194)
		(width 0.127)
		(layer "In2.Cu")
		(net "PERST_N")
	)
	(segment
		(start 51.6382 5.7658)
		(end 52.214018 5.7658)
		(width 0.127)
		(layer "In2.Cu")
		(net "PERST_N")
	)
	(segment
		(start 52.214018 5.7658)
		(end 57.5564 0.423418)
		(width 0.127)
		(layer "In2.Cu")
		(net "PERST_N")
	)
	(segment
		(start 53.3908 -14.4272)
		(end 53.3908 -16.7132)
		(width 0.127)
		(layer "In2.Cu")
		(net "PERST_N")
	)
	(segment
		(start 52.8066 -12.827)
		(end 52.8066 -13.843)
		(width 0.127)
		(layer "In2.Cu")
		(net "PERST_N")
	)
	(segment
		(start 54.0639 -17.3863)
		(end 54.099206 -17.3863)
		(width 0.127)
		(layer "In2.Cu")
		(net "PERST_N")
	)
	(segment
		(start 52.2986 -8.3566)
		(end 52.2986 -8.4582)
		(width 0.127)
		(layer "In2.Cu")
		(net "PERST_N")
	)
	(segment
		(start 57.5564 -2.2352)
		(end 53.356002 -6.435598)
		(width 0.127)
		(layer "In2.Cu")
		(net "PERST_N")
	)
	(segment
		(start 53.356002 -6.435598)
		(end 53.356002 -7.299198)
		(width 0.127)
		(layer "In2.Cu")
		(net "PERST_N")
	)
	(segment
		(start 55.0291 -18.3515)
		(end 55.5752 -18.8976)
		(width 0.127)
		(layer "In2.Cu")
		(net "PERST_N")
	)
	(segment
		(start 53.3908 -16.7132)
		(end 54.0639 -17.3863)
		(width 0.127)
		(layer "In2.Cu")
		(net "PERST_N")
	)
	(segment
		(start 52.8066 -13.843)
		(end 53.3908 -14.4272)
		(width 0.127)
		(layer "In2.Cu")
		(net "PERST_N")
	)
	(segment
		(start 52.0954 -8.6614)
		(end 52.0954 -12.1158)
		(width 0.127)
		(layer "In2.Cu")
		(net "PERST_N")
	)
	(segment
		(start 52.2986 -8.4582)
		(end 52.0954 -8.6614)
		(width 0.127)
		(layer "In2.Cu")
		(net "PERST_N")
	)
	(segment
		(start 55.0291 -18.316194)
		(end 55.0291 -18.3515)
		(width 0.127)
		(layer "In2.Cu")
		(net "PERST_N")
	)
	(segment
		(start 53.356002 -7.299198)
		(end 52.2986 -8.3566)
		(width 0.127)
		(layer "In2.Cu")
		(net "PERST_N")
	)
	(segment
		(start 51.0921 6.3119)
		(end 51.6382 5.7658)
		(width 0.127)
		(layer "In3.Cu")
		(net "PERST_N")
	)
	(segment
		(start 35.938206 6.3119)
		(end 51.0921 6.3119)
		(width 0.127)
		(layer "In3.Cu")
		(net "PERST_N")
	)
	(segment
		(start 28.5623 8.4582)
		(end 33.791906 8.4582)
		(width 0.127)
		(layer "In3.Cu")
		(net "PERST_N")
	)
	(segment
		(start 33.791906 8.4582)
		(end 35.938206 6.3119)
		(width 0.127)
		(layer "In3.Cu")
		(net "PERST_N")
	)
	(via
		(at 27.178 -32.2072)
		(size 0.7112)
		(drill 0.3556)
		(layers "F.Cu" "B.Cu")
		(net "PD_SLOT3_PRSNT1")
	)
	(segment
		(start 27.4955 -32.5247)
		(end 27.178 -32.2072)
		(width 0.1016)
		(layer "B.Cu")
		(net "PD_SLOT3_PRSNT1")
	)
	(segment
		(start 29.901388 -33.2486)
		(end 31.080202 -32.069786)
		(width 0.1016)
		(layer "B.Cu")
		(net "PD_SLOT3_PRSNT1")
	)
	(segment
		(start 27.4955 -33.2486)
		(end 27.4955 -32.5247)
		(width 0.1016)
		(layer "B.Cu")
		(net "PD_SLOT3_PRSNT1")
	)
	(segment
		(start 27.4955 -33.2486)
		(end 29.901388 -33.2486)
		(width 0.1016)
		(layer "B.Cu")
		(net "PD_SLOT3_PRSNT1")
	)
	(via
		(at 32.7787 -3.302)
		(size 0.7112)
		(drill 0.3556)
		(layers "F.Cu" "B.Cu")
		(net "PD_SLOT2_PRSNT1")
	)
	(segment
		(start 29.6164 -7.0866)
		(end 32.7787 -3.9243)
		(width 0.1016)
		(layer "B.Cu")
		(net "PD_SLOT2_PRSNT1")
	)
	(segment
		(start 31.080202 -11.749786)
		(end 30.520386 -11.749786)
		(width 0.1016)
		(layer "B.Cu")
		(net "PD_SLOT2_PRSNT1")
	)
	(segment
		(start 30.520386 -11.749786)
		(end 29.6164 -10.8458)
		(width 0.1016)
		(layer "B.Cu")
		(net "PD_SLOT2_PRSNT1")
	)
	(segment
		(start 32.7787 -3.9243)
		(end 32.7787 -3.302)
		(width 0.1016)
		(layer "B.Cu")
		(net "PD_SLOT2_PRSNT1")
	)
	(segment
		(start 32.7787 -3.302)
		(end 32.7787 -2.0574)
		(width 0.1016)
		(layer "B.Cu")
		(net "PD_SLOT2_PRSNT1")
	)
	(segment
		(start 29.6164 -10.8458)
		(end 29.6164 -7.0866)
		(width 0.1016)
		(layer "B.Cu")
		(net "PD_SLOT2_PRSNT1")
	)
	(segment
		(start 132.1943 -11.4808)
		(end 132.969 -11.4808)
		(width 0.4064)
		(layer "F.Cu")
		(net "P3V3_STBY")
	)
	(segment
		(start 119.3546 -16.4973)
		(end 119.4943 -16.637)
		(width 0.381)
		(layer "F.Cu")
		(net "P3V3_STBY")
	)
	(segment
		(start 132.1435 -13.6144)
		(end 132.1689 -13.589)
		(width 0.4572)
		(layer "F.Cu")
		(net "P3V3_STBY")
	)
	(segment
		(start 132.1181 -18.8214)
		(end 132.9436 -18.8214)
		(width 0.4572)
		(layer "F.Cu")
		(net "P3V3_STBY")
	)
	(segment
		(start 126.5682 -20.1168)
		(end 126.5682 -20.6629)
		(width 0.508)
		(layer "F.Cu")
		(net "P3V3_STBY")
	)
	(segment
		(start 27.1907 -23.3045)
		(end 27.94 -24.0538)
		(width 0.508)
		(layer "F.Cu")
		(net "P3V3_STBY")
	)
	(segment
		(start 117.277388 -21.247354)
		(end 117.162834 -21.1328)
		(width 0.4064)
		(layer "F.Cu")
		(net "P3V3_STBY")
	)
	(segment
		(start 116.967 -21.1328)
		(end 116.5606 -20.7264)
		(width 0.4064)
		(layer "F.Cu")
		(net "P3V3_STBY")
	)
	(segment
		(start 18.6436 -15.8242)
		(end 18.6436 -15.7734)
		(width 0.4064)
		(layer "F.Cu")
		(net "P3V3_STBY")
	)
	(segment
		(start 25.723596 9.798304)
		(end 25.179782 10.342118)
		(width 0.5588)
		(layer "F.Cu")
		(net "P3V3_STBY")
	)
	(segment
		(start 21.7424 4.1783)
		(end 23.3553 4.1783)
		(width 0.4064)
		(layer "F.Cu")
		(net "P3V3_STBY")
	)
	(segment
		(start 25.179782 10.342118)
		(end 25.179782 12.133072)
		(width 0.5588)
		(layer "F.Cu")
		(net "P3V3_STBY")
	)
	(segment
		(start 126.1872 -19.304)
		(end 126.3142 -19.431)
		(width 0.508)
		(layer "F.Cu")
		(net "P3V3_STBY")
	)
	(segment
		(start 40.079422 -27.570176)
		(end 40.079422 -28.459684)
		(width 0.508)
		(layer "F.Cu")
		(net "P3V3_STBY")
	)
	(segment
		(start 129.159 -10.3759)
		(end 129.2098 -10.3251)
		(width 0.4064)
		(layer "F.Cu")
		(net "P3V3_STBY")
	)
	(segment
		(start 127.0635 -20.7137)
		(end 127.6858 -20.0914)
		(width 0.3048)
		(layer "F.Cu")
		(net "P3V3_STBY")
	)
	(segment
		(start 24.3078 -15.7353)
		(end 23.8633 -16.1798)
		(width 0.508)
		(layer "F.Cu")
		(net "P3V3_STBY")
	)
	(segment
		(start 23.3426 -21.4376)
		(end 22.734524 -20.829524)
		(width 0.3048)
		(layer "F.Cu")
		(net "P3V3_STBY")
	)
	(segment
		(start 20.699476 -27.750262)
		(end 20.699476 -28.043124)
		(width 0.3048)
		(layer "F.Cu")
		(net "P3V3_STBY")
	)
	(segment
		(start 19.102578 -15.314422)
		(end 19.4056 -15.314422)
		(width 0.4064)
		(layer "F.Cu")
		(net "P3V3_STBY")
	)
	(segment
		(start 62.5221 -16.1798)
		(end 62.2427 -15.9004)
		(width 0.508)
		(layer "F.Cu")
		(net "P3V3_STBY")
	)
	(segment
		(start 130.37312 -3.175)
		(end 131.2037 -3.175)
		(width 0.3048)
		(layer "F.Cu")
		(net "P3V3_STBY")
	)
	(segment
		(start 132.1181 -17.78)
		(end 132.1181 -18.8214)
		(width 0.4572)
		(layer "F.Cu")
		(net "P3V3_STBY")
	)
	(segment
		(start 28.1686 -26.4795)
		(end 28.1686 -24.2824)
		(width 0.508)
		(layer "F.Cu")
		(net "P3V3_STBY")
	)
	(segment
		(start 24.3078 -15.2908)
		(end 24.3078 -15.7353)
		(width 0.508)
		(layer "F.Cu")
		(net "P3V3_STBY")
	)
	(segment
		(start 20.32 5.2197)
		(end 20.7137 4.826)
		(width 0.4064)
		(layer "F.Cu")
		(net "P3V3_STBY")
	)
	(segment
		(start 116.6114 -7.2644)
		(end 116.8146 -7.0612)
		(width 0.4572)
		(layer "F.Cu")
		(net "P3V3_STBY")
	)
	(segment
		(start 23.3045 -22.3012)
		(end 23.3426 -22.2631)
		(width 0.3048)
		(layer "F.Cu")
		(net "P3V3_STBY")
	)
	(segment
		(start 119.4943 -16.637)
		(end 118.7958 -16.637)
		(width 0.4572)
		(layer "F.Cu")
		(net "P3V3_STBY")
	)
	(segment
		(start 127.6858 -20.0914)
		(end 127.6858 -19.47672)
		(width 0.3048)
		(layer "F.Cu")
		(net "P3V3_STBY")
	)
	(segment
		(start 133.2738 -5.9182)
		(end 133.5278 -5.9182)
		(width 0.4572)
		(layer "F.Cu")
		(net "P3V3_STBY")
	)
	(segment
		(start 119.1895 -11.2522)
		(end 119.1895 -10.2362)
		(width 0.4064)
		(layer "F.Cu")
		(net "P3V3_STBY")
	)
	(segment
		(start 126.619 -20.7137)
		(end 127.0635 -20.7137)
		(width 0.3048)
		(layer "F.Cu")
		(net "P3V3_STBY")
	)
	(segment
		(start 132.6515 -6.7564)
		(end 132.6515 -5.715)
		(width 0.4572)
		(layer "F.Cu")
		(net "P3V3_STBY")
	)
	(segment
		(start 133.0706 -5.715)
		(end 133.2738 -5.9182)
		(width 0.4572)
		(layer "F.Cu")
		(net "P3V3_STBY")
	)
	(segment
		(start 118.7958 -16.637)
		(end 118.7196 -16.7132)
		(width 0.4572)
		(layer "F.Cu")
		(net "P3V3_STBY")
	)
	(segment
		(start 23.8633 -16.1798)
		(end 23.4569 -16.1798)
		(width 0.508)
		(layer "F.Cu")
		(net "P3V3_STBY")
	)
	(segment
		(start 92.6211 -19.431)
		(end 93.1037 -19.9136)
		(width 0.3048)
		(layer "F.Cu")
		(net "P3V3_STBY")
	)
	(segment
		(start 23.3426 -22.2631)
		(end 23.3426 -21.4376)
		(width 0.3048)
		(layer "F.Cu")
		(net "P3V3_STBY")
	)
	(segment
		(start 52.0446 -16.2306)
		(end 52.4764 -16.6624)
		(width 0.508)
		(layer "F.Cu")
		(net "P3V3_STBY")
	)
	(segment
		(start 132.0292 -22.0853)
		(end 132.1435 -21.971)
		(width 0.4064)
		(layer "F.Cu")
		(net "P3V3_STBY")
	)
	(segment
		(start 118.1862 -10.2108)
		(end 116.8908 -8.9154)
		(width 0.508)
		(layer "F.Cu")
		(net "P3V3_STBY")
	)
	(segment
		(start 131.2037 -3.175)
		(end 131.6355 -2.7432)
		(width 0.3048)
		(layer "F.Cu")
		(net "P3V3_STBY")
	)
	(segment
		(start 126.3142 -19.8628)
		(end 126.5682 -20.1168)
		(width 0.508)
		(layer "F.Cu")
		(net "P3V3_STBY")
	)
	(segment
		(start 40.079422 -27.570176)
		(end 40.96893 -27.570176)
		(width 0.508)
		(layer "F.Cu")
		(net "P3V3_STBY")
	)
	(segment
		(start 56.7309 -16.3703)
		(end 56.7309 -15.9004)
		(width 0.508)
		(layer "F.Cu")
		(net "P3V3_STBY")
	)
	(segment
		(start 126.5682 -20.6629)
		(end 126.619 -20.7137)
		(width 0.508)
		(layer "F.Cu")
		(net "P3V3_STBY")
	)
	(segment
		(start 21.4376 4.6863)
		(end 21.4376 4.4831)
		(width 0.4064)
		(layer "F.Cu")
		(net "P3V3_STBY")
	)
	(segment
		(start 20.7137 4.826)
		(end 21.2979 4.826)
		(width 0.4064)
		(layer "F.Cu")
		(net "P3V3_STBY")
	)
	(segment
		(start 119.1641 -10.2108)
		(end 118.1862 -10.2108)
		(width 0.508)
		(layer "F.Cu")
		(net "P3V3_STBY")
	)
	(segment
		(start 18.6436 -15.7734)
		(end 19.102578 -15.314422)
		(width 0.4064)
		(layer "F.Cu")
		(net "P3V3_STBY")
	)
	(segment
		(start 52.4764 -16.6624)
		(end 56.4388 -16.6624)
		(width 0.508)
		(layer "F.Cu")
		(net "P3V3_STBY")
	)
	(segment
		(start 20.699476 -28.043124)
		(end 20.2184 -28.5242)
		(width 0.3048)
		(layer "F.Cu")
		(net "P3V3_STBY")
	)
	(segment
		(start 40.079422 -26.680668)
		(end 40.079422 -27.570176)
		(width 0.508)
		(layer "F.Cu")
		(net "P3V3_STBY")
	)
	(segment
		(start 25.723596 9.074404)
		(end 25.723596 9.798304)
		(width 0.5588)
		(layer "F.Cu")
		(net "P3V3_STBY")
	)
	(segment
		(start 125.5395 -21.5519)
		(end 124.4092 -21.5519)
		(width 0.4064)
		(layer "F.Cu")
		(net "P3V3_STBY")
	)
	(segment
		(start 132.6515 -5.715)
		(end 133.0706 -5.715)
		(width 0.4572)
		(layer "F.Cu")
		(net "P3V3_STBY")
	)
	(segment
		(start 128.9939 -10.3759)
		(end 129.159 -10.3759)
		(width 0.4064)
		(layer "F.Cu")
		(net "P3V3_STBY")
	)
	(segment
		(start 117.747288 -21.1328)
		(end 117.391942 -21.1328)
		(width 0.4572)
		(layer "F.Cu")
		(net "P3V3_STBY")
	)
	(segment
		(start 21.4376 4.4831)
		(end 21.7424 4.1783)
		(width 0.4064)
		(layer "F.Cu")
		(net "P3V3_STBY")
	)
	(segment
		(start 118.687088 -20.193)
		(end 117.747288 -21.1328)
		(width 0.4572)
		(layer "F.Cu")
		(net "P3V3_STBY")
	)
	(segment
		(start 119.0879 -15.5956)
		(end 119.3546 -15.8623)
		(width 0.381)
		(layer "F.Cu")
		(net "P3V3_STBY")
	)
	(segment
		(start 128.1176 -11.2522)
		(end 128.9939 -10.3759)
		(width 0.4064)
		(layer "F.Cu")
		(net "P3V3_STBY")
	)
	(segment
		(start 26.2382 -23.3045)
		(end 27.1907 -23.3045)
		(width 0.508)
		(layer "F.Cu")
		(net "P3V3_STBY")
	)
	(segment
		(start 40.079422 -6.360668)
		(end 40.079422 -7.250176)
		(width 0.508)
		(layer "F.Cu")
		(net "P3V3_STBY")
	)
	(segment
		(start 117.7798 -7.0612)
		(end 118.7958 -8.0772)
		(width 0.4572)
		(layer "F.Cu")
		(net "P3V3_STBY")
	)
	(segment
		(start 20.7772 -22.4028)
		(end 20.955 -22.225)
		(width 0.508)
		(layer "F.Cu")
		(net "P3V3_STBY")
	)
	(segment
		(start 22.734524 -20.829524)
		(end 22.314662 -20.829524)
		(width 0.3048)
		(layer "F.Cu")
		(net "P3V3_STBY")
	)
	(segment
		(start 126.3777 -20.7137)
		(end 125.5395 -21.5519)
		(width 0.4064)
		(layer "F.Cu")
		(net "P3V3_STBY")
	)
	(segment
		(start 62.2427 -15.9004)
		(end 56.7309 -15.9004)
		(width 0.4572)
		(layer "F.Cu")
		(net "P3V3_STBY")
	)
	(segment
		(start 20.32 5.246624)
		(end 20.32 5.2197)
		(width 0.4064)
		(layer "F.Cu")
		(net "P3V3_STBY")
	)
	(segment
		(start 23.495 -22.5806)
		(end 23.3045 -22.3901)
		(width 0.508)
		(layer "F.Cu")
		(net "P3V3_STBY")
	)
	(segment
		(start 40.079422 -7.250176)
		(end 40.96893 -7.250176)
		(width 0.508)
		(layer "F.Cu")
		(net "P3V3_STBY")
	)
	(segment
		(start 117.391942 -21.1328)
		(end 117.277388 -21.247354)
		(width 0.4572)
		(layer "F.Cu")
		(net "P3V3_STBY")
	)
	(segment
		(start 132.0292 -22.7584)
		(end 132.0292 -22.0853)
		(width 0.4064)
		(layer "F.Cu")
		(net "P3V3_STBY")
	)
	(segment
		(start 21.2979 4.826)
		(end 21.4376 4.6863)
		(width 0.4064)
		(layer "F.Cu")
		(net "P3V3_STBY")
	)
	(segment
		(start 118.7958 -8.0772)
		(end 119.1387 -8.0772)
		(width 0.4572)
		(layer "F.Cu")
		(net "P3V3_STBY")
	)
	(segment
		(start 126.3142 -19.431)
		(end 126.3142 -19.8628)
		(width 0.508)
		(layer "F.Cu")
		(net "P3V3_STBY")
	)
	(segment
		(start 28.1686 -24.2824)
		(end 27.94 -24.0538)
		(width 0.508)
		(layer "F.Cu")
		(net "P3V3_STBY")
	)
	(segment
		(start 25.5143 -22.5806)
		(end 23.495 -22.5806)
		(width 0.508)
		(layer "F.Cu")
		(net "P3V3_STBY")
	)
	(segment
		(start 128.1176 -11.303)
		(end 128.1176 -11.2522)
		(width 0.4064)
		(layer "F.Cu")
		(net "P3V3_STBY")
	)
	(segment
		(start 116.5606 -20.7264)
		(end 116.5606 -19.4945)
		(width 0.4064)
		(layer "F.Cu")
		(net "P3V3_STBY")
	)
	(segment
		(start 132.1689 -13.589)
		(end 132.9436 -13.589)
		(width 0.4064)
		(layer "F.Cu")
		(net "P3V3_STBY")
	)
	(segment
		(start 119.3546 -15.8623)
		(end 119.3546 -16.4973)
		(width 0.381)
		(layer "F.Cu")
		(net "P3V3_STBY")
	)
	(segment
		(start 92.6211 -18.48104)
		(end 92.6211 -19.431)
		(width 0.3048)
		(layer "F.Cu")
		(net "P3V3_STBY")
	)
	(segment
		(start 126.619 -20.7137)
		(end 126.3777 -20.7137)
		(width 0.4064)
		(layer "F.Cu")
		(net "P3V3_STBY")
	)
	(segment
		(start 118.7323 -14.5542)
		(end 118.7323 -15.24)
		(width 0.4064)
		(layer "F.Cu")
		(net "P3V3_STBY")
	)
	(segment
		(start 132.1435 -14.6558)
		(end 132.1435 -13.6144)
		(width 0.4572)
		(layer "F.Cu")
		(net "P3V3_STBY")
	)
	(segment
		(start 119.1895 -10.2362)
		(end 119.1641 -10.2108)
		(width 0.4064)
		(layer "F.Cu")
		(net "P3V3_STBY")
	)
	(segment
		(start 26.9621 -27.686)
		(end 28.1686 -26.4795)
		(width 0.508)
		(layer "F.Cu")
		(net "P3V3_STBY")
	)
	(segment
		(start 118.7069 -20.193)
		(end 118.687088 -20.193)
		(width 0.4572)
		(layer "F.Cu")
		(net "P3V3_STBY")
	)
	(segment
		(start 117.162834 -21.1328)
		(end 116.967 -21.1328)
		(width 0.4064)
		(layer "F.Cu")
		(net "P3V3_STBY")
	)
	(segment
		(start 116.8146 -7.0612)
		(end 117.7798 -7.0612)
		(width 0.4572)
		(layer "F.Cu")
		(net "P3V3_STBY")
	)
	(segment
		(start 56.4388 -16.6624)
		(end 56.7309 -16.3703)
		(width 0.508)
		(layer "F.Cu")
		(net "P3V3_STBY")
	)
	(segment
		(start 23.3045 -22.3901)
		(end 23.3045 -22.3012)
		(width 0.508)
		(layer "F.Cu")
		(net "P3V3_STBY")
	)
	(segment
		(start 118.7323 -15.24)
		(end 119.0879 -15.5956)
		(width 0.4064)
		(layer "F.Cu")
		(net "P3V3_STBY")
	)
	(segment
		(start 39.189914 -27.570176)
		(end 40.079422 -27.570176)
		(width 0.508)
		(layer "F.Cu")
		(net "P3V3_STBY")
	)
	(segment
		(start 20.7772 -23.0759)
		(end 20.7772 -22.4028)
		(width 0.508)
		(layer "F.Cu")
		(net "P3V3_STBY")
	)
	(segment
		(start 26.2382 -23.3045)
		(end 25.5143 -22.5806)
		(width 0.508)
		(layer "F.Cu")
		(net "P3V3_STBY")
	)
	(segment
		(start 26.3398 8.4582)
		(end 25.723596 9.074404)
		(width 0.5588)
		(layer "F.Cu")
		(net "P3V3_STBY")
	)
	(via
		(at 27.94 -24.0538)
		(size 0.5588)
		(drill 0.3048)
		(layers "F.Cu" "B.Cu")
		(net "P3V3_STBY")
	)
	(via
		(at 112.7633 -5.5626)
		(size 0.5588)
		(drill 0.3048)
		(layers "F.Cu" "B.Cu")
		(net "P3V3_STBY")
	)
	(via
		(at 39.5224 -24.9428)
		(size 0.5588)
		(drill 0.3048)
		(layers "F.Cu" "B.Cu")
		(net "P3V3_STBY")
	)
	(via
		(at 41.7576 1.2192)
		(size 0.508)
		(drill 0.254)
		(layers "F.Cu" "B.Cu")
		(net "P3V3_STBY")
	)
	(via
		(at 113.8682 3.3782)
		(size 0.508)
		(drill 0.254)
		(layers "F.Cu" "B.Cu")
		(net "P3V3_STBY")
	)
	(via
		(at 42.3672 -13.4366)
		(size 0.5588)
		(drill 0.3048)
		(layers "F.Cu" "B.Cu")
		(net "P3V3_STBY")
	)
	(via
		(at 131.8641 -14.0843)
		(size 0.7112)
		(drill 0.3556)
		(layers "F.Cu" "B.Cu")
		(net "P3V3_STBY")
	)
	(via
		(at 103.0478 0.8382)
		(size 0.508)
		(drill 0.254)
		(layers "F.Cu" "B.Cu")
		(net "P3V3_STBY")
	)
	(via
		(at 120.47728 -7.0866)
		(size 0.7112)
		(drill 0.3556)
		(layers "F.Cu" "B.Cu")
		(net "P3V3_STBY")
	)
	(via
		(at 116.6114 -7.2644)
		(size 0.508)
		(drill 0.254)
		(layers "F.Cu" "B.Cu")
		(net "P3V3_STBY")
	)
	(via
		(at 42.9006 -5.0673)
		(size 0.5588)
		(drill 0.3048)
		(layers "F.Cu" "B.Cu")
		(net "P3V3_STBY")
	)
	(via
		(at 111.8235 -5.3721)
		(size 0.5588)
		(drill 0.3048)
		(layers "F.Cu" "B.Cu")
		(net "P3V3_STBY")
	)
	(via
		(at 116.8908 -8.9154)
		(size 0.508)
		(drill 0.254)
		(layers "F.Cu" "B.Cu")
		(net "P3V3_STBY")
	)
	(via
		(at 20.32 5.246624)
		(size 0.508)
		(drill 0.254)
		(layers "F.Cu" "B.Cu")
		(net "P3V3_STBY")
	)
	(via
		(at 42.3418 -5.842)
		(size 0.5588)
		(drill 0.3048)
		(layers "F.Cu" "B.Cu")
		(net "P3V3_STBY")
	)
	(via
		(at 121.92 -10.668)
		(size 0.508)
		(drill 0.254)
		(layers "F.Cu" "B.Cu")
		(net "P3V3_STBY")
	)
	(via
		(at 125.6284 -12.9286)
		(size 0.508)
		(drill 0.254)
		(layers "F.Cu" "B.Cu")
		(net "P3V3_STBY")
	)
	(via
		(at 32.7152 5.6134)
		(size 0.5588)
		(drill 0.3048)
		(layers "F.Cu" "B.Cu")
		(net "P3V3_STBY")
	)
	(via
		(at 132.6388 -9.5758)
		(size 0.508)
		(drill 0.254)
		(layers "F.Cu" "B.Cu")
		(net "P3V3_STBY")
	)
	(via
		(at 26.3398 8.4582)
		(size 0.5588)
		(drill 0.3048)
		(layers "F.Cu" "B.Cu")
		(net "P3V3_STBY")
	)
	(via
		(at 132.0292 -22.7584)
		(size 0.508)
		(drill 0.254)
		(layers "F.Cu" "B.Cu")
		(net "P3V3_STBY")
	)
	(via
		(at 131.0894 0.889)
		(size 0.508)
		(drill 0.254)
		(layers "F.Cu" "B.Cu")
		(net "P3V3_STBY")
	)
	(via
		(at 133.5278 -5.9182)
		(size 0.508)
		(drill 0.254)
		(layers "F.Cu" "B.Cu")
		(net "P3V3_STBY")
	)
	(via
		(at 20.2184 -28.5242)
		(size 0.508)
		(drill 0.254)
		(layers "F.Cu" "B.Cu")
		(net "P3V3_STBY")
	)
	(via
		(at 18.6436 -15.8242)
		(size 0.508)
		(drill 0.254)
		(layers "F.Cu" "B.Cu")
		(net "P3V3_STBY")
	)
	(via
		(at 118.7196 -16.7132)
		(size 0.508)
		(drill 0.254)
		(layers "F.Cu" "B.Cu")
		(net "P3V3_STBY")
	)
	(via
		(at 132.9436 -18.8214)
		(size 0.508)
		(drill 0.254)
		(layers "F.Cu" "B.Cu")
		(net "P3V3_STBY")
	)
	(via
		(at 33.274 3.4798)
		(size 0.7112)
		(drill 0.3556)
		(layers "F.Cu" "B.Cu")
		(net "P3V3_STBY")
	)
	(via
		(at 115.7478 3.3782)
		(size 0.7112)
		(drill 0.3556)
		(layers "F.Cu" "B.Cu")
		(net "P3V3_STBY")
	)
	(via
		(at 52.0446 -16.2306)
		(size 0.508)
		(drill 0.254)
		(layers "F.Cu" "B.Cu")
		(net "P3V3_STBY")
	)
	(via
		(at 117.277388 -21.247354)
		(size 0.508)
		(drill 0.254)
		(layers "F.Cu" "B.Cu")
		(net "P3V3_STBY")
	)
	(via
		(at 100.4824 2.8956)
		(size 0.508)
		(drill 0.254)
		(layers "F.Cu" "B.Cu")
		(net "P3V3_STBY")
	)
	(via
		(at 100.9269 -1.524)
		(size 0.508)
		(drill 0.254)
		(layers "F.Cu" "B.Cu")
		(net "P3V3_STBY")
	)
	(via
		(at 25.723596 9.074404)
		(size 0.508)
		(drill 0.254)
		(layers "F.Cu" "B.Cu")
		(net "P3V3_STBY")
	)
	(via
		(at 128.1176 -11.303)
		(size 0.508)
		(drill 0.254)
		(layers "F.Cu" "B.Cu")
		(net "P3V3_STBY")
	)
	(via
		(at 24.3078 -15.2908)
		(size 0.508)
		(drill 0.254)
		(layers "F.Cu" "B.Cu")
		(net "P3V3_STBY")
	)
	(via
		(at 20.6502 -16.002)
		(size 0.7112)
		(drill 0.3556)
		(layers "F.Cu" "B.Cu")
		(net "P3V3_STBY")
	)
	(via
		(at 123.403106 1.107694)
		(size 0.508)
		(drill 0.254)
		(layers "F.Cu" "B.Cu")
		(net "P3V3_STBY")
	)
	(via
		(at 125.984 -4.5212)
		(size 0.508)
		(drill 0.254)
		(layers "F.Cu" "B.Cu")
		(net "P3V3_STBY")
	)
	(via
		(at 126.1872 -19.304)
		(size 0.508)
		(drill 0.254)
		(layers "F.Cu" "B.Cu")
		(net "P3V3_STBY")
	)
	(via
		(at 42.4942 -14.4018)
		(size 0.5588)
		(drill 0.3048)
		(layers "F.Cu" "B.Cu")
		(net "P3V3_STBY")
	)
	(via
		(at 131.7498 -1.8796)
		(size 0.508)
		(drill 0.254)
		(layers "F.Cu" "B.Cu")
		(net "P3V3_STBY")
	)
	(via
		(at 131.7752 -9.6774)
		(size 0.508)
		(drill 0.254)
		(layers "F.Cu" "B.Cu")
		(net "P3V3_STBY")
	)
	(via
		(at 116.3574 -0.5334)
		(size 0.508)
		(drill 0.254)
		(layers "F.Cu" "B.Cu")
		(net "P3V3_STBY")
	)
	(via
		(at 20.955 -22.225)
		(size 0.508)
		(drill 0.254)
		(layers "F.Cu" "B.Cu")
		(net "P3V3_STBY")
	)
	(via
		(at 132.9436 -13.589)
		(size 0.508)
		(drill 0.254)
		(layers "F.Cu" "B.Cu")
		(net "P3V3_STBY")
	)
	(via
		(at 113.665 -4.9784)
		(size 0.508)
		(drill 0.254)
		(layers "F.Cu" "B.Cu")
		(net "P3V3_STBY")
	)
	(via
		(at 32.7787 4.7498)
		(size 0.5588)
		(drill 0.3048)
		(layers "F.Cu" "B.Cu")
		(net "P3V3_STBY")
	)
	(via
		(at 132.969 -11.4808)
		(size 0.508)
		(drill 0.254)
		(layers "F.Cu" "B.Cu")
		(net "P3V3_STBY")
	)
	(via
		(at 117.7798 -4.1148)
		(size 0.508)
		(drill 0.254)
		(layers "F.Cu" "B.Cu")
		(net "P3V3_STBY")
	)
	(segment
		(start 30.099 -21.840444)
		(end 29.8831 -22.056344)
		(width 0.7366)
		(layer "B.Cu")
		(net "P3V3_STBY")
	)
	(segment
		(start 18.8214 -16.002)
		(end 20.6502 -16.002)
		(width 0.508)
		(layer "B.Cu")
		(net "P3V3_STBY")
	)
	(segment
		(start 103.0478 0.8382)
		(end 102.997 0.8382)
		(width 0.4064)
		(layer "B.Cu")
		(net "P3V3_STBY")
	)
	(segment
		(start 39.1668 0.5207)
		(end 38.9509 0.3048)
		(width 0.508)
		(layer "B.Cu")
		(net "P3V3_STBY")
	)
	(segment
		(start 120.47728 -4.68122)
		(end 120.47728 -7.0866)
		(width 0.4064)
		(layer "B.Cu")
		(net "P3V3_STBY")
	)
	(segment
		(start 20.6502 -16.002)
		(end 21.1836 -16.5354)
		(width 0.508)
		(layer "B.Cu")
		(net "P3V3_STBY")
	)
	(segment
		(start 121.1961 -9.8933)
		(end 121.5263 -9.8933)
		(width 0.4064)
		(layer "B.Cu")
		(net "P3V3_STBY")
	)
	(segment
		(start 20.955 -22.4028)
		(end 20.699476 -22.658324)
		(width 0.3048)
		(layer "B.Cu")
		(net "P3V3_STBY")
	)
	(segment
		(start 121.92 -10.668)
		(end 121.8692 -10.668)
		(width 0.508)
		(layer "B.Cu")
		(net "P3V3_STBY")
	)
	(segment
		(start 20.699476 -22.658324)
		(end 20.699476 -23.151338)
		(width 0.3048)
		(layer "B.Cu")
		(net "P3V3_STBY")
	)
	(segment
		(start 24.3078 -15.494)
		(end 24.3078 -15.2908)
		(width 0.508)
		(layer "B.Cu")
		(net "P3V3_STBY")
	)
	(segment
		(start 124.3838 0.3429)
		(end 124.1679 0.3429)
		(width 0.4064)
		(layer "B.Cu")
		(net "P3V3_STBY")
	)
	(segment
		(start 33.909 0.3048)
		(end 35.5219 0.3048)
		(width 0.508)
		(layer "B.Cu")
		(net "P3V3_STBY")
	)
	(segment
		(start 126.1872 -19.304)
		(end 126.3142 -19.177)
		(width 0.508)
		(layer "B.Cu")
		(net "P3V3_STBY")
	)
	(segment
		(start 126.59106 -18.39976)
		(end 126.6317 -18.4404)
		(width 0.3048)
		(layer "B.Cu")
		(net "P3V3_STBY")
	)
	(segment
		(start 41.7576 1.2192)
		(end 41.7322 1.1938)
		(width 0.508)
		(layer "B.Cu")
		(net "P3V3_STBY")
	)
	(segment
		(start 100.9269 -1.524)
		(end 100.9269 -1.651)
		(width 0.4064)
		(layer "B.Cu")
		(net "P3V3_STBY")
	)
	(segment
		(start 100.9269 -1.651)
		(end 101.8032 -2.5273)
		(width 0.4064)
		(layer "B.Cu")
		(net "P3V3_STBY")
	)
	(segment
		(start 126.59106 -16.90116)
		(end 126.59106 -18.39976)
		(width 0.3048)
		(layer "B.Cu")
		(net "P3V3_STBY")
	)
	(segment
		(start 105.0544 2.9337)
		(end 104.450896 2.9337)
		(width 0.4064)
		(layer "B.Cu")
		(net "P3V3_STBY")
	)
	(segment
		(start 126.3142 -19.177)
		(end 126.3142 -18.7579)
		(width 0.508)
		(layer "B.Cu")
		(net "P3V3_STBY")
	)
	(segment
		(start 120.47728 -7.0866)
		(end 120.47728 -9.17448)
		(width 0.4064)
		(layer "B.Cu")
		(net "P3V3_STBY")
	)
	(segment
		(start 100.5586 2.8956)
		(end 101.0666 3.4036)
		(width 0.4572)
		(layer "B.Cu")
		(net "P3V3_STBY")
	)
	(segment
		(start 125.6284 -12.1539)
		(end 124.587 -12.1539)
		(width 0.4572)
		(layer "B.Cu")
		(net "P3V3_STBY")
	)
	(segment
		(start 35.5219 0.3048)
		(end 35.5346 0.2921)
		(width 0.508)
		(layer "B.Cu")
		(net "P3V3_STBY")
	)
	(segment
		(start 113.72342 -4.91998)
		(end 113.665 -4.9784)
		(width 0.4064)
		(layer "B.Cu")
		(net "P3V3_STBY")
	)
	(segment
		(start 131.318 0.6604)
		(end 131.0894 0.889)
		(width 0.4572)
		(layer "B.Cu")
		(net "P3V3_STBY")
	)
	(segment
		(start 38.9509 0.3048)
		(end 38.4048 0.3048)
		(width 0.508)
		(layer "B.Cu")
		(net "P3V3_STBY")
	)
	(segment
		(start 24.3078 -15.2908)
		(end 24.4348 -15.2908)
		(width 0.7366)
		(layer "B.Cu")
		(net "P3V3_STBY")
	)
	(segment
		(start 117.4496 2.0701)
		(end 117.4496 2.1463)
		(width 0.4572)
		(layer "B.Cu")
		(net "P3V3_STBY")
	)
	(segment
		(start 125.6284 -12.1539)
		(end 125.6284 -12.9286)
		(width 0.4064)
		(layer "B.Cu")
		(net "P3V3_STBY")
	)
	(segment
		(start 24.4348 -15.2908)
		(end 25.2222 -16.0782)
		(width 0.7366)
		(layer "B.Cu")
		(net "P3V3_STBY")
	)
	(segment
		(start 123.2916 -4.6482)
		(end 123.2916 -3.3655)
		(width 0.508)
		(layer "B.Cu")
		(net "P3V3_STBY")
	)
	(segment
		(start 102.997 0.8382)
		(end 102.7811 0.6223)
		(width 0.4064)
		(layer "B.Cu")
		(net "P3V3_STBY")
	)
	(segment
		(start 28.1686 -16.0782)
		(end 30.099 -18.0086)
		(width 0.7366)
		(layer "B.Cu")
		(net "P3V3_STBY")
	)
	(segment
		(start 23.2664 -16.5354)
		(end 24.3078 -15.494)
		(width 0.508)
		(layer "B.Cu")
		(net "P3V3_STBY")
	)
	(segment
		(start 27.940254 -24.054054)
		(end 27.94 -24.0538)
		(width 0.7366)
		(layer "B.Cu")
		(net "P3V3_STBY")
	)
	(segment
		(start 20.955 -27.8511)
		(end 20.8915 -27.8511)
		(width 0.508)
		(layer "B.Cu")
		(net "P3V3_STBY")
	)
	(segment
		(start 102.2477 3.4036)
		(end 102.2604 3.4163)
		(width 0.4572)
		(layer "B.Cu")
		(net "P3V3_STBY")
	)
	(segment
		(start 115.054634 -3.09118)
		(end 113.72342 -4.422394)
		(width 0.4064)
		(layer "B.Cu")
		(net "P3V3_STBY")
	)
	(segment
		(start 40.079422 -12.139422)
		(end 40.079422 -7.250176)
		(width 0.4064)
		(layer "B.Cu")
		(net "P3V3_STBY")
	)
	(segment
		(start 124.52096 -3.175)
		(end 123.4821 -3.175)
		(width 0.3048)
		(layer "B.Cu")
		(net "P3V3_STBY")
	)
	(segment
		(start 127.8763 -10.5664)
		(end 128.0033 -10.4394)
		(width 0.4572)
		(layer "B.Cu")
		(net "P3V3_STBY")
	)
	(segment
		(start 116.3574 -0.5588)
		(end 116.5733 -0.7747)
		(width 0.4572)
		(layer "B.Cu")
		(net "P3V3_STBY")
	)
	(segment
		(start 115.54968 -3.09118)
		(end 115.054634 -3.09118)
		(width 0.4064)
		(layer "B.Cu")
		(net "P3V3_STBY")
	)
	(segment
		(start 113.46688 2.97688)
		(end 113.8682 3.3782)
		(width 0.3556)
		(layer "B.Cu")
		(net "P3V3_STBY")
	)
	(segment
		(start 128.2827 0.7747)
		(end 129.3749 0.7747)
		(width 0.4572)
		(layer "B.Cu")
		(net "P3V3_STBY")
	)
	(segment
		(start 33.2867 0.9271)
		(end 33.909 0.3048)
		(width 0.508)
		(layer "B.Cu")
		(net "P3V3_STBY")
	)
	(segment
		(start 38.72484 1.92024)
		(end 39.20236 1.92024)
		(width 0.3556)
		(layer "B.Cu")
		(net "P3V3_STBY")
	)
	(segment
		(start 116.2177 3.3782)
		(end 115.7478 3.3782)
		(width 0.4572)
		(layer "B.Cu")
		(net "P3V3_STBY")
	)
	(segment
		(start 131.318 -0.0254)
		(end 131.318 0.6604)
		(width 0.4572)
		(layer "B.Cu")
		(net "P3V3_STBY")
	)
	(segment
		(start 113.72342 -4.422394)
		(end 113.72342 -4.91998)
		(width 0.4064)
		(layer "B.Cu")
		(net "P3V3_STBY")
	)
	(segment
		(start 101.8032 -2.5273)
		(end 103.886 -2.5273)
		(width 0.4064)
		(layer "B.Cu")
		(net "P3V3_STBY")
	)
	(segment
		(start 103.321104 0.8382)
		(end 103.0478 0.8382)
		(width 0.4064)
		(layer "B.Cu")
		(net "P3V3_STBY")
	)
	(segment
		(start 117.6401 -3.9751)
		(end 117.6401 -3.8481)
		(width 0.3048)
		(layer "B.Cu")
		(net "P3V3_STBY")
	)
	(segment
		(start 121.6025 -9.9695)
		(end 121.5263 -9.8933)
		(width 0.4064)
		(layer "B.Cu")
		(net "P3V3_STBY")
	)
	(segment
		(start 25.2222 -16.0782)
		(end 28.1686 -16.0782)
		(width 0.7366)
		(layer "B.Cu")
		(net "P3V3_STBY")
	)
	(segment
		(start 102.7811 0.6223)
		(end 102.2604 0.6223)
		(width 0.4064)
		(layer "B.Cu")
		(net "P3V3_STBY")
	)
	(segment
		(start 100.4824 2.8956)
		(end 100.5586 2.8956)
		(width 0.4572)
		(layer "B.Cu")
		(net "P3V3_STBY")
	)
	(segment
		(start 128.1176 -11.303)
		(end 127.8763 -11.0617)
		(width 0.4572)
		(layer "B.Cu")
		(net "P3V3_STBY")
	)
	(segment
		(start 116.5733 -0.7747)
		(end 117.4496 -0.7747)
		(width 0.4572)
		(layer "B.Cu")
		(net "P3V3_STBY")
	)
	(segment
		(start 115.7478 3.3782)
		(end 113.8682 3.3782)
		(width 0.4572)
		(layer "B.Cu")
		(net "P3V3_STBY")
	)
	(segment
		(start 26.3398 -25.1333)
		(end 26.3652 -25.1587)
		(width 0.4064)
		(layer "B.Cu")
		(net "P3V3_STBY")
	)
	(segment
		(start 38.4302 1.6256)
		(end 38.72484 1.92024)
		(width 0.3556)
		(layer "B.Cu")
		(net "P3V3_STBY")
	)
	(segment
		(start 127.8763 -11.0617)
		(end 127.8763 -10.5664)
		(width 0.4572)
		(layer "B.Cu")
		(net "P3V3_STBY")
	)
	(segment
		(start 41.7322 1.1938)
		(end 41.7068 1.1938)
		(width 0.508)
		(layer "B.Cu")
		(net "P3V3_STBY")
	)
	(segment
		(start 29.8831 -22.056344)
		(end 29.8831 -22.458426)
		(width 0.7366)
		(layer "B.Cu")
		(net "P3V3_STBY")
	)
	(segment
		(start 116.3574 -0.5334)
		(end 116.3574 -0.5588)
		(width 0.4572)
		(layer "B.Cu")
		(net "P3V3_STBY")
	)
	(segment
		(start 117.7925 -1.91262)
		(end 117.7925 -1.1176)
		(width 0.508)
		(layer "B.Cu")
		(net "P3V3_STBY")
	)
	(segment
		(start 121.6025 -10.4013)
		(end 121.6025 -9.9695)
		(width 0.508)
		(layer "B.Cu")
		(net "P3V3_STBY")
	)
	(segment
		(start 104.450896 2.9337)
		(end 103.968296 3.4163)
		(width 0.4064)
		(layer "B.Cu")
		(net "P3V3_STBY")
	)
	(segment
		(start 18.6436 -15.8242)
		(end 18.8214 -16.002)
		(width 0.508)
		(layer "B.Cu")
		(net "P3V3_STBY")
	)
	(segment
		(start 117.7798 -4.1148)
		(end 117.6401 -3.9751)
		(width 0.3048)
		(layer "B.Cu")
		(net "P3V3_STBY")
	)
	(segment
		(start 28.287472 -24.054054)
		(end 27.940254 -24.054054)
		(width 0.7366)
		(layer "B.Cu")
		(net "P3V3_STBY")
	)
	(segment
		(start 129.3749 0.7747)
		(end 130.9751 0.7747)
		(width 0.4572)
		(layer "B.Cu")
		(net "P3V3_STBY")
	)
	(segment
		(start 120.47728 -9.17448)
		(end 121.1961 -9.8933)
		(width 0.4064)
		(layer "B.Cu")
		(net "P3V3_STBY")
	)
	(segment
		(start 117.6401 -3.8481)
		(end 116.85524 -3.06324)
		(width 0.3048)
		(layer "B.Cu")
		(net "P3V3_STBY")
	)
	(segment
		(start 121.8692 -10.668)
		(end 121.6025 -10.4013)
		(width 0.508)
		(layer "B.Cu")
		(net "P3V3_STBY")
	)
	(segment
		(start 38.4048 0.3048)
		(end 38.4302 0.3302)
		(width 0.3556)
		(layer "B.Cu")
		(net "P3V3_STBY")
	)
	(segment
		(start 124.1679 0.3429)
		(end 123.403106 1.107694)
		(width 0.4064)
		(layer "B.Cu")
		(net "P3V3_STBY")
	)
	(segment
		(start 21.1836 -16.5354)
		(end 23.2664 -16.5354)
		(width 0.508)
		(layer "B.Cu")
		(net "P3V3_STBY")
	)
	(segment
		(start 123.4821 -3.175)
		(end 123.2916 -3.3655)
		(width 0.3048)
		(layer "B.Cu")
		(net "P3V3_STBY")
	)
	(segment
		(start 27.9019 -24.0919)
		(end 27.94 -24.0538)
		(width 0.4064)
		(layer "B.Cu")
		(net "P3V3_STBY")
	)
	(segment
		(start 41.0337 0.5207)
		(end 39.1668 0.5207)
		(width 0.508)
		(layer "B.Cu")
		(net "P3V3_STBY")
	)
	(segment
		(start 26.3652 -24.0919)
		(end 27.9019 -24.0919)
		(width 0.4064)
		(layer "B.Cu")
		(net "P3V3_STBY")
	)
	(segment
		(start 41.7068 1.1938)
		(end 41.0337 0.5207)
		(width 0.508)
		(layer "B.Cu")
		(net "P3V3_STBY")
	)
	(segment
		(start 101.0666 3.4036)
		(end 102.2477 3.4036)
		(width 0.4572)
		(layer "B.Cu")
		(net "P3V3_STBY")
	)
	(segment
		(start 29.8831 -22.458426)
		(end 28.287472 -24.054054)
		(width 0.7366)
		(layer "B.Cu")
		(net "P3V3_STBY")
	)
	(segment
		(start 117.7925 -1.1176)
		(end 117.4496 -0.7747)
		(width 0.508)
		(layer "B.Cu")
		(net "P3V3_STBY")
	)
	(segment
		(start 125.984 -4.5212)
		(end 125.8189 -4.6863)
		(width 0.4572)
		(layer "B.Cu")
		(net "P3V3_STBY")
	)
	(segment
		(start 125.8189 -4.6863)
		(end 123.2535 -4.6863)
		(width 0.4572)
		(layer "B.Cu")
		(net "P3V3_STBY")
	)
	(segment
		(start 103.886 0.2667)
		(end 103.886 0.273304)
		(width 0.4064)
		(layer "B.Cu")
		(net "P3V3_STBY")
	)
	(segment
		(start 33.64484 1.92024)
		(end 35.09264 1.92024)
		(width 0.3048)
		(layer "B.Cu")
		(net "P3V3_STBY")
	)
	(segment
		(start 123.2535 -4.6863)
		(end 123.2916 -4.6482)
		(width 0.508)
		(layer "B.Cu")
		(net "P3V3_STBY")
	)
	(segment
		(start 33.6296 1.905)
		(end 33.64484 1.92024)
		(width 0.3048)
		(layer "B.Cu")
		(net "P3V3_STBY")
	)
	(segment
		(start 103.886 0.273304)
		(end 103.321104 0.8382)
		(width 0.4064)
		(layer "B.Cu")
		(net "P3V3_STBY")
	)
	(segment
		(start 26.3652 -24.0919)
		(end 26.3398 -24.1173)
		(width 0.4064)
		(layer "B.Cu")
		(net "P3V3_STBY")
	)
	(segment
		(start 33.2867 1.1557)
		(end 33.2867 0.9271)
		(width 0.508)
		(layer "B.Cu")
		(net "P3V3_STBY")
	)
	(segment
		(start 20.955 -22.225)
		(end 20.955 -22.4028)
		(width 0.3048)
		(layer "B.Cu")
		(net "P3V3_STBY")
	)
	(segment
		(start 126.3142 -18.7579)
		(end 126.6317 -18.4404)
		(width 0.508)
		(layer "B.Cu")
		(net "P3V3_STBY")
	)
	(segment
		(start 42.3672 -13.4366)
		(end 42.3418 -13.4112)
		(width 0.4064)
		(layer "B.Cu")
		(net "P3V3_STBY")
	)
	(segment
		(start 117.4496 2.1463)
		(end 116.2177 3.3782)
		(width 0.4572)
		(layer "B.Cu")
		(net "P3V3_STBY")
	)
	(segment
		(start 41.3512 -13.4112)
		(end 40.079422 -12.139422)
		(width 0.4064)
		(layer "B.Cu")
		(net "P3V3_STBY")
	)
	(segment
		(start 20.8915 -27.8511)
		(end 20.2184 -28.5242)
		(width 0.508)
		(layer "B.Cu")
		(net "P3V3_STBY")
	)
	(segment
		(start 30.099 -18.0086)
		(end 30.099 -21.840444)
		(width 0.7366)
		(layer "B.Cu")
		(net "P3V3_STBY")
	)
	(segment
		(start 116.85524 -3.06324)
		(end 116.60124 -3.06324)
		(width 0.3048)
		(layer "B.Cu")
		(net "P3V3_STBY")
	)
	(segment
		(start 26.3398 -24.1173)
		(end 26.3398 -25.1333)
		(width 0.4064)
		(layer "B.Cu")
		(net "P3V3_STBY")
	)
	(segment
		(start 38.4302 0.3302)
		(end 38.4302 1.6256)
		(width 0.3556)
		(layer "B.Cu")
		(net "P3V3_STBY")
	)
	(segment
		(start 103.968296 3.4163)
		(end 102.2604 3.4163)
		(width 0.4064)
		(layer "B.Cu")
		(net "P3V3_STBY")
	)
	(segment
		(start 42.3418 -13.4112)
		(end 41.3512 -13.4112)
		(width 0.4064)
		(layer "B.Cu")
		(net "P3V3_STBY")
	)
	(segment
		(start 130.9751 0.7747)
		(end 131.0894 0.889)
		(width 0.4572)
		(layer "B.Cu")
		(net "P3V3_STBY")
	)
	(segment
		(start 112.4966 2.97688)
		(end 113.46688 2.97688)
		(width 0.3556)
		(layer "B.Cu")
		(net "P3V3_STBY")
	)
	(segment
		(start 21.320252 5.902452)
		(end 21.320252 8.712454)
		(width 0.4064)
		(layer "In2.Cu")
		(net "P3V3_STBY")
	)
	(segment
		(start 117.589046 -21.247354)
		(end 117.277388 -21.247354)
		(width 0.4572)
		(layer "In2.Cu")
		(net "P3V3_STBY")
	)
	(segment
		(start 20.7264 5.3086)
		(end 21.320252 5.902452)
		(width 0.4064)
		(layer "In2.Cu")
		(net "P3V3_STBY")
	)
	(segment
		(start 118.5672 -16.8656)
		(end 118.5672 -20.2692)
		(width 0.4572)
		(layer "In2.Cu")
		(net "P3V3_STBY")
	)
	(segment
		(start 131.6355 -1.9939)
		(end 131.6355 -4.0259)
		(width 0.4572)
		(layer "In2.Cu")
		(net "P3V3_STBY")
	)
	(segment
		(start 24.8412 9.9568)
		(end 25.723596 9.074404)
		(width 0.4064)
		(layer "In2.Cu")
		(net "P3V3_STBY")
	)
	(segment
		(start 20.32 5.246624)
		(end 20.381976 5.3086)
		(width 0.4064)
		(layer "In2.Cu")
		(net "P3V3_STBY")
	)
	(segment
		(start 22.564598 9.9568)
		(end 24.8412 9.9568)
		(width 0.4064)
		(layer "In2.Cu")
		(net "P3V3_STBY")
	)
	(segment
		(start 21.320252 8.712454)
		(end 22.564598 9.9568)
		(width 0.4064)
		(layer "In2.Cu")
		(net "P3V3_STBY")
	)
	(segment
		(start 118.5672 -20.2692)
		(end 117.589046 -21.247354)
		(width 0.4572)
		(layer "In2.Cu")
		(net "P3V3_STBY")
	)
	(segment
		(start 50.8 -14.986)
		(end 43.0784 -14.986)
		(width 0.508)
		(layer "In2.Cu")
		(net "P3V3_STBY")
	)
	(segment
		(start 52.0446 -16.2306)
		(end 50.8 -14.986)
		(width 0.508)
		(layer "In2.Cu")
		(net "P3V3_STBY")
	)
	(segment
		(start 118.7196 -16.7132)
		(end 118.5672 -16.8656)
		(width 0.4572)
		(layer "In2.Cu")
		(net "P3V3_STBY")
	)
	(segment
		(start 20.381976 5.3086)
		(end 20.7264 5.3086)
		(width 0.4064)
		(layer "In2.Cu")
		(net "P3V3_STBY")
	)
	(segment
		(start 131.7498 -1.8796)
		(end 131.6355 -1.9939)
		(width 0.4572)
		(layer "In2.Cu")
		(net "P3V3_STBY")
	)
	(segment
		(start 43.0784 -14.986)
		(end 42.4942 -14.4018)
		(width 0.508)
		(layer "In2.Cu")
		(net "P3V3_STBY")
	)
	(segment
		(start 131.6355 -4.0259)
		(end 133.5278 -5.9182)
		(width 0.4572)
		(layer "In2.Cu")
		(net "P3V3_STBY")
	)
	(segment
		(start 28.2575 -24.0538)
		(end 29.0322 -23.2791)
		(width 1.016)
		(layer "In3.Cu")
		(net "P3V3_STBY")
	)
	(segment
		(start 20.6248 -28.1178)
		(end 20.6248 -22.733)
		(width 0.508)
		(layer "In3.Cu")
		(net "P3V3_STBY")
	)
	(segment
		(start 40.079422 -7.250176)
		(end 40.96893 -7.250176)
		(width 0.508)
		(layer "In3.Cu")
		(net "P3V3_STBY")
	)
	(segment
		(start 125.2728 -0.1524)
		(end 124.012706 1.107694)
		(width 0.508)
		(layer "In3.Cu")
		(net "P3V3_STBY")
	)
	(segment
		(start 29.0322 -23.2791)
		(end 29.0322 -22.5044)
		(width 1.016)
		(layer "In3.Cu")
		(net "P3V3_STBY")
	)
	(segment
		(start 125.984 -4.5212)
		(end 125.2728 -3.81)
		(width 0.508)
		(layer "In3.Cu")
		(net "P3V3_STBY")
	)
	(segment
		(start 20.6248 -22.733)
		(end 20.955 -22.4028)
		(width 0.508)
		(layer "In3.Cu")
		(net "P3V3_STBY")
	)
	(segment
		(start 20.955 -22.4028)
		(end 20.955 -22.225)
		(width 0.508)
		(layer "In3.Cu")
		(net "P3V3_STBY")
	)
	(segment
		(start 125.4252 -13.1318)
		(end 124.302774 -13.1318)
		(width 0.508)
		(layer "In3.Cu")
		(net "P3V3_STBY")
	)
	(segment
		(start 20.2184 -28.5242)
		(end 20.6248 -28.1178)
		(width 0.508)
		(layer "In3.Cu")
		(net "P3V3_STBY")
	)
	(segment
		(start 21.2598 -22.5298)
		(end 20.955 -22.225)
		(width 0.508)
		(layer "In3.Cu")
		(net "P3V3_STBY")
	)
	(segment
		(start 23.4442 -22.5298)
		(end 21.2598 -22.5298)
		(width 0.508)
		(layer "In3.Cu")
		(net "P3V3_STBY")
	)
	(segment
		(start 29.0322 -22.5044)
		(end 31.0007 -20.5359)
		(width 1.016)
		(layer "In3.Cu")
		(net "P3V3_STBY")
	)
	(segment
		(start 27.94 -24.0538)
		(end 28.2575 -24.0538)
		(width 1.016)
		(layer "In3.Cu")
		(net "P3V3_STBY")
	)
	(segment
		(start 40.079422 -7.250176)
		(end 40.079422 -8.139684)
		(width 0.508)
		(layer "In3.Cu")
		(net "P3V3_STBY")
	)
	(segment
		(start 126.3396 -19.304)
		(end 126.5301 -19.1135)
		(width 0.4572)
		(layer "In3.Cu")
		(net "P3V3_STBY")
	)
	(segment
		(start 125.6284 -12.9286)
		(end 125.4252 -13.1318)
		(width 0.508)
		(layer "In3.Cu")
		(net "P3V3_STBY")
	)
	(segment
		(start 31.0007 -20.5359)
		(end 35.1155 -20.5359)
		(width 1.016)
		(layer "In3.Cu")
		(net "P3V3_STBY")
	)
	(segment
		(start 27.94 -24.0538)
		(end 27.5844 -23.6982)
		(width 0.508)
		(layer "In3.Cu")
		(net "P3V3_STBY")
	)
	(segment
		(start 126.5301 -19.1135)
		(end 129.978658 -19.1135)
		(width 0.4572)
		(layer "In3.Cu")
		(net "P3V3_STBY")
	)
	(segment
		(start 125.2728 -3.81)
		(end 125.2728 -0.1524)
		(width 0.508)
		(layer "In3.Cu")
		(net "P3V3_STBY")
	)
	(segment
		(start 40.079422 -6.360668)
		(end 40.079422 -7.250176)
		(width 0.508)
		(layer "In3.Cu")
		(net "P3V3_STBY")
	)
	(segment
		(start 27.5844 -23.6982)
		(end 24.6126 -23.6982)
		(width 0.508)
		(layer "In3.Cu")
		(net "P3V3_STBY")
	)
	(segment
		(start 124.012706 1.107694)
		(end 123.403106 1.107694)
		(width 0.508)
		(layer "In3.Cu")
		(net "P3V3_STBY")
	)
	(segment
		(start 129.978658 -19.1135)
		(end 130.270758 -18.8214)
		(width 0.4572)
		(layer "In3.Cu")
		(net "P3V3_STBY")
	)
	(segment
		(start 124.302774 -13.1318)
		(end 120.721374 -16.7132)
		(width 0.508)
		(layer "In3.Cu")
		(net "P3V3_STBY")
	)
	(segment
		(start 24.6126 -23.6982)
		(end 23.4442 -22.5298)
		(width 0.508)
		(layer "In3.Cu")
		(net "P3V3_STBY")
	)
	(segment
		(start 120.721374 -16.7132)
		(end 118.7196 -16.7132)
		(width 0.508)
		(layer "In3.Cu")
		(net "P3V3_STBY")
	)
	(segment
		(start 126.1872 -19.304)
		(end 126.3396 -19.304)
		(width 0.4572)
		(layer "In3.Cu")
		(net "P3V3_STBY")
	)
	(segment
		(start 130.270758 -18.8214)
		(end 132.9436 -18.8214)
		(width 0.4572)
		(layer "In3.Cu")
		(net "P3V3_STBY")
	)
	(segment
		(start 35.1155 -20.5359)
		(end 39.5224 -24.9428)
		(width 1.016)
		(layer "In3.Cu")
		(net "P3V3_STBY")
	)
	(segment
		(start 39.189914 -7.250176)
		(end 40.079422 -7.250176)
		(width 0.508)
		(layer "In3.Cu")
		(net "P3V3_STBY")
	)
	(segment
		(start 101.219 -24.5364)
		(end 101.1936 -24.5618)
		(width 0.4572)
		(layer "F.Cu")
		(net "P3V3")
	)
	(segment
		(start 38.080442 -7.250176)
		(end 38.96995 -7.250176)
		(width 0.508)
		(layer "F.Cu")
		(net "P3V3")
	)
	(segment
		(start 38.080442 -7.250176)
		(end 38.080442 -8.139684)
		(width 0.508)
		(layer "F.Cu")
		(net "P3V3")
	)
	(segment
		(start 39.079932 -10.860278)
		(end 39.079932 -11.749786)
		(width 0.508)
		(layer "F.Cu")
		(net "P3V3")
	)
	(segment
		(start 38.190424 -11.749786)
		(end 39.079932 -11.749786)
		(width 0.508)
		(layer "F.Cu")
		(net "P3V3")
	)
	(segment
		(start 40.079422 -12.860528)
		(end 40.079422 -13.750036)
		(width 0.508)
		(layer "F.Cu")
		(net "P3V3")
	)
	(segment
		(start 39.189914 -13.750036)
		(end 40.079422 -13.750036)
		(width 0.508)
		(layer "F.Cu")
		(net "P3V3")
	)
	(segment
		(start 37.190934 -7.250176)
		(end 38.080442 -7.250176)
		(width 0.508)
		(layer "F.Cu")
		(net "P3V3")
	)
	(segment
		(start 38.080442 -6.360668)
		(end 38.080442 -7.250176)
		(width 0.508)
		(layer "F.Cu")
		(net "P3V3")
	)
	(segment
		(start 39.079932 -11.749786)
		(end 39.079932 -12.639294)
		(width 0.508)
		(layer "F.Cu")
		(net "P3V3")
	)
	(segment
		(start 101.219 -22.1361)
		(end 101.219 -24.5364)
		(width 0.4572)
		(layer "F.Cu")
		(net "P3V3")
	)
	(segment
		(start 40.079422 -13.750036)
		(end 40.079422 -14.639544)
		(width 0.508)
		(layer "F.Cu")
		(net "P3V3")
	)
	(via
		(at 35.1028 -2.5527)
		(size 0.5588)
		(drill 0.3048)
		(layers "F.Cu" "B.Cu")
		(net "P3V3")
	)
	(via
		(at 35.1409 1.1684)
		(size 0.5588)
		(drill 0.3048)
		(layers "F.Cu" "B.Cu")
		(net "P3V3")
	)
	(via
		(at 127.762 -33.0454)
		(size 0.508)
		(drill 0.254)
		(layers "F.Cu" "B.Cu")
		(net "P3V3")
	)
	(via
		(at 35.941 -2.5654)
		(size 0.5588)
		(drill 0.3048)
		(layers "F.Cu" "B.Cu")
		(net "P3V3")
	)
	(via
		(at 35.4076 3.1242)
		(size 0.7112)
		(drill 0.3556)
		(layers "F.Cu" "B.Cu")
		(net "P3V3")
	)
	(via
		(at 35.687 -0.8763)
		(size 0.5588)
		(drill 0.3048)
		(layers "F.Cu" "B.Cu")
		(net "P3V3")
	)
	(via
		(at 36.0553 1.1684)
		(size 0.5588)
		(drill 0.3048)
		(layers "F.Cu" "B.Cu")
		(net "P3V3")
	)
	(via
		(at 101.1936 -24.5618)
		(size 0.508)
		(drill 0.254)
		(layers "F.Cu" "B.Cu")
		(net "P3V3")
	)
	(via
		(at 53.3654 -17.9578)
		(size 0.508)
		(drill 0.254)
		(layers "F.Cu" "B.Cu")
		(net "P3V3")
	)
	(via
		(at 36.703 1.7145)
		(size 0.5588)
		(drill 0.3048)
		(layers "F.Cu" "B.Cu")
		(net "P3V3")
	)
	(via
		(at 37.0332 -2.032)
		(size 0.7112)
		(drill 0.3556)
		(layers "F.Cu" "B.Cu")
		(net "P3V3")
	)
	(segment
		(start 53.3654 -17.9578)
		(end 55.372 -17.9578)
		(width 0.508)
		(layer "B.Cu")
		(net "P3V3")
	)
	(segment
		(start 127.762 -33.0454)
		(end 127.9906 -33.274)
		(width 0.635)
		(layer "B.Cu")
		(net "P3V3")
	)
	(segment
		(start 57.2516 -16.0782)
		(end 79.375 -16.0782)
		(width 0.508)
		(layer "B.Cu")
		(net "P3V3")
	)
	(segment
		(start 97.663 -21.6408)
		(end 100.584 -24.5618)
		(width 0.508)
		(layer "B.Cu")
		(net "P3V3")
	)
	(segment
		(start 55.372 -17.9578)
		(end 57.2516 -16.0782)
		(width 0.508)
		(layer "B.Cu")
		(net "P3V3")
	)
	(segment
		(start 127.9906 -33.274)
		(end 129.0066 -33.274)
		(width 0.635)
		(layer "B.Cu")
		(net "P3V3")
	)
	(segment
		(start 84.9376 -21.6408)
		(end 97.663 -21.6408)
		(width 0.508)
		(layer "B.Cu")
		(net "P3V3")
	)
	(segment
		(start 100.584 -24.5618)
		(end 101.1936 -24.5618)
		(width 0.508)
		(layer "B.Cu")
		(net "P3V3")
	)
	(segment
		(start 79.375 -16.0782)
		(end 84.9376 -21.6408)
		(width 0.508)
		(layer "B.Cu")
		(net "P3V3")
	)
	(segment
		(start 39.079932 -32.069786)
		(end 39.96944 -32.069786)
		(width 0.508)
		(layer "In2.Cu")
		(net "P3V3")
	)
	(segment
		(start 39.189914 -34.070036)
		(end 40.079422 -34.070036)
		(width 0.508)
		(layer "In2.Cu")
		(net "P3V3")
	)
	(segment
		(start 37.190934 -27.570176)
		(end 38.080442 -27.570176)
		(width 0.508)
		(layer "In2.Cu")
		(net "P3V3")
	)
	(segment
		(start 37.190934 -7.250176)
		(end 38.080442 -7.250176)
		(width 0.508)
		(layer "In2.Cu")
		(net "P3V3")
	)
	(segment
		(start 38.080442 -27.570176)
		(end 38.96995 -27.570176)
		(width 0.508)
		(layer "In2.Cu")
		(net "P3V3")
	)
	(segment
		(start 39.079932 -11.749786)
		(end 39.079932 -12.639294)
		(width 0.508)
		(layer "In2.Cu")
		(net "P3V3")
	)
	(segment
		(start 40.9194 -16.6878)
		(end 41.8592 -15.748)
		(width 0.508)
		(layer "In2.Cu")
		(net "P3V3")
	)
	(segment
		(start 40.079422 -12.860528)
		(end 40.079422 -13.750036)
		(width 0.508)
		(layer "In2.Cu")
		(net "P3V3")
	)
	(segment
		(start 39.189914 -13.750036)
		(end 40.079422 -13.750036)
		(width 0.508)
		(layer "In2.Cu")
		(net "P3V3")
	)
	(segment
		(start 52.4764 -17.9578)
		(end 53.3654 -17.9578)
		(width 0.508)
		(layer "In2.Cu")
		(net "P3V3")
	)
	(segment
		(start 40.079422 -13.750036)
		(end 40.96893 -13.750036)
		(width 0.508)
		(layer "In2.Cu")
		(net "P3V3")
	)
	(segment
		(start 40.079422 -13.750036)
		(end 40.079422 -14.639544)
		(width 0.508)
		(layer "In2.Cu")
		(net "P3V3")
	)
	(segment
		(start 38.190424 -11.749786)
		(end 39.079932 -11.749786)
		(width 0.508)
		(layer "In2.Cu")
		(net "P3V3")
	)
	(segment
		(start 40.079422 -33.180528)
		(end 40.079422 -34.070036)
		(width 0.508)
		(layer "In2.Cu")
		(net "P3V3")
	)
	(segment
		(start 39.079932 -32.069786)
		(end 39.079932 -32.959294)
		(width 0.508)
		(layer "In2.Cu")
		(net "P3V3")
	)
	(segment
		(start 38.190424 -32.069786)
		(end 39.079932 -32.069786)
		(width 0.508)
		(layer "In2.Cu")
		(net "P3V3")
	)
	(segment
		(start 39.079932 -10.860278)
		(end 39.079932 -11.749786)
		(width 0.508)
		(layer "In2.Cu")
		(net "P3V3")
	)
	(segment
		(start 38.080442 -7.250176)
		(end 38.96995 -7.250176)
		(width 0.508)
		(layer "In2.Cu")
		(net "P3V3")
	)
	(segment
		(start 38.080442 -26.680668)
		(end 38.080442 -27.570176)
		(width 0.508)
		(layer "In2.Cu")
		(net "P3V3")
	)
	(segment
		(start 41.8592 -15.748)
		(end 50.2666 -15.748)
		(width 0.508)
		(layer "In2.Cu")
		(net "P3V3")
	)
	(segment
		(start 38.080442 -7.250176)
		(end 38.080442 -8.139684)
		(width 0.508)
		(layer "In2.Cu")
		(net "P3V3")
	)
	(segment
		(start 38.080442 -27.570176)
		(end 38.080442 -28.459684)
		(width 0.508)
		(layer "In2.Cu")
		(net "P3V3")
	)
	(segment
		(start 50.2666 -15.748)
		(end 52.4764 -17.9578)
		(width 0.508)
		(layer "In2.Cu")
		(net "P3V3")
	)
	(segment
		(start 39.079932 -11.749786)
		(end 39.96944 -11.749786)
		(width 0.508)
		(layer "In2.Cu")
		(net "P3V3")
	)
	(segment
		(start 38.080442 -6.360668)
		(end 38.080442 -7.250176)
		(width 0.508)
		(layer "In2.Cu")
		(net "P3V3")
	)
	(segment
		(start 39.079932 -31.180278)
		(end 39.079932 -32.069786)
		(width 0.508)
		(layer "In2.Cu")
		(net "P3V3")
	)
	(segment
		(start 127.762 -33.0454)
		(end 126.5174 -31.8008)
		(width 0.635)
		(layer "In3.Cu")
		(net "P3V3")
	)
	(segment
		(start 123.2662 -31.2293)
		(end 122.6947 -31.8008)
		(width 0.635)
		(layer "In3.Cu")
		(net "P3V3")
	)
	(segment
		(start 120.0404 -31.8008)
		(end 113.2332 -24.9936)
		(width 0.635)
		(layer "In3.Cu")
		(net "P3V3")
	)
	(segment
		(start 125.8951 -31.2293)
		(end 123.2662 -31.2293)
		(width 0.635)
		(layer "In3.Cu")
		(net "P3V3")
	)
	(segment
		(start 122.6947 -31.8008)
		(end 120.0404 -31.8008)
		(width 0.635)
		(layer "In3.Cu")
		(net "P3V3")
	)
	(segment
		(start 126.5174 -31.8008)
		(end 126.4666 -31.8008)
		(width 0.635)
		(layer "In3.Cu")
		(net "P3V3")
	)
	(segment
		(start 113.2332 -24.9936)
		(end 101.6254 -24.9936)
		(width 0.635)
		(layer "In3.Cu")
		(net "P3V3")
	)
	(segment
		(start 101.6254 -24.9936)
		(end 101.1936 -24.5618)
		(width 0.635)
		(layer "In3.Cu")
		(net "P3V3")
	)
	(segment
		(start 126.4666 -31.8008)
		(end 125.8951 -31.2293)
		(width 0.635)
		(layer "In3.Cu")
		(net "P3V3")
	)
	(segment
		(start 33.080452 -28.680918)
		(end 33.080452 -29.570426)
		(width 0.508)
		(layer "F.Cu")
		(net "P12V_SLOT3")
	)
	(segment
		(start 15.1384 -24.9428)
		(end 15.1384 -24.003)
		(width 0.2032)
		(layer "F.Cu")
		(net "P12V_SLOT3")
	)
	(segment
		(start 31.080202 -29.570426)
		(end 31.96971 -29.570426)
		(width 0.508)
		(layer "F.Cu")
		(net "P12V_SLOT3")
	)
	(segment
		(start 33.080452 -29.570426)
		(end 33.080452 -30.459934)
		(width 0.508)
		(layer "F.Cu")
		(net "P12V_SLOT3")
	)
	(segment
		(start 32.190944 -32.069786)
		(end 33.080452 -32.069786)
		(width 0.508)
		(layer "F.Cu")
		(net "P12V_SLOT3")
	)
	(segment
		(start 33.080452 -31.180278)
		(end 33.080452 -32.069786)
		(width 0.508)
		(layer "F.Cu")
		(net "P12V_SLOT3")
	)
	(segment
		(start 30.190694 -29.570426)
		(end 31.080202 -29.570426)
		(width 0.508)
		(layer "F.Cu")
		(net "P12V_SLOT3")
	)
	(segment
		(start 31.080202 -29.570426)
		(end 31.080202 -30.459934)
		(width 0.508)
		(layer "F.Cu")
		(net "P12V_SLOT3")
	)
	(segment
		(start 32.079692 -33.180528)
		(end 32.079692 -34.070036)
		(width 0.508)
		(layer "F.Cu")
		(net "P12V_SLOT3")
	)
	(segment
		(start 15.3924 -23.749)
		(end 16.4973 -23.749)
		(width 0.2032)
		(layer "F.Cu")
		(net "P12V_SLOT3")
	)
	(segment
		(start 31.080202 -28.680918)
		(end 31.080202 -29.570426)
		(width 0.508)
		(layer "F.Cu")
		(net "P12V_SLOT3")
	)
	(segment
		(start 32.190944 -29.570426)
		(end 33.080452 -29.570426)
		(width 0.508)
		(layer "F.Cu")
		(net "P12V_SLOT3")
	)
	(segment
		(start 31.190184 -34.070036)
		(end 32.079692 -34.070036)
		(width 0.508)
		(layer "F.Cu")
		(net "P12V_SLOT3")
	)
	(segment
		(start 33.080452 -32.069786)
		(end 33.080452 -32.959294)
		(width 0.508)
		(layer "F.Cu")
		(net "P12V_SLOT3")
	)
	(segment
		(start 33.080452 -32.069786)
		(end 33.96996 -32.069786)
		(width 0.508)
		(layer "F.Cu")
		(net "P12V_SLOT3")
	)
	(segment
		(start 15.1384 -24.003)
		(end 15.3924 -23.749)
		(width 0.2032)
		(layer "F.Cu")
		(net "P12V_SLOT3")
	)
	(segment
		(start 16.4973 -23.749)
		(end 16.7513 -24.003)
		(width 0.2032)
		(layer "F.Cu")
		(net "P12V_SLOT3")
	)
	(segment
		(start 32.079692 -34.070036)
		(end 32.9692 -34.070036)
		(width 0.508)
		(layer "F.Cu")
		(net "P12V_SLOT3")
	)
	(via
		(at 13.7922 -29.4132)
		(size 0.5588)
		(drill 0.3048)
		(layers "F.Cu" "B.Cu")
		(net "P12V_SLOT3")
	)
	(via
		(at 12.8524 -25.5524)
		(size 0.5588)
		(drill 0.3048)
		(layers "F.Cu" "B.Cu")
		(net "P12V_SLOT3")
	)
	(via
		(at 12.9032 -31.3436)
		(size 0.5588)
		(drill 0.3048)
		(layers "F.Cu" "B.Cu")
		(net "P12V_SLOT3")
	)
	(via
		(at 12.827 -24.7396)
		(size 0.5588)
		(drill 0.3048)
		(layers "F.Cu" "B.Cu")
		(net "P12V_SLOT3")
	)
	(via
		(at 12.954 -29.464)
		(size 0.5588)
		(drill 0.3048)
		(layers "F.Cu" "B.Cu")
		(net "P12V_SLOT3")
	)
	(via
		(at 14.9606 -29.2862)
		(size 0.7112)
		(drill 0.3556)
		(layers "F.Cu" "B.Cu")
		(net "P12V_SLOT3")
	)
	(via
		(at 12.954 -30.3784)
		(size 0.5588)
		(drill 0.3048)
		(layers "F.Cu" "B.Cu")
		(net "P12V_SLOT3")
	)
	(via
		(at 12.954 -26.4922)
		(size 0.5588)
		(drill 0.3048)
		(layers "F.Cu" "B.Cu")
		(net "P12V_SLOT3")
	)
	(segment
		(start 31.080202 -29.570426)
		(end 31.080202 -30.459934)
		(width 0.508)
		(layer "In3.Cu")
		(net "P12V_SLOT3")
	)
	(segment
		(start 31.190184 -27.570176)
		(end 32.079692 -27.570176)
		(width 0.508)
		(layer "In3.Cu")
		(net "P12V_SLOT3")
	)
	(segment
		(start 33.080452 -29.570426)
		(end 33.080452 -30.459934)
		(width 0.508)
		(layer "In3.Cu")
		(net "P12V_SLOT3")
	)
	(segment
		(start 32.079692 -27.570176)
		(end 32.079692 -28.459684)
		(width 0.508)
		(layer "In3.Cu")
		(net "P12V_SLOT3")
	)
	(segment
		(start 33.080452 -31.180278)
		(end 33.080452 -32.069786)
		(width 0.508)
		(layer "In3.Cu")
		(net "P12V_SLOT3")
	)
	(segment
		(start 33.080452 -28.680918)
		(end 33.080452 -29.570426)
		(width 0.508)
		(layer "In3.Cu")
		(net "P12V_SLOT3")
	)
	(segment
		(start 32.190944 -32.069786)
		(end 33.080452 -32.069786)
		(width 0.508)
		(layer "In3.Cu")
		(net "P12V_SLOT3")
	)
	(segment
		(start 31.080202 -28.680918)
		(end 31.080202 -29.570426)
		(width 0.508)
		(layer "In3.Cu")
		(net "P12V_SLOT3")
	)
	(segment
		(start 31.190184 -34.070036)
		(end 32.079692 -34.070036)
		(width 0.508)
		(layer "In3.Cu")
		(net "P12V_SLOT3")
	)
	(segment
		(start 33.080452 -29.570426)
		(end 33.96996 -29.570426)
		(width 0.508)
		(layer "In3.Cu")
		(net "P12V_SLOT3")
	)
	(segment
		(start 32.079692 -34.070036)
		(end 32.9692 -34.070036)
		(width 0.508)
		(layer "In3.Cu")
		(net "P12V_SLOT3")
	)
	(segment
		(start 30.190694 -29.570426)
		(end 31.080202 -29.570426)
		(width 0.508)
		(layer "In3.Cu")
		(net "P12V_SLOT3")
	)
	(segment
		(start 33.080452 -32.069786)
		(end 33.080452 -32.959294)
		(width 0.508)
		(layer "In3.Cu")
		(net "P12V_SLOT3")
	)
	(segment
		(start 31.080202 -29.570426)
		(end 31.96971 -29.570426)
		(width 0.508)
		(layer "In3.Cu")
		(net "P12V_SLOT3")
	)
	(segment
		(start 32.079692 -27.570176)
		(end 32.9692 -27.570176)
		(width 0.508)
		(layer "In3.Cu")
		(net "P12V_SLOT3")
	)
	(segment
		(start 32.079692 -33.180528)
		(end 32.079692 -34.070036)
		(width 0.508)
		(layer "In3.Cu")
		(net "P12V_SLOT3")
	)
	(segment
		(start 32.190944 -29.570426)
		(end 33.080452 -29.570426)
		(width 0.508)
		(layer "In3.Cu")
		(net "P12V_SLOT3")
	)
	(segment
		(start 33.080452 -32.069786)
		(end 33.96996 -32.069786)
		(width 0.508)
		(layer "In3.Cu")
		(net "P12V_SLOT3")
	)
	(segment
		(start 14.157706 -18.712688)
		(end 14.760194 -18.1102)
		(width 0.2032)
		(layer "F.Cu")
		(net "P12V_SLOT2")
	)
	(segment
		(start 30.190694 -9.250426)
		(end 31.080202 -9.250426)
		(width 0.508)
		(layer "F.Cu")
		(net "P12V_SLOT2")
	)
	(segment
		(start 32.190944 -9.250426)
		(end 33.080452 -9.250426)
		(width 0.508)
		(layer "F.Cu")
		(net "P12V_SLOT2")
	)
	(segment
		(start 31.080202 -9.250426)
		(end 31.96971 -9.250426)
		(width 0.508)
		(layer "F.Cu")
		(net "P12V_SLOT2")
	)
	(segment
		(start 31.080202 -8.360918)
		(end 31.080202 -9.250426)
		(width 0.508)
		(layer "F.Cu")
		(net "P12V_SLOT2")
	)
	(segment
		(start 33.080452 -8.360918)
		(end 33.080452 -9.250426)
		(width 0.508)
		(layer "F.Cu")
		(net "P12V_SLOT2")
	)
	(segment
		(start 33.080452 -9.250426)
		(end 33.080452 -10.139934)
		(width 0.508)
		(layer "F.Cu")
		(net "P12V_SLOT2")
	)
	(segment
		(start 16.039338 -18.934938)
		(end 16.039338 -19.323812)
		(width 0.2032)
		(layer "F.Cu")
		(net "P12V_SLOT2")
	)
	(segment
		(start 32.190944 -11.749786)
		(end 33.080452 -11.749786)
		(width 0.508)
		(layer "F.Cu")
		(net "P12V_SLOT2")
	)
	(segment
		(start 33.080452 -10.860278)
		(end 33.080452 -11.749786)
		(width 0.508)
		(layer "F.Cu")
		(net "P12V_SLOT2")
	)
	(segment
		(start 31.080202 -9.250426)
		(end 31.080202 -10.139934)
		(width 0.508)
		(layer "F.Cu")
		(net "P12V_SLOT2")
	)
	(segment
		(start 32.079692 -6.360668)
		(end 32.079692 -7.250176)
		(width 0.508)
		(layer "F.Cu")
		(net "P12V_SLOT2")
	)
	(segment
		(start 33.080452 -11.749786)
		(end 33.080452 -12.639294)
		(width 0.508)
		(layer "F.Cu")
		(net "P12V_SLOT2")
	)
	(segment
		(start 31.190184 -7.250176)
		(end 32.079692 -7.250176)
		(width 0.508)
		(layer "F.Cu")
		(net "P12V_SLOT2")
	)
	(segment
		(start 32.079692 -12.860528)
		(end 32.079692 -13.750036)
		(width 0.508)
		(layer "F.Cu")
		(net "P12V_SLOT2")
	)
	(segment
		(start 32.079692 -13.750036)
		(end 32.9692 -13.750036)
		(width 0.508)
		(layer "F.Cu")
		(net "P12V_SLOT2")
	)
	(segment
		(start 14.760194 -18.1102)
		(end 15.2146 -18.1102)
		(width 0.2032)
		(layer "F.Cu")
		(net "P12V_SLOT2")
	)
	(segment
		(start 31.190184 -13.750036)
		(end 32.079692 -13.750036)
		(width 0.508)
		(layer "F.Cu")
		(net "P12V_SLOT2")
	)
	(segment
		(start 32.079692 -7.250176)
		(end 32.079692 -8.139684)
		(width 0.508)
		(layer "F.Cu")
		(net "P12V_SLOT2")
	)
	(segment
		(start 15.2146 -18.1102)
		(end 16.039338 -18.934938)
		(width 0.2032)
		(layer "F.Cu")
		(net "P12V_SLOT2")
	)
	(via
		(at 26.8986 -14.1732)
		(size 0.5588)
		(drill 0.3048)
		(layers "F.Cu" "B.Cu")
		(net "P12V_SLOT2")
	)
	(via
		(at 26.0858 -14.1478)
		(size 0.5588)
		(drill 0.3048)
		(layers "F.Cu" "B.Cu")
		(net "P12V_SLOT2")
	)
	(via
		(at 26.9494 -13.335)
		(size 0.5588)
		(drill 0.3048)
		(layers "F.Cu" "B.Cu")
		(net "P12V_SLOT2")
	)
	(via
		(at 12.9286 -17.0688)
		(size 0.5588)
		(drill 0.3048)
		(layers "F.Cu" "B.Cu")
		(net "P12V_SLOT2")
	)
	(via
		(at 13.7414 -17.2212)
		(size 0.5588)
		(drill 0.3048)
		(layers "F.Cu" "B.Cu")
		(net "P12V_SLOT2")
	)
	(via
		(at 13.4112 -19.7612)
		(size 0.5588)
		(drill 0.3048)
		(layers "F.Cu" "B.Cu")
		(net "P12V_SLOT2")
	)
	(via
		(at 12.8524 -18.0086)
		(size 0.5588)
		(drill 0.3048)
		(layers "F.Cu" "B.Cu")
		(net "P12V_SLOT2")
	)
	(via
		(at 12.827 -19.1262)
		(size 0.5588)
		(drill 0.3048)
		(layers "F.Cu" "B.Cu")
		(net "P12V_SLOT2")
	)
	(via
		(at 26.0604 -15.0114)
		(size 0.5588)
		(drill 0.3048)
		(layers "F.Cu" "B.Cu")
		(net "P12V_SLOT2")
	)
	(via
		(at 26.8732 -15.0368)
		(size 0.5588)
		(drill 0.3048)
		(layers "F.Cu" "B.Cu")
		(net "P12V_SLOT2")
	)
	(via
		(at 26.0858 -13.335)
		(size 0.5588)
		(drill 0.3048)
		(layers "F.Cu" "B.Cu")
		(net "P12V_SLOT2")
	)
	(via
		(at 13.716 -18.542)
		(size 0.7112)
		(drill 0.3556)
		(layers "F.Cu" "B.Cu")
		(net "P12V_SLOT2")
	)
	(segment
		(start 82.1436 -20.4343)
		(end 54.3433 -20.4343)
		(width 0.1016)
		(layer "F.Cu")
		(net "P12V")
	)
	(segment
		(start 15.4178 -23.3172)
		(end 16.3957 -23.3172)
		(width 0.2032)
		(layer "F.Cu")
		(net "P12V")
	)
	(segment
		(start 15.4813 -17.7673)
		(end 16.291052 -18.577052)
		(width 0.2032)
		(layer "F.Cu")
		(net "P12V")
	)
	(segment
		(start 16.291052 -18.577052)
		(end 16.786352 -18.577052)
		(width 0.2032)
		(layer "F.Cu")
		(net "P12V")
	)
	(segment
		(start 54.3433 -20.4343)
		(end 53.2892 -19.3802)
		(width 0.1016)
		(layer "F.Cu")
		(net "P12V")
	)
	(segment
		(start 15.1384 -23.0378)
		(end 15.4178 -23.3172)
		(width 0.2032)
		(layer "F.Cu")
		(net "P12V")
	)
	(segment
		(start 21.314664 -20.829524)
		(end 21.314664 -21.357336)
		(width 0.3048)
		(layer "F.Cu")
		(net "P12V")
	)
	(segment
		(start 82.1944 -19.1516)
		(end 82.1944 -20.3835)
		(width 0.1016)
		(layer "F.Cu")
		(net "P12V")
	)
	(segment
		(start 20.3835 -21.6408)
		(end 19.7231 -22.3012)
		(width 0.3048)
		(layer "F.Cu")
		(net "P12V")
	)
	(segment
		(start 15.1384 -22.1488)
		(end 15.1384 -23.0378)
		(width 0.2032)
		(layer "F.Cu")
		(net "P12V")
	)
	(segment
		(start 19.689064 -26.750264)
		(end 20.699476 -26.750264)
		(width 0.3048)
		(layer "F.Cu")
		(net "P12V")
	)
	(segment
		(start 53.2892 -19.3802)
		(end 52.705 -19.3802)
		(width 0.1016)
		(layer "F.Cu")
		(net "P12V")
	)
	(segment
		(start 21.314664 -21.357336)
		(end 21.0312 -21.6408)
		(width 0.3048)
		(layer "F.Cu")
		(net "P12V")
	)
	(segment
		(start 15.4813 -17.389094)
		(end 15.4813 -17.7673)
		(width 0.2032)
		(layer "F.Cu")
		(net "P12V")
	)
	(segment
		(start 16.3957 -23.3172)
		(end 16.7513 -22.9616)
		(width 0.2032)
		(layer "F.Cu")
		(net "P12V")
	)
	(segment
		(start 16.133318 -16.737076)
		(end 15.4813 -17.389094)
		(width 0.2032)
		(layer "F.Cu")
		(net "P12V")
	)
	(segment
		(start 21.0312 -21.6408)
		(end 20.3835 -21.6408)
		(width 0.3048)
		(layer "F.Cu")
		(net "P12V")
	)
	(segment
		(start 19.304 -26.3652)
		(end 19.689064 -26.750264)
		(width 0.3048)
		(layer "F.Cu")
		(net "P12V")
	)
	(segment
		(start 19.7231 -22.3012)
		(end 19.5072 -22.3012)
		(width 0.3048)
		(layer "F.Cu")
		(net "P12V")
	)
	(segment
		(start 19.5072 -22.3012)
		(end 19.4818 -22.3266)
		(width 0.3048)
		(layer "F.Cu")
		(net "P12V")
	)
	(segment
		(start 82.1944 -20.3835)
		(end 82.1436 -20.4343)
		(width 0.1016)
		(layer "F.Cu")
		(net "P12V")
	)
	(via
		(at 12.827 -20.8788)
		(size 0.5588)
		(drill 0.3048)
		(layers "F.Cu" "B.Cu")
		(net "P12V")
	)
	(via
		(at 19.4818 -22.3266)
		(size 0.508)
		(drill 0.254)
		(layers "F.Cu" "B.Cu")
		(net "P12V")
	)
	(via
		(at 16.8402 9.0424)
		(size 0.5588)
		(drill 0.3048)
		(layers "F.Cu" "B.Cu")
		(net "P12V")
	)
	(via
		(at 15.6464 -20.8788)
		(size 0.5588)
		(drill 0.3048)
		(layers "F.Cu" "B.Cu")
		(net "P12V")
	)
	(via
		(at 19.304 -26.3652)
		(size 0.5588)
		(drill 0.3048)
		(layers "F.Cu" "B.Cu")
		(net "P12V")
	)
	(via
		(at 14.224 -15.621)
		(size 0.5588)
		(drill 0.3048)
		(layers "F.Cu" "B.Cu")
		(net "P12V")
	)
	(via
		(at 12.8524 -21.844)
		(size 0.5588)
		(drill 0.3048)
		(layers "F.Cu" "B.Cu")
		(net "P12V")
	)
	(via
		(at 16.8148 6.0198)
		(size 0.5588)
		(drill 0.3048)
		(layers "F.Cu" "B.Cu")
		(net "P12V")
	)
	(via
		(at 10.3378 -17.5006)
		(size 0.7112)
		(drill 0.3556)
		(layers "F.Cu" "B.Cu")
		(net "P12V")
	)
	(via
		(at 16.51 -15.4178)
		(size 0.5588)
		(drill 0.3048)
		(layers "F.Cu" "B.Cu")
		(net "P12V")
	)
	(via
		(at 18.8468 7.1882)
		(size 0.5588)
		(drill 0.3048)
		(layers "F.Cu" "B.Cu")
		(net "P12V")
	)
	(via
		(at 13.7668 -22.6568)
		(size 0.5588)
		(drill 0.3048)
		(layers "F.Cu" "B.Cu")
		(net "P12V")
	)
	(via
		(at 17.9324 7.1628)
		(size 0.5588)
		(drill 0.3048)
		(layers "F.Cu" "B.Cu")
		(net "P12V")
	)
	(via
		(at 17.907 6.0452)
		(size 0.5588)
		(drill 0.3048)
		(layers "F.Cu" "B.Cu")
		(net "P12V")
	)
	(via
		(at 15.113 -15.621)
		(size 0.5588)
		(drill 0.3048)
		(layers "F.Cu" "B.Cu")
		(net "P12V")
	)
	(via
		(at 15.7734 6.0198)
		(size 0.5588)
		(drill 0.3048)
		(layers "F.Cu" "B.Cu")
		(net "P12V")
	)
	(via
		(at 17.9324 9.0678)
		(size 0.5588)
		(drill 0.3048)
		(layers "F.Cu" "B.Cu")
		(net "P12V")
	)
	(via
		(at 14.224 -13.8176)
		(size 0.5588)
		(drill 0.3048)
		(layers "F.Cu" "B.Cu")
		(net "P12V")
	)
	(via
		(at 15.4432 -22.4663)
		(size 0.7112)
		(drill 0.3556)
		(layers "F.Cu" "B.Cu")
		(net "P12V")
	)
	(via
		(at 17.3101 -26.7208)
		(size 0.5588)
		(drill 0.3048)
		(layers "F.Cu" "B.Cu")
		(net "P12V")
	)
	(via
		(at 15.7988 9.0424)
		(size 0.5588)
		(drill 0.3048)
		(layers "F.Cu" "B.Cu")
		(net "P12V")
	)
	(via
		(at 17.2974 -15.9766)
		(size 0.5588)
		(drill 0.3048)
		(layers "F.Cu" "B.Cu")
		(net "P12V")
	)
	(via
		(at 18.8468 9.0932)
		(size 0.5588)
		(drill 0.3048)
		(layers "F.Cu" "B.Cu")
		(net "P12V")
	)
	(via
		(at 52.705 -19.3802)
		(size 0.508)
		(drill 0.254)
		(layers "F.Cu" "B.Cu")
		(net "P12V")
	)
	(via
		(at 16.8402 7.1374)
		(size 0.5588)
		(drill 0.3048)
		(layers "F.Cu" "B.Cu")
		(net "P12V")
	)
	(via
		(at 15.7988 7.1374)
		(size 0.5588)
		(drill 0.3048)
		(layers "F.Cu" "B.Cu")
		(net "P12V")
	)
	(via
		(at 18.4023 -26.3017)
		(size 0.5588)
		(drill 0.3048)
		(layers "F.Cu" "B.Cu")
		(net "P12V")
	)
	(via
		(at 17.3228 2.8321)
		(size 0.7112)
		(drill 0.3556)
		(layers "F.Cu" "B.Cu")
		(net "P12V")
	)
	(via
		(at 18.5674 -25.4508)
		(size 0.5588)
		(drill 0.3048)
		(layers "F.Cu" "B.Cu")
		(net "P12V")
	)
	(via
		(at 14.605 -20.8534)
		(size 0.5588)
		(drill 0.3048)
		(layers "F.Cu" "B.Cu")
		(net "P12V")
	)
	(via
		(at 17.907 8.1026)
		(size 0.5588)
		(drill 0.3048)
		(layers "F.Cu" "B.Cu")
		(net "P12V")
	)
	(via
		(at 17.7038 3.6068)
		(size 0.7112)
		(drill 0.3556)
		(layers "F.Cu" "B.Cu")
		(net "P12V")
	)
	(via
		(at 13.2842 -15.0368)
		(size 0.5588)
		(drill 0.3048)
		(layers "F.Cu" "B.Cu")
		(net "P12V")
	)
	(via
		(at 15.0876 -14.3256)
		(size 0.5588)
		(drill 0.3048)
		(layers "F.Cu" "B.Cu")
		(net "P12V")
	)
	(via
		(at 18.8214 6.0706)
		(size 0.5588)
		(drill 0.3048)
		(layers "F.Cu" "B.Cu")
		(net "P12V")
	)
	(via
		(at 18.8214 8.128)
		(size 0.5588)
		(drill 0.3048)
		(layers "F.Cu" "B.Cu")
		(net "P12V")
	)
	(via
		(at 16.7767 -25.9588)
		(size 0.5588)
		(drill 0.3048)
		(layers "F.Cu" "B.Cu")
		(net "P12V")
	)
	(via
		(at 17.6022 -25.9334)
		(size 0.5588)
		(drill 0.3048)
		(layers "F.Cu" "B.Cu")
		(net "P12V")
	)
	(via
		(at 16.8148 8.0772)
		(size 0.5588)
		(drill 0.3048)
		(layers "F.Cu" "B.Cu")
		(net "P12V")
	)
	(via
		(at 14.3002 -14.6558)
		(size 0.5588)
		(drill 0.3048)
		(layers "F.Cu" "B.Cu")
		(net "P12V")
	)
	(via
		(at 12.8524 -22.6568)
		(size 0.5588)
		(drill 0.3048)
		(layers "F.Cu" "B.Cu")
		(net "P12V")
	)
	(via
		(at 15.8496 -14.9352)
		(size 0.5588)
		(drill 0.3048)
		(layers "F.Cu" "B.Cu")
		(net "P12V")
	)
	(via
		(at 17.78 -25.0444)
		(size 0.5588)
		(drill 0.3048)
		(layers "F.Cu" "B.Cu")
		(net "P12V")
	)
	(via
		(at 16.7894 -25.1333)
		(size 0.5588)
		(drill 0.3048)
		(layers "F.Cu" "B.Cu")
		(net "P12V")
	)
	(via
		(at 13.7922 -20.8788)
		(size 0.5588)
		(drill 0.3048)
		(layers "F.Cu" "B.Cu")
		(net "P12V")
	)
	(via
		(at 13.7668 -21.7932)
		(size 0.5588)
		(drill 0.3048)
		(layers "F.Cu" "B.Cu")
		(net "P12V")
	)
	(via
		(at 15.7734 8.0772)
		(size 0.5588)
		(drill 0.3048)
		(layers "F.Cu" "B.Cu")
		(net "P12V")
	)
	(segment
		(start 20.163536 -24.151336)
		(end 19.6088 -23.5966)
		(width 0.3048)
		(layer "B.Cu")
		(net "P12V")
	)
	(segment
		(start 19.6088 -23.5966)
		(end 19.6088 -22.4536)
		(width 0.3048)
		(layer "B.Cu")
		(net "P12V")
	)
	(segment
		(start 18.221706 -27.866594)
		(end 17.67205 -28.41625)
		(width 0.2032)
		(layer "B.Cu")
		(net "P12V")
	)
	(segment
		(start 17.24025 -28.41625)
		(end 16.176498 -27.352498)
		(width 0.2032)
		(layer "B.Cu")
		(net "P12V")
	)
	(segment
		(start 19.6088 -22.4536)
		(end 19.4818 -22.3266)
		(width 0.3048)
		(layer "B.Cu")
		(net "P12V")
	)
	(segment
		(start 17.67205 -28.41625)
		(end 17.24025 -28.41625)
		(width 0.2032)
		(layer "B.Cu")
		(net "P12V")
	)
	(segment
		(start 16.176498 -27.352498)
		(end 16.176498 -26.895298)
		(width 0.2032)
		(layer "B.Cu")
		(net "P12V")
	)
	(segment
		(start 20.699476 -24.151336)
		(end 20.163536 -24.151336)
		(width 0.3048)
		(layer "B.Cu")
		(net "P12V")
	)
	(segment
		(start 23.8252 -20.2184)
		(end 25.3746 -20.2184)
		(width 0.1016)
		(layer "In3.Cu")
		(net "P12V")
	)
	(segment
		(start 50.042064 -16.336264)
		(end 52.324 -18.6182)
		(width 0.1016)
		(layer "In3.Cu")
		(net "P12V")
	)
	(segment
		(start 52.324 -18.9992)
		(end 52.705 -19.3802)
		(width 0.1016)
		(layer "In3.Cu")
		(net "P12V")
	)
	(segment
		(start 42.413936 -16.336264)
		(end 50.042064 -16.336264)
		(width 0.1016)
		(layer "In3.Cu")
		(net "P12V")
	)
	(segment
		(start 41.6052 -17.145)
		(end 42.413936 -16.336264)
		(width 0.1016)
		(layer "In3.Cu")
		(net "P12V")
	)
	(segment
		(start 20.32 -21.59)
		(end 22.4536 -21.59)
		(width 0.1016)
		(layer "In3.Cu")
		(net "P12V")
	)
	(segment
		(start 25.3746 -20.2184)
		(end 28.448 -17.145)
		(width 0.1016)
		(layer "In3.Cu")
		(net "P12V")
	)
	(segment
		(start 28.448 -17.145)
		(end 41.6052 -17.145)
		(width 0.1016)
		(layer "In3.Cu")
		(net "P12V")
	)
	(segment
		(start 19.4818 -22.3266)
		(end 19.5834 -22.3266)
		(width 0.508)
		(layer "In3.Cu")
		(net "P12V")
	)
	(segment
		(start 22.4536 -21.59)
		(end 23.8252 -20.2184)
		(width 0.1016)
		(layer "In3.Cu")
		(net "P12V")
	)
	(segment
		(start 52.324 -18.6182)
		(end 52.324 -18.9992)
		(width 0.1016)
		(layer "In3.Cu")
		(net "P12V")
	)
	(segment
		(start 19.5834 -22.3266)
		(end 20.32 -21.59)
		(width 0.1016)
		(layer "In3.Cu")
		(net "P12V")
	)
	(segment
		(start 129.8575 -25.4254)
		(end 128.9304 -25.4254)
		(width 0.1016)
		(layer "F.Cu")
		(net "NON_REM0")
	)
	(segment
		(start 128.239266 -26.116534)
		(end 127.19558 -26.116534)
		(width 0.1016)
		(layer "F.Cu")
		(net "NON_REM0")
	)
	(segment
		(start 129.9591 -25.527)
		(end 129.8575 -25.4254)
		(width 0.1016)
		(layer "F.Cu")
		(net "NON_REM0")
	)
	(segment
		(start 128.9304 -25.4254)
		(end 128.239266 -26.116534)
		(width 0.1016)
		(layer "F.Cu")
		(net "NON_REM0")
	)
	(segment
		(start 129.9591 -24.4856)
		(end 129.9591 -25.527)
		(width 0.1016)
		(layer "F.Cu")
		(net "NON_REM0")
	)
	(via
		(at 128.9304 -25.4254)
		(size 0.7112)
		(drill 0.3556)
		(layers "F.Cu" "B.Cu")
		(net "NON_REM0")
	)
	(segment
		(start 100.03155 4.84124)
		(end 99.86899 5.0038)
		(width 0.4572)
		(layer "F.Cu")
		(net "GND")
	)
	(segment
		(start 21.5519 -15.3416)
		(end 21.5138 -15.3035)
		(width 0.4064)
		(layer "F.Cu")
		(net "GND")
	)
	(segment
		(start 133.2738 -4.6736)
		(end 133.4516 -4.8514)
		(width 0.4572)
		(layer "F.Cu")
		(net "GND")
	)
	(segment
		(start 132.1943 -10.4394)
		(end 133.0452 -10.4394)
		(width 0.4064)
		(layer "F.Cu")
		(net "GND")
	)
	(segment
		(start 46.779942 12.133072)
		(end 46.779942 9.842246)
		(width 0.5588)
		(layer "F.Cu")
		(net "GND")
	)
	(segment
		(start 126.9873 -1.165606)
		(end 127.6096 -1.787906)
		(width 0.4064)
		(layer "F.Cu")
		(net "GND")
	)
	(segment
		(start 32.37992 12.133072)
		(end 32.37992 9.842246)
		(width 0.5588)
		(layer "F.Cu")
		(net "GND")
	)
	(segment
		(start 116.175028 9.943846)
		(end 116.551202 9.567672)
		(width 0.5588)
		(layer "F.Cu")
		(net "GND")
	)
	(segment
		(start 43.402504 1.292352)
		(end 43.688 1.006856)
		(width 0.3556)
		(layer "F.Cu")
		(net "GND")
	)
	(segment
		(start 132.1181 -19.8882)
		(end 132.1435 -19.8628)
		(width 0.4064)
		(layer "F.Cu")
		(net "GND")
	)
	(segment
		(start 63.58001 12.133072)
		(end 63.58001 9.842246)
		(width 0.5588)
		(layer "F.Cu")
		(net "GND")
	)
	(segment
		(start 129.7305 -30.5943)
		(end 129.8448 -30.7086)
		(width 0.4572)
		(layer "F.Cu")
		(net "GND")
	)
	(segment
		(start 87.579962 12.133072)
		(end 87.579962 9.842246)
		(width 0.5588)
		(layer "F.Cu")
		(net "GND")
	)
	(segment
		(start 133.2611 -19.8628)
		(end 133.2865 -19.8374)
		(width 0.4064)
		(layer "F.Cu")
		(net "GND")
	)
	(segment
		(start 128.905 -22.2377)
		(end 129.1463 -22.479)
		(width 0.4572)
		(layer "F.Cu")
		(net "GND")
	)
	(segment
		(start 126.9873 -1.016)
		(end 126.8857 -0.9144)
		(width 0.4064)
		(layer "F.Cu")
		(net "GND")
	)
	(segment
		(start 113.774982 9.943846)
		(end 114.151156 9.567672)
		(width 0.5588)
		(layer "F.Cu")
		(net "GND")
	)
	(segment
		(start 97.282 -18.4404)
		(end 95.9104 -18.4404)
		(width 0.4572)
		(layer "F.Cu")
		(net "GND")
	)
	(segment
		(start 89.980008 9.842246)
		(end 90.356182 9.466072)
		(width 0.5588)
		(layer "F.Cu")
		(net "GND")
	)
	(segment
		(start 132.6515 -4.6736)
		(end 133.2738 -4.6736)
		(width 0.4572)
		(layer "F.Cu")
		(net "GND")
	)
	(segment
		(start 94.4372 -19.9136)
		(end 93.9927 -19.9136)
		(width 0.4572)
		(layer "F.Cu")
		(net "GND")
	)
	(segment
		(start 84.4804 -20.6375)
		(end 85.232748 -20.6375)
		(width 0.4572)
		(layer "F.Cu")
		(net "GND")
	)
	(segment
		(start 34.779966 9.842246)
		(end 35.15614 9.466072)
		(width 0.5588)
		(layer "F.Cu")
		(net "GND")
	)
	(segment
		(start 95.9104 -18.4404)
		(end 94.4372 -19.9136)
		(width 0.4572)
		(layer "F.Cu")
		(net "GND")
	)
	(segment
		(start 21.6408 -23.8506)
		(end 21.3233 -24.1681)
		(width 0.508)
		(layer "F.Cu")
		(net "GND")
	)
	(segment
		(start 37.180012 9.842246)
		(end 37.556186 9.466072)
		(width 0.5588)
		(layer "F.Cu")
		(net "GND")
	)
	(segment
		(start 51.57978 9.842246)
		(end 51.955954 9.466072)
		(width 0.5588)
		(layer "F.Cu")
		(net "GND")
	)
	(segment
		(start 32.37992 9.842246)
		(end 32.756094 9.466072)
		(width 0.5588)
		(layer "F.Cu")
		(net "GND")
	)
	(segment
		(start 49.179988 9.842246)
		(end 49.556162 9.466072)
		(width 0.5588)
		(layer "F.Cu")
		(net "GND")
	)
	(segment
		(start 31.3944 9.4488)
		(end 30.988 9.4488)
		(width 0.5588)
		(layer "F.Cu")
		(net "GND")
	)
	(segment
		(start 120.97512 12.234672)
		(end 120.97512 9.943846)
		(width 0.5588)
		(layer "F.Cu")
		(net "GND")
	)
	(segment
		(start 51.57978 12.133072)
		(end 51.57978 9.842246)
		(width 0.5588)
		(layer "F.Cu")
		(net "GND")
	)
	(segment
		(start 120.5738 -25.24252)
		(end 120.473978 -25.342342)
		(width 0.4064)
		(layer "F.Cu")
		(net "GND")
	)
	(segment
		(start 129.7305 -29.3624)
		(end 129.7305 -30.5943)
		(width 0.4572)
		(layer "F.Cu")
		(net "GND")
	)
	(segment
		(start 80.379824 9.842246)
		(end 80.755998 9.466072)
		(width 0.5588)
		(layer "F.Cu")
		(net "GND")
	)
	(segment
		(start 26.9621 -26.6446)
		(end 26.9621 -25.6032)
		(width 0.4064)
		(layer "F.Cu")
		(net "GND")
	)
	(segment
		(start 120.97512 9.943846)
		(end 121.351294 9.567672)
		(width 0.5588)
		(layer "F.Cu")
		(net "GND")
	)
	(segment
		(start 83.3628 -19.5072)
		(end 83.7184 -19.1516)
		(width 0.4572)
		(layer "F.Cu")
		(net "GND")
	)
	(segment
		(start 123.9012 1.8288)
		(end 123.952 1.8288)
		(width 0.4064)
		(layer "F.Cu")
		(net "GND")
	)
	(segment
		(start 104.2035 -22.1996)
		(end 102.997 -22.1996)
		(width 0.4572)
		(layer "F.Cu")
		(net "GND")
	)
	(segment
		(start 27.579828 10.278872)
		(end 27.579828 12.133072)
		(width 0.5588)
		(layer "F.Cu")
		(net "GND")
	)
	(segment
		(start 68.379848 9.842246)
		(end 68.756022 9.466072)
		(width 0.5588)
		(layer "F.Cu")
		(net "GND")
	)
	(segment
		(start 118.0719 -19.4691)
		(end 117.6528 -19.4691)
		(width 0.4064)
		(layer "F.Cu")
		(net "GND")
	)
	(segment
		(start 92.3798 9.842246)
		(end 92.755974 9.466072)
		(width 0.5588)
		(layer "F.Cu")
		(net "GND")
	)
	(segment
		(start 127.315976 -21.502624)
		(end 127.569976 -21.502624)
		(width 0.508)
		(layer "F.Cu")
		(net "GND")
	)
	(segment
		(start 126.6317 -21.59)
		(end 127.2286 -21.59)
		(width 0.508)
		(layer "F.Cu")
		(net "GND")
	)
	(segment
		(start 131.162552 -33.524952)
		(end 131.4958 -33.8582)
		(width 0.4064)
		(layer "F.Cu")
		(net "GND")
	)
	(segment
		(start 120.8151 -23.3934)
		(end 120.786398 -23.422102)
		(width 0.4064)
		(layer "F.Cu")
		(net "GND")
	)
	(segment
		(start 97.179892 9.689338)
		(end 97.57283 9.2964)
		(width 0.5588)
		(layer "F.Cu")
		(net "GND")
	)
	(segment
		(start 46.779942 9.842246)
		(end 47.156116 9.466072)
		(width 0.5588)
		(layer "F.Cu")
		(net "GND")
	)
	(segment
		(start 56.379872 12.133072)
		(end 56.379872 9.842246)
		(width 0.5588)
		(layer "F.Cu")
		(net "GND")
	)
	(segment
		(start 58.779918 9.842246)
		(end 59.156092 9.466072)
		(width 0.5588)
		(layer "F.Cu")
		(net "GND")
	)
	(segment
		(start 133.1976 -15.6972)
		(end 133.2357 -15.6591)
		(width 0.4572)
		(layer "F.Cu")
		(net "GND")
	)
	(segment
		(start 70.779894 9.842246)
		(end 71.156068 9.466072)
		(width 0.5588)
		(layer "F.Cu")
		(net "GND")
	)
	(segment
		(start 90.9701 -17.18056)
		(end 90.9701 -16.5989)
		(width 0.3556)
		(layer "F.Cu")
		(net "GND")
	)
	(segment
		(start 132.1689 -12.5476)
		(end 132.9436 -12.5476)
		(width 0.4064)
		(layer "F.Cu")
		(net "GND")
	)
	(segment
		(start 22.3266 -15.1384)
		(end 22.2504 -15.1384)
		(width 0.4064)
		(layer "F.Cu")
		(net "GND")
	)
	(segment
		(start 122.5296 -11.7348)
		(end 122.047 -12.2174)
		(width 0.3048)
		(layer "F.Cu")
		(net "GND")
	)
	(segment
		(start 44.379896 9.842246)
		(end 44.75607 9.466072)
		(width 0.5588)
		(layer "F.Cu")
		(net "GND")
	)
	(segment
		(start 65.979802 12.133072)
		(end 65.979802 9.842246)
		(width 0.5588)
		(layer "F.Cu")
		(net "GND")
	)
	(segment
		(start 132.1181 -19.8882)
		(end 132.1181 -20.9042)
		(width 0.4064)
		(layer "F.Cu")
		(net "GND")
	)
	(segment
		(start 22.2504 -15.1384)
		(end 22.0472 -15.3416)
		(width 0.4064)
		(layer "F.Cu")
		(net "GND")
	)
	(segment
		(start 19.7485 -27.5209)
		(end 19.7866 -27.4828)
		(width 0.4064)
		(layer "F.Cu")
		(net "GND")
	)
	(segment
		(start 128.0414 -31.7246)
		(end 128.0668 -31.7246)
		(width 0.4572)
		(layer "F.Cu")
		(net "GND")
	)
	(segment
		(start 128.175004 12.234672)
		(end 128.175004 10.127996)
		(width 0.5588)
		(layer "F.Cu")
		(net "GND")
	)
	(segment
		(start 21.814536 -20.829524)
		(end 21.814536 -21.408136)
		(width 0.3048)
		(layer "F.Cu")
		(net "GND")
	)
	(segment
		(start 85.232748 -20.6375)
		(end 86.09076 -19.779488)
		(width 0.4572)
		(layer "F.Cu")
		(net "GND")
	)
	(segment
		(start 85.179916 9.842246)
		(end 85.55609 9.466072)
		(width 0.5588)
		(layer "F.Cu")
		(net "GND")
	)
	(segment
		(start 102.997 -22.1996)
		(end 102.4128 -22.7838)
		(width 0.4572)
		(layer "F.Cu")
		(net "GND")
	)
	(segment
		(start 99.86899 5.0038)
		(end 99.8347 5.0038)
		(width 0.4572)
		(layer "F.Cu")
		(net "GND")
	)
	(segment
		(start 122.9106 -8.0518)
		(end 122.53468 -8.0518)
		(width 0.3048)
		(layer "F.Cu")
		(net "GND")
	)
	(segment
		(start 126.8857 -0.9144)
		(end 126.8857 0.1524)
		(width 0.4064)
		(layer "F.Cu")
		(net "GND")
	)
	(segment
		(start 22.4155 -22.0091)
		(end 22.4155 -22.3012)
		(width 0.3048)
		(layer "F.Cu")
		(net "GND")
	)
	(segment
		(start 126.9873 -1.016)
		(end 126.9873 -1.165606)
		(width 0.4064)
		(layer "F.Cu")
		(net "GND")
	)
	(segment
		(start 65.979802 9.842246)
		(end 66.355976 9.466072)
		(width 0.5588)
		(layer "F.Cu")
		(net "GND")
	)
	(segment
		(start 20.467066 -15.30604)
		(end 20.502626 -15.3416)
		(width 0.4064)
		(layer "F.Cu")
		(net "GND")
	)
	(segment
		(start 132.1181 -20.9042)
		(end 132.1435 -20.9296)
		(width 0.4064)
		(layer "F.Cu")
		(net "GND")
	)
	(segment
		(start 75.579986 9.842246)
		(end 75.95616 9.466072)
		(width 0.5588)
		(layer "F.Cu")
		(net "GND")
	)
	(segment
		(start 118.3894 -19.1516)
		(end 118.0719 -19.4691)
		(width 0.4064)
		(layer "F.Cu")
		(net "GND")
	)
	(segment
		(start 130.7973 -29.5148)
		(end 130.2258 -29.5148)
		(width 0.4064)
		(layer "F.Cu")
		(net "GND")
	)
	(segment
		(start 98.175318 -21.183346)
		(end 99.186746 -21.183346)
		(width 0.3556)
		(layer "F.Cu")
		(net "GND")
	)
	(segment
		(start 118.4021 -26.7843)
		(end 118.2878 -26.67)
		(width 0.4572)
		(layer "F.Cu")
		(net "GND")
	)
	(segment
		(start 130.0734 -29.3624)
		(end 129.7305 -29.3624)
		(width 0.4064)
		(layer "F.Cu")
		(net "GND")
	)
	(segment
		(start 130.2258 -29.5148)
		(end 130.0734 -29.3624)
		(width 0.4064)
		(layer "F.Cu")
		(net "GND")
	)
	(segment
		(start 128.905 -22.02688)
		(end 128.905 -22.2377)
		(width 0.4572)
		(layer "F.Cu")
		(net "GND")
	)
	(segment
		(start 44.379896 12.133072)
		(end 44.379896 9.842246)
		(width 0.5588)
		(layer "F.Cu")
		(net "GND")
	)
	(segment
		(start 123.22048 -8.36168)
		(end 122.9106 -8.0518)
		(width 0.3048)
		(layer "F.Cu")
		(net "GND")
	)
	(segment
		(start 132.1435 -19.8628)
		(end 133.2611 -19.8628)
		(width 0.4064)
		(layer "F.Cu")
		(net "GND")
	)
	(segment
		(start 27.178 -25.4)
		(end 27.178 -24.7904)
		(width 0.508)
		(layer "F.Cu")
		(net "GND")
	)
	(segment
		(start 133.1722 -28.448)
		(end 133.6167 -28.8925)
		(width 0.4064)
		(layer "F.Cu")
		(net "GND")
	)
	(segment
		(start 21.3233 -24.1681)
		(end 20.9804 -24.1681)
		(width 0.508)
		(layer "F.Cu")
		(net "GND")
	)
	(segment
		(start 118.4021 -27.6098)
		(end 118.4021 -26.7843)
		(width 0.4572)
		(layer "F.Cu")
		(net "GND")
	)
	(segment
		(start 53.979826 9.842246)
		(end 54.356 9.466072)
		(width 0.5588)
		(layer "F.Cu")
		(net "GND")
	)
	(segment
		(start 131.162552 -32.531812)
		(end 131.162552 -33.524952)
		(width 0.4064)
		(layer "F.Cu")
		(net "GND")
	)
	(segment
		(start 30.332172 10.329672)
		(end 29.979874 10.68197)
		(width 0.5588)
		(layer "F.Cu")
		(net "GND")
	)
	(segment
		(start 61.179964 12.133072)
		(end 61.179964 9.842246)
		(width 0.5588)
		(layer "F.Cu")
		(net "GND")
	)
	(segment
		(start 131.1402 -9.6266)
		(end 130.4417 -10.3251)
		(width 0.4064)
		(layer "F.Cu")
		(net "GND")
	)
	(segment
		(start 100.1268 -22.1234)
		(end 100.1268 -22.7584)
		(width 0.3556)
		(layer "F.Cu")
		(net "GND")
	)
	(segment
		(start 20.9804 -24.1681)
		(end 20.7772 -23.9649)
		(width 0.508)
		(layer "F.Cu")
		(net "GND")
	)
	(segment
		(start 127.2286 -21.59)
		(end 127.315976 -21.502624)
		(width 0.508)
		(layer "F.Cu")
		(net "GND")
	)
	(segment
		(start 111.374936 10.61974)
		(end 111.374936 9.943846)
		(width 0.5588)
		(layer "F.Cu")
		(net "GND")
	)
	(segment
		(start 85.179916 12.133072)
		(end 85.179916 9.842246)
		(width 0.5588)
		(layer "F.Cu")
		(net "GND")
	)
	(segment
		(start 119.1387 -5.9944)
		(end 117.9576 -5.9944)
		(width 0.4572)
		(layer "F.Cu")
		(net "GND")
	)
	(segment
		(start 128.0668 -31.7246)
		(end 128.4859 -31.3055)
		(width 0.4572)
		(layer "F.Cu")
		(net "GND")
	)
	(segment
		(start 117.6528 -19.4691)
		(end 117.6528 -20.1676)
		(width 0.4064)
		(layer "F.Cu")
		(net "GND")
	)
	(segment
		(start 132.715 -2.7432)
		(end 133.223 -3.2512)
		(width 0.4064)
		(layer "F.Cu")
		(net "GND")
	)
	(segment
		(start 97.179892 12.133072)
		(end 97.179892 9.689338)
		(width 0.5588)
		(layer "F.Cu")
		(net "GND")
	)
	(segment
		(start 132.1435 -15.6972)
		(end 133.1976 -15.6972)
		(width 0.4572)
		(layer "F.Cu")
		(net "GND")
	)
	(segment
		(start 131.1275 -8.763)
		(end 131.1402 -8.7757)
		(width 0.4064)
		(layer "F.Cu")
		(net "GND")
	)
	(segment
		(start 22.4155 -22.3012)
		(end 22.4155 -23.2029)
		(width 0.3048)
		(layer "F.Cu")
		(net "GND")
	)
	(segment
		(start 132.6769 -7.8232)
		(end 133.096 -7.8232)
		(width 0.4064)
		(layer "F.Cu")
		(net "GND")
	)
	(segment
		(start 133.505448 -31.018988)
		(end 134.893812 -31.018988)
		(width 0.4064)
		(layer "F.Cu")
		(net "GND")
	)
	(segment
		(start 108.97489 9.943846)
		(end 109.351064 9.567672)
		(width 0.5588)
		(layer "F.Cu")
		(net "GND")
	)
	(segment
		(start 131.8387 -24.4856)
		(end 131.8514 -24.4983)
		(width 0.4064)
		(layer "F.Cu")
		(net "GND")
	)
	(segment
		(start 130.4417 -10.3251)
		(end 130.2512 -10.3251)
		(width 0.4064)
		(layer "F.Cu")
		(net "GND")
	)
	(segment
		(start 117.9576 -5.9944)
		(end 117.8306 -6.1214)
		(width 0.4572)
		(layer "F.Cu")
		(net "GND")
	)
	(segment
		(start 128.380744 -21.502624)
		(end 128.905 -22.02688)
		(width 0.4572)
		(layer "F.Cu")
		(net "GND")
	)
	(segment
		(start 87.579962 9.842246)
		(end 87.956136 9.466072)
		(width 0.5588)
		(layer "F.Cu")
		(net "GND")
	)
	(segment
		(start 120.5738 -24.96185)
		(end 120.5738 -25.24252)
		(width 0.4064)
		(layer "F.Cu")
		(net "GND")
	)
	(segment
		(start 132.5245 -2.7432)
		(end 132.715 -2.7432)
		(width 0.4064)
		(layer "F.Cu")
		(net "GND")
	)
	(segment
		(start 73.17994 12.133072)
		(end 73.17994 9.842246)
		(width 0.5588)
		(layer "F.Cu")
		(net "GND")
	)
	(segment
		(start 133.096 -7.8232)
		(end 133.5532 -7.366)
		(width 0.4064)
		(layer "F.Cu")
		(net "GND")
	)
	(segment
		(start 100.8126 4.572)
		(end 100.366322 4.572)
		(width 0.4572)
		(layer "F.Cu")
		(net "GND")
	)
	(segment
		(start 80.379824 12.133072)
		(end 80.379824 9.842246)
		(width 0.5588)
		(layer "F.Cu")
		(net "GND")
	)
	(segment
		(start 121.42978 -29.616654)
		(end 120.294146 -29.616654)
		(width 0.3048)
		(layer "F.Cu")
		(net "GND")
	)
	(segment
		(start 133.6167 -28.8925)
		(end 133.6167 -29.5148)
		(width 0.4064)
		(layer "F.Cu")
		(net "GND")
	)
	(segment
		(start 119.1387 -5.9944)
		(end 119.1387 -7.0358)
		(width 0.4572)
		(layer "F.Cu")
		(net "GND")
	)
	(segment
		(start 30.988 9.4488)
		(end 30.332172 10.104628)
		(width 0.5588)
		(layer "F.Cu")
		(net "GND")
	)
	(segment
		(start 130.57505 10.00125)
		(end 130.57505 12.234672)
		(width 0.5588)
		(layer "F.Cu")
		(net "GND")
	)
	(segment
		(start 28.1813 9.6774)
		(end 27.579828 10.278872)
		(width 0.5588)
		(layer "F.Cu")
		(net "GND")
	)
	(segment
		(start 94.779846 12.133072)
		(end 94.779846 9.842246)
		(width 0.5588)
		(layer "F.Cu")
		(net "GND")
	)
	(segment
		(start 133.223 -3.2512)
		(end 133.4516 -3.2512)
		(width 0.4064)
		(layer "F.Cu")
		(net "GND")
	)
	(segment
		(start 90.9701 -16.5989)
		(end 90.7796 -16.4084)
		(width 0.3556)
		(layer "F.Cu")
		(net "GND")
	)
	(segment
		(start 34.779966 12.133072)
		(end 34.779966 9.842246)
		(width 0.5588)
		(layer "F.Cu")
		(net "GND")
	)
	(segment
		(start 21.0566 6.0452)
		(end 20.5867 6.5151)
		(width 0.381)
		(layer "F.Cu")
		(net "GND")
	)
	(segment
		(start 118.304056 -9.144)
		(end 117.121432 -7.961376)
		(width 0.4572)
		(layer "F.Cu")
		(net "GND")
	)
	(segment
		(start 120.786398 -23.422102)
		(end 120.786398 -24.749252)
		(width 0.4064)
		(layer "F.Cu")
		(net "GND")
	)
	(segment
		(start 68.379848 12.133072)
		(end 68.379848 9.842246)
		(width 0.5588)
		(layer "F.Cu")
		(net "GND")
	)
	(segment
		(start 26.9621 -25.6032)
		(end 27.1653 -25.4)
		(width 0.508)
		(layer "F.Cu")
		(net "GND")
	)
	(segment
		(start 126.619 -21.6027)
		(end 126.6317 -21.59)
		(width 0.508)
		(layer "F.Cu")
		(net "GND")
	)
	(segment
		(start 116.175028 12.234672)
		(end 116.175028 9.943846)
		(width 0.5588)
		(layer "F.Cu")
		(net "GND")
	)
	(segment
		(start 77.979778 12.133072)
		(end 77.979778 9.842246)
		(width 0.5588)
		(layer "F.Cu")
		(net "GND")
	)
	(segment
		(start 29.979874 10.68197)
		(end 29.979874 12.133072)
		(width 0.5588)
		(layer "F.Cu")
		(net "GND")
	)
	(segment
		(start 124.2187 -22.352)
		(end 124.468636 -22.352)
		(width 0.4064)
		(layer "F.Cu")
		(net "GND")
	)
	(segment
		(start 63.58001 9.842246)
		(end 63.956184 9.466072)
		(width 0.5588)
		(layer "F.Cu")
		(net "GND")
	)
	(segment
		(start 21.1074 5.8547)
		(end 21.0566 5.9055)
		(width 0.381)
		(layer "F.Cu")
		(net "GND")
	)
	(segment
		(start 19.7866 -27.432)
		(end 19.7866 -27.4828)
		(width 0.3048)
		(layer "F.Cu")
		(net "GND")
	)
	(segment
		(start 108.97489 12.234418)
		(end 108.97489 9.943846)
		(width 0.5588)
		(layer "F.Cu")
		(net "GND")
	)
	(segment
		(start 113.774982 12.234672)
		(end 113.774982 9.943846)
		(width 0.5588)
		(layer "F.Cu")
		(net "GND")
	)
	(segment
		(start 118.7069 -19.1516)
		(end 118.3894 -19.1516)
		(width 0.4064)
		(layer "F.Cu")
		(net "GND")
	)
	(segment
		(start 39.579804 9.842246)
		(end 39.955978 9.466072)
		(width 0.5588)
		(layer "F.Cu")
		(net "GND")
	)
	(segment
		(start 127.6096 -1.787906)
		(end 127.6096 -1.8034)
		(width 0.4064)
		(layer "F.Cu")
		(net "GND")
	)
	(segment
		(start 70.779894 12.133072)
		(end 70.779894 9.842246)
		(width 0.5588)
		(layer "F.Cu")
		(net "GND")
	)
	(segment
		(start 120.786398 -24.749252)
		(end 120.5738 -24.96185)
		(width 0.4064)
		(layer "F.Cu")
		(net "GND")
	)
	(segment
		(start 43.688 1.006856)
		(end 43.688 0.48514)
		(width 0.3556)
		(layer "F.Cu")
		(net "GND")
	)
	(segment
		(start 128.175004 10.127996)
		(end 128.6764 9.6266)
		(width 0.5588)
		(layer "F.Cu")
		(net "GND")
	)
	(segment
		(start 22.0472 -15.3416)
		(end 21.5519 -15.3416)
		(width 0.4064)
		(layer "F.Cu")
		(net "GND")
	)
	(segment
		(start 131.1402 -8.7757)
		(end 131.1402 -9.6266)
		(width 0.4064)
		(layer "F.Cu")
		(net "GND")
	)
	(segment
		(start 123.952 1.8288)
		(end 124.206 1.5748)
		(width 0.4064)
		(layer "F.Cu")
		(net "GND")
	)
	(segment
		(start 128.4859 -31.3055)
		(end 128.8796 -31.3055)
		(width 0.4572)
		(layer "F.Cu")
		(net "GND")
	)
	(segment
		(start 19.7485 -27.7876)
		(end 19.7485 -27.5209)
		(width 0.4064)
		(layer "F.Cu")
		(net "GND")
	)
	(segment
		(start 20.379944 9.2964)
		(end 20.379944 12.133072)
		(width 0.5588)
		(layer "F.Cu")
		(net "GND")
	)
	(segment
		(start 123.374912 9.943846)
		(end 123.751086 9.567672)
		(width 0.5588)
		(layer "F.Cu")
		(net "GND")
	)
	(segment
		(start 132.1435 -16.7386)
		(end 132.1435 -15.6972)
		(width 0.4572)
		(layer "F.Cu")
		(net "GND")
	)
	(segment
		(start 83.3628 -20.6883)
		(end 83.3628 -19.5072)
		(width 0.4572)
		(layer "F.Cu")
		(net "GND")
	)
	(segment
		(start 94.779846 9.842246)
		(end 95.15602 9.466072)
		(width 0.5588)
		(layer "F.Cu")
		(net "GND")
	)
	(segment
		(start 19.1643 -28.3718)
		(end 19.7485 -27.7876)
		(width 0.4064)
		(layer "F.Cu")
		(net "GND")
	)
	(segment
		(start 49.179988 12.133072)
		(end 49.179988 9.842246)
		(width 0.5588)
		(layer "F.Cu")
		(net "GND")
	)
	(segment
		(start 122.5296 -11.3538)
		(end 122.5296 -11.7348)
		(width 0.3048)
		(layer "F.Cu")
		(net "GND")
	)
	(segment
		(start 22.4155 -23.2029)
		(end 22.2758 -23.3426)
		(width 0.3048)
		(layer "F.Cu")
		(net "GND")
	)
	(segment
		(start 56.379872 9.842246)
		(end 56.756046 9.466072)
		(width 0.5588)
		(layer "F.Cu")
		(net "GND")
	)
	(segment
		(start 21.814536 -21.408136)
		(end 22.4155 -22.0091)
		(width 0.3048)
		(layer "F.Cu")
		(net "GND")
	)
	(segment
		(start 84.5566 -19.1516)
		(end 84.8106 -19.4056)
		(width 0.4572)
		(layer "F.Cu")
		(net "GND")
	)
	(segment
		(start 123.375166 12.234672)
		(end 123.374912 10.40892)
		(width 0.5588)
		(layer "F.Cu")
		(net "GND")
	)
	(segment
		(start 122.047 -12.2174)
		(end 122.047 -12.32408)
		(width 0.3048)
		(layer "F.Cu")
		(net "GND")
	)
	(segment
		(start 58.779918 12.133072)
		(end 58.779918 9.842246)
		(width 0.5588)
		(layer "F.Cu")
		(net "GND")
	)
	(segment
		(start 119.1387 -9.144)
		(end 118.304056 -9.144)
		(width 0.4572)
		(layer "F.Cu")
		(net "GND")
	)
	(segment
		(start 118.575074 9.943846)
		(end 118.951248 9.567672)
		(width 0.5588)
		(layer "F.Cu")
		(net "GND")
	)
	(segment
		(start 75.579986 12.133072)
		(end 75.579986 9.842246)
		(width 0.5588)
		(layer "F.Cu")
		(net "GND")
	)
	(segment
		(start 21.0566 5.9055)
		(end 21.0566 6.0452)
		(width 0.381)
		(layer "F.Cu")
		(net "GND")
	)
	(segment
		(start 125.774958 9.943846)
		(end 126.151132 9.567672)
		(width 0.5588)
		(layer "F.Cu")
		(net "GND")
	)
	(segment
		(start 19.968464 -27.250136)
		(end 19.7866 -27.432)
		(width 0.3048)
		(layer "F.Cu")
		(net "GND")
	)
	(segment
		(start 124.206 1.5748)
		(end 124.7013 1.5748)
		(width 0.4064)
		(layer "F.Cu")
		(net "GND")
	)
	(segment
		(start 99.186746 -21.183346)
		(end 100.1268 -22.1234)
		(width 0.3556)
		(layer "F.Cu")
		(net "GND")
	)
	(segment
		(start 61.179964 9.842246)
		(end 61.556138 9.466072)
		(width 0.5588)
		(layer "F.Cu")
		(net "GND")
	)
	(segment
		(start 125.774958 12.234672)
		(end 125.774958 9.943846)
		(width 0.5588)
		(layer "F.Cu")
		(net "GND")
	)
	(segment
		(start 20.502626 -15.3416)
		(end 21.5519 -15.3416)
		(width 0.4064)
		(layer "F.Cu")
		(net "GND")
	)
	(segment
		(start 37.180012 12.133072)
		(end 37.180012 9.842246)
		(width 0.5588)
		(layer "F.Cu")
		(net "GND")
	)
	(segment
		(start 73.17994 9.842246)
		(end 73.556114 9.466072)
		(width 0.5588)
		(layer "F.Cu")
		(net "GND")
	)
	(segment
		(start 53.979826 12.133072)
		(end 53.979826 9.842246)
		(width 0.5588)
		(layer "F.Cu")
		(net "GND")
	)
	(segment
		(start 82.77987 12.133072)
		(end 82.77987 9.842246)
		(width 0.5588)
		(layer "F.Cu")
		(net "GND")
	)
	(segment
		(start 39.579804 12.133072)
		(end 39.579804 9.842246)
		(width 0.5588)
		(layer "F.Cu")
		(net "GND")
	)
	(segment
		(start 30.332172 10.104628)
		(end 30.332172 10.329672)
		(width 0.5588)
		(layer "F.Cu")
		(net "GND")
	)
	(segment
		(start 82.77987 9.842246)
		(end 83.156044 9.466072)
		(width 0.5588)
		(layer "F.Cu")
		(net "GND")
	)
	(segment
		(start 92.3798 12.133072)
		(end 92.3798 9.842246)
		(width 0.5588)
		(layer "F.Cu")
		(net "GND")
	)
	(segment
		(start 89.980008 12.133072)
		(end 89.980008 9.842246)
		(width 0.5588)
		(layer "F.Cu")
		(net "GND")
	)
	(segment
		(start 111.374936 9.943846)
		(end 111.75111 9.567672)
		(width 0.5588)
		(layer "F.Cu")
		(net "GND")
	)
	(segment
		(start 77.979778 9.842246)
		(end 78.355952 9.466072)
		(width 0.5588)
		(layer "F.Cu")
		(net "GND")
	)
	(segment
		(start 100.366322 4.572)
		(end 100.03155 4.84124)
		(width 0.4572)
		(layer "F.Cu")
		(net "GND")
	)
	(segment
		(start 83.7184 -19.1516)
		(end 84.5566 -19.1516)
		(width 0.4572)
		(layer "F.Cu")
		(net "GND")
	)
	(segment
		(start 83.4136 -20.6375)
		(end 83.3628 -20.6883)
		(width 0.4572)
		(layer "F.Cu")
		(net "GND")
	)
	(segment
		(start 127.569976 -21.502624)
		(end 128.380744 -21.502624)
		(width 0.4572)
		(layer "F.Cu")
		(net "GND")
	)
	(segment
		(start 108.975144 12.234672)
		(end 108.97489 12.234418)
		(width 0.5588)
		(layer "F.Cu")
		(net "GND")
	)
	(segment
		(start 123.7361 -22.8346)
		(end 124.2187 -22.352)
		(width 0.4064)
		(layer "F.Cu")
		(net "GND")
	)
	(segment
		(start 20.699476 -27.250136)
		(end 19.968464 -27.250136)
		(width 0.3048)
		(layer "F.Cu")
		(net "GND")
	)
	(segment
		(start 118.575074 12.234672)
		(end 118.575074 9.943846)
		(width 0.5588)
		(layer "F.Cu")
		(net "GND")
	)
	(segment
		(start 130.8481 -24.4856)
		(end 131.8387 -24.4856)
		(width 0.4064)
		(layer "F.Cu")
		(net "GND")
	)
	(segment
		(start 120.294146 -29.616654)
		(end 120.2182 -29.6926)
		(width 0.3048)
		(layer "F.Cu")
		(net "GND")
	)
	(segment
		(start 84.4804 -20.6375)
		(end 83.4136 -20.6375)
		(width 0.4572)
		(layer "F.Cu")
		(net "GND")
	)
	(segment
		(start 124.7013 1.5748)
		(end 124.7013 0.6604)
		(width 0.4064)
		(layer "F.Cu")
		(net "GND")
	)
	(segment
		(start 123.22048 -8.8138)
		(end 123.22048 -8.36168)
		(width 0.3048)
		(layer "F.Cu")
		(net "GND")
	)
	(segment
		(start 111.37519 12.234672)
		(end 111.374936 10.61974)
		(width 0.5588)
		(layer "F.Cu")
		(net "GND")
	)
	(segment
		(start 117.6528 -20.1676)
		(end 117.4242 -20.3962)
		(width 0.4064)
		(layer "F.Cu")
		(net "GND")
	)
	(segment
		(start 124.7013 0.6604)
		(end 124.968 0.3937)
		(width 0.4064)
		(layer "F.Cu")
		(net "GND")
	)
	(segment
		(start 28.1813 9.398)
		(end 28.1813 9.6774)
		(width 0.5588)
		(layer "F.Cu")
		(net "GND")
	)
	(segment
		(start 20.5867 6.5151)
		(end 20.5867 6.5913)
		(width 0.381)
		(layer "F.Cu")
		(net "GND")
	)
	(segment
		(start 130.0988 9.525)
		(end 130.57505 10.00125)
		(width 0.5588)
		(layer "F.Cu")
		(net "GND")
	)
	(segment
		(start 27.1653 -25.4)
		(end 27.178 -25.4)
		(width 0.508)
		(layer "F.Cu")
		(net "GND")
	)
	(segment
		(start 123.374912 10.40892)
		(end 123.374912 9.943846)
		(width 0.5588)
		(layer "F.Cu")
		(net "GND")
	)
	(via
		(at 29.2227 -4.0767)
		(size 0.5588)
		(drill 0.3048)
		(layers "F.Cu" "B.Cu")
		(net "GND")
	)
	(via
		(at 117.5512 -33.2232)
		(size 0.508)
		(drill 0.254)
		(layers "F.Cu" "B.Cu")
		(net "GND")
	)
	(via
		(at 4.8006 -33.782)
		(size 0.508)
		(drill 0.254)
		(layers "F.Cu" "B.Cu")
		(net "GND")
	)
	(via
		(at 20.8534 -34.1503)
		(size 0.5588)
		(drill 0.3048)
		(layers "F.Cu" "B.Cu")
		(net "GND")
	)
	(via
		(at 68.756022 9.466072)
		(size 0.508)
		(drill 0.254)
		(layers "F.Cu" "B.Cu")
		(net "GND")
	)
	(via
		(at 32.4104 -15.5956)
		(size 0.5588)
		(drill 0.3048)
		(layers "F.Cu" "B.Cu")
		(net "GND")
	)
	(via
		(at 63.956184 9.466072)
		(size 0.508)
		(drill 0.254)
		(layers "F.Cu" "B.Cu")
		(net "GND")
	)
	(via
		(at 21.7932 -27.0256)
		(size 0.508)
		(drill 0.254)
		(layers "F.Cu" "B.Cu")
		(net "GND")
	)
	(via
		(at 1.8923 -17.7419)
		(size 0.508)
		(drill 0.254)
		(layers "F.Cu" "B.Cu")
		(net "GND")
	)
	(via
		(at 131.8514 -24.4983)
		(size 0.508)
		(drill 0.254)
		(layers "F.Cu" "B.Cu")
		(net "GND")
	)
	(via
		(at 134.893812 -31.018988)
		(size 0.508)
		(drill 0.254)
		(layers "F.Cu" "B.Cu")
		(net "GND")
	)
	(via
		(at 81.069688 6.435852)
		(size 0.508)
		(drill 0.254)
		(layers "F.Cu" "B.Cu")
		(net "GND")
	)
	(via
		(at 27.2034 3.4417)
		(size 0.5588)
		(drill 0.3048)
		(layers "F.Cu" "B.Cu")
		(net "GND")
	)
	(via
		(at 92.755974 9.466072)
		(size 0.508)
		(drill 0.254)
		(layers "F.Cu" "B.Cu")
		(net "GND")
	)
	(via
		(at 113.00714 6.476492)
		(size 0.508)
		(drill 0.254)
		(layers "F.Cu" "B.Cu")
		(net "GND")
	)
	(via
		(at 25.5651 -34.1503)
		(size 0.5588)
		(drill 0.3048)
		(layers "F.Cu" "B.Cu")
		(net "GND")
	)
	(via
		(at 119.48414 6.476492)
		(size 0.508)
		(drill 0.254)
		(layers "F.Cu" "B.Cu")
		(net "GND")
	)
	(via
		(at 124.0282 -19.2786)
		(size 0.508)
		(drill 0.254)
		(layers "F.Cu" "B.Cu")
		(net "GND")
	)
	(via
		(at 125.96114 6.476492)
		(size 0.508)
		(drill 0.254)
		(layers "F.Cu" "B.Cu")
		(net "GND")
	)
	(via
		(at 127.25654 6.476492)
		(size 0.508)
		(drill 0.254)
		(layers "F.Cu" "B.Cu")
		(net "GND")
	)
	(via
		(at 116.551202 9.567672)
		(size 0.508)
		(drill 0.254)
		(layers "F.Cu" "B.Cu")
		(net "GND")
	)
	(via
		(at 27.4574 -4.0894)
		(size 0.5588)
		(drill 0.3048)
		(layers "F.Cu" "B.Cu")
		(net "GND")
	)
	(via
		(at 127.6096 -1.8034)
		(size 0.508)
		(drill 0.254)
		(layers "F.Cu" "B.Cu")
		(net "GND")
	)
	(via
		(at 19.0754 -10.2743)
		(size 0.508)
		(drill 0.254)
		(layers "F.Cu" "B.Cu")
		(net "GND")
	)
	(via
		(at 40.7543 -0.8255)
		(size 0.5588)
		(drill 0.3048)
		(layers "F.Cu" "B.Cu")
		(net "GND")
	)
	(via
		(at 21.5646 -18.7198)
		(size 0.508)
		(drill 0.254)
		(layers "F.Cu" "B.Cu")
		(net "GND")
	)
	(via
		(at 21.7678 -34.1503)
		(size 0.5588)
		(drill 0.3048)
		(layers "F.Cu" "B.Cu")
		(net "GND")
	)
	(via
		(at 28.3591 -4.1021)
		(size 0.5588)
		(drill 0.3048)
		(layers "F.Cu" "B.Cu")
		(net "GND")
	)
	(via
		(at 116.89334 6.476492)
		(size 0.508)
		(drill 0.254)
		(layers "F.Cu" "B.Cu")
		(net "GND")
	)
	(via
		(at 22.3266 -15.1384)
		(size 0.5588)
		(drill 0.3048)
		(layers "F.Cu" "B.Cu")
		(net "GND")
	)
	(via
		(at 28.3972 -4.9276)
		(size 0.5588)
		(drill 0.3048)
		(layers "F.Cu" "B.Cu")
		(net "GND")
	)
	(via
		(at 124.468636 -22.352)
		(size 0.508)
		(drill 0.254)
		(layers "F.Cu" "B.Cu")
		(net "GND")
	)
	(via
		(at 1.4097 -13.3858)
		(size 0.508)
		(drill 0.254)
		(layers "F.Cu" "B.Cu")
		(net "GND")
	)
	(via
		(at 120.2182 -29.6926)
		(size 0.508)
		(drill 0.254)
		(layers "F.Cu" "B.Cu")
		(net "GND")
	)
	(via
		(at 114.8588 -33.3248)
		(size 0.508)
		(drill 0.254)
		(layers "F.Cu" "B.Cu")
		(net "GND")
	)
	(via
		(at 45.6057 -3.4163)
		(size 0.5588)
		(drill 0.3048)
		(layers "F.Cu" "B.Cu")
		(net "GND")
	)
	(via
		(at 16.129 -4.6736)
		(size 0.508)
		(drill 0.254)
		(layers "F.Cu" "B.Cu")
		(net "GND")
	)
	(via
		(at 110.41634 6.476492)
		(size 0.508)
		(drill 0.254)
		(layers "F.Cu" "B.Cu")
		(net "GND")
	)
	(via
		(at 75.95616 9.466072)
		(size 0.508)
		(drill 0.254)
		(layers "F.Cu" "B.Cu")
		(net "GND")
	)
	(via
		(at 122.53468 -8.0518)
		(size 0.508)
		(drill 0.254)
		(layers "F.Cu" "B.Cu")
		(net "GND")
	)
	(via
		(at 97.909888 6.435852)
		(size 0.508)
		(drill 0.254)
		(layers "F.Cu" "B.Cu")
		(net "GND")
	)
	(via
		(at 24.9428 -10.1092)
		(size 0.5588)
		(drill 0.3048)
		(layers "F.Cu" "B.Cu")
		(net "GND")
	)
	(via
		(at 133.2357 -15.6591)
		(size 0.508)
		(drill 0.254)
		(layers "F.Cu" "B.Cu")
		(net "GND")
	)
	(via
		(at 115.59794 6.476492)
		(size 0.508)
		(drill 0.254)
		(layers "F.Cu" "B.Cu")
		(net "GND")
	)
	(via
		(at 6.8326 -16.7894)
		(size 0.508)
		(drill 0.254)
		(layers "F.Cu" "B.Cu")
		(net "GND")
	)
	(via
		(at 133.0452 -10.4394)
		(size 0.508)
		(drill 0.254)
		(layers "F.Cu" "B.Cu")
		(net "GND")
	)
	(via
		(at 7.7978 -13.4747)
		(size 0.508)
		(drill 0.254)
		(layers "F.Cu" "B.Cu")
		(net "GND")
	)
	(via
		(at 20.5867 6.5913)
		(size 0.508)
		(drill 0.254)
		(layers "F.Cu" "B.Cu")
		(net "GND")
	)
	(via
		(at 133.7945 -17.1704)
		(size 0.7112)
		(drill 0.3556)
		(layers "F.Cu" "B.Cu")
		(net "GND")
	)
	(via
		(at 24.3332 -12.4206)
		(size 0.5588)
		(drill 0.3048)
		(layers "F.Cu" "B.Cu")
		(net "GND")
	)
	(via
		(at 123.751086 9.567672)
		(size 0.508)
		(drill 0.254)
		(layers "F.Cu" "B.Cu")
		(net "GND")
	)
	(via
		(at 117.121432 -7.961376)
		(size 0.508)
		(drill 0.254)
		(layers "F.Cu" "B.Cu")
		(net "GND")
	)
	(via
		(at 128.0414 -31.7246)
		(size 0.508)
		(drill 0.254)
		(layers "F.Cu" "B.Cu")
		(net "GND")
	)
	(via
		(at 19.1008 -20.1422)
		(size 0.508)
		(drill 0.254)
		(layers "F.Cu" "B.Cu")
		(net "GND")
	)
	(via
		(at 135.9789 -33.3883)
		(size 0.508)
		(drill 0.254)
		(layers "F.Cu" "B.Cu")
		(net "GND")
	)
	(via
		(at 133.5532 -7.366)
		(size 0.508)
		(drill 0.254)
		(layers "F.Cu" "B.Cu")
		(net "GND")
	)
	(via
		(at 102.4128 -22.7838)
		(size 0.508)
		(drill 0.254)
		(layers "F.Cu" "B.Cu")
		(net "GND")
	)
	(via
		(at 124.5108 -34.036)
		(size 0.508)
		(drill 0.254)
		(layers "F.Cu" "B.Cu")
		(net "GND")
	)
	(via
		(at 40.7797 -2.6162)
		(size 0.5588)
		(drill 0.3048)
		(layers "F.Cu" "B.Cu")
		(net "GND")
	)
	(via
		(at 32.756094 9.466072)
		(size 0.508)
		(drill 0.254)
		(layers "F.Cu" "B.Cu")
		(net "GND")
	)
	(via
		(at 53.4797 -3.8608)
		(size 0.508)
		(drill 0.254)
		(layers "F.Cu" "B.Cu")
		(net "GND")
	)
	(via
		(at 121.351294 9.567672)
		(size 0.508)
		(drill 0.254)
		(layers "F.Cu" "B.Cu")
		(net "GND")
	)
	(via
		(at 13.6652 -34.1376)
		(size 0.5588)
		(drill 0.3048)
		(layers "F.Cu" "B.Cu")
		(net "GND")
	)
	(via
		(at 24.9682 -9.2964)
		(size 0.5588)
		(drill 0.3048)
		(layers "F.Cu" "B.Cu")
		(net "GND")
	)
	(via
		(at 129.8448 -30.7086)
		(size 0.508)
		(drill 0.254)
		(layers "F.Cu" "B.Cu")
		(net "GND")
	)
	(via
		(at 27.4955 -4.9149)
		(size 0.5588)
		(drill 0.3048)
		(layers "F.Cu" "B.Cu")
		(net "GND")
	)
	(via
		(at 123.2916 -28.1178)
		(size 0.508)
		(drill 0.254)
		(layers "F.Cu" "B.Cu")
		(net "GND")
	)
	(via
		(at 95.15602 9.466072)
		(size 0.508)
		(drill 0.254)
		(layers "F.Cu" "B.Cu")
		(net "GND")
	)
	(via
		(at 49.556162 9.466072)
		(size 0.508)
		(drill 0.254)
		(layers "F.Cu" "B.Cu")
		(net "GND")
	)
	(via
		(at 22.7076 -34.1503)
		(size 0.5588)
		(drill 0.3048)
		(layers "F.Cu" "B.Cu")
		(net "GND")
	)
	(via
		(at 1.3716 -19.8882)
		(size 0.508)
		(drill 0.254)
		(layers "F.Cu" "B.Cu")
		(net "GND")
	)
	(via
		(at 24.5364 -25.273)
		(size 0.508)
		(drill 0.254)
		(layers "F.Cu" "B.Cu")
		(net "GND")
	)
	(via
		(at 129.84734 6.476492)
		(size 0.508)
		(drill 0.254)
		(layers "F.Cu" "B.Cu")
		(net "GND")
	)
	(via
		(at 118.2878 -26.67)
		(size 0.508)
		(drill 0.254)
		(layers "F.Cu" "B.Cu")
		(net "GND")
	)
	(via
		(at 114.30254 6.476492)
		(size 0.508)
		(drill 0.254)
		(layers "F.Cu" "B.Cu")
		(net "GND")
	)
	(via
		(at 133.2865 -19.8374)
		(size 0.508)
		(drill 0.254)
		(layers "F.Cu" "B.Cu")
		(net "GND")
	)
	(via
		(at 79.774288 6.435852)
		(size 0.508)
		(drill 0.254)
		(layers "F.Cu" "B.Cu")
		(net "GND")
	)
	(via
		(at 128.6764 9.6266)
		(size 0.508)
		(drill 0.254)
		(layers "F.Cu" "B.Cu")
		(net "GND")
	)
	(via
		(at 1.359662 -30.804104)
		(size 0.508)
		(drill 0.254)
		(layers "F.Cu" "B.Cu")
		(net "GND")
	)
	(via
		(at 135.8392 -14.0335)
		(size 0.508)
		(drill 0.254)
		(layers "F.Cu" "B.Cu")
		(net "GND")
	)
	(via
		(at 78.355952 9.466072)
		(size 0.508)
		(drill 0.254)
		(layers "F.Cu" "B.Cu")
		(net "GND")
	)
	(via
		(at 39.9542 -0.6096)
		(size 0.508)
		(drill 0.254)
		(layers "F.Cu" "B.Cu")
		(net "GND")
	)
	(via
		(at 82.365088 6.435852)
		(size 0.508)
		(drill 0.254)
		(layers "F.Cu" "B.Cu")
		(net "GND")
	)
	(via
		(at 88.842088 6.435852)
		(size 0.508)
		(drill 0.254)
		(layers "F.Cu" "B.Cu")
		(net "GND")
	)
	(via
		(at 111.71174 6.476492)
		(size 0.508)
		(drill 0.254)
		(layers "F.Cu" "B.Cu")
		(net "GND")
	)
	(via
		(at 133.4516 -4.8514)
		(size 0.508)
		(drill 0.254)
		(layers "F.Cu" "B.Cu")
		(net "GND")
	)
	(via
		(at 126.151132 9.567672)
		(size 0.508)
		(drill 0.254)
		(layers "F.Cu" "B.Cu")
		(net "GND")
	)
	(via
		(at 19.812 -34.1503)
		(size 0.5588)
		(drill 0.3048)
		(layers "F.Cu" "B.Cu")
		(net "GND")
	)
	(via
		(at 47.156116 9.466072)
		(size 0.508)
		(drill 0.254)
		(layers "F.Cu" "B.Cu")
		(net "GND")
	)
	(via
		(at 77.0636 6.4516)
		(size 0.508)
		(drill 0.254)
		(layers "F.Cu" "B.Cu")
		(net "GND")
	)
	(via
		(at 27.2034 2.6289)
		(size 0.5588)
		(drill 0.3048)
		(layers "F.Cu" "B.Cu")
		(net "GND")
	)
	(via
		(at 100.8126 4.572)
		(size 0.508)
		(drill 0.254)
		(layers "F.Cu" "B.Cu")
		(net "GND")
	)
	(via
		(at 85.55609 9.466072)
		(size 0.508)
		(drill 0.254)
		(layers "F.Cu" "B.Cu")
		(net "GND")
	)
	(via
		(at 22.2758 -23.3426)
		(size 0.508)
		(drill 0.254)
		(layers "F.Cu" "B.Cu")
		(net "GND")
	)
	(via
		(at 39.955978 9.466072)
		(size 0.508)
		(drill 0.254)
		(layers "F.Cu" "B.Cu")
		(net "GND")
	)
	(via
		(at 27.178 -24.7904)
		(size 0.508)
		(drill 0.254)
		(layers "F.Cu" "B.Cu")
		(net "GND")
	)
	(via
		(at 18.0848 -15.0368)
		(size 0.508)
		(drill 0.254)
		(layers "F.Cu" "B.Cu")
		(net "GND")
	)
	(via
		(at 25.8826 -9.2964)
		(size 0.5588)
		(drill 0.3048)
		(layers "F.Cu" "B.Cu")
		(net "GND")
	)
	(via
		(at 128.55194 6.476492)
		(size 0.508)
		(drill 0.254)
		(layers "F.Cu" "B.Cu")
		(net "GND")
	)
	(via
		(at 123.9012 1.8288)
		(size 0.508)
		(drill 0.254)
		(layers "F.Cu" "B.Cu")
		(net "GND")
	)
	(via
		(at 144.9832 -20.0914)
		(size 0.508)
		(drill 0.254)
		(layers "F.Cu" "B.Cu")
		(net "GND")
	)
	(via
		(at 125.3236 -28.1178)
		(size 0.508)
		(drill 0.254)
		(layers "F.Cu" "B.Cu")
		(net "GND")
	)
	(via
		(at 18.8468 -34.1503)
		(size 0.5588)
		(drill 0.3048)
		(layers "F.Cu" "B.Cu")
		(net "GND")
	)
	(via
		(at 66.355976 9.466072)
		(size 0.508)
		(drill 0.254)
		(layers "F.Cu" "B.Cu")
		(net "GND")
	)
	(via
		(at 22.2758 -27.5844)
		(size 0.508)
		(drill 0.254)
		(layers "F.Cu" "B.Cu")
		(net "GND")
	)
	(via
		(at 56.756046 9.466072)
		(size 0.508)
		(drill 0.254)
		(layers "F.Cu" "B.Cu")
		(net "GND")
	)
	(via
		(at 124.27458 -28.11653)
		(size 0.508)
		(drill 0.254)
		(layers "F.Cu" "B.Cu")
		(net "GND")
	)
	(via
		(at 124.66574 6.476492)
		(size 0.508)
		(drill 0.254)
		(layers "F.Cu" "B.Cu")
		(net "GND")
	)
	(via
		(at 5.1943 -13.7795)
		(size 0.508)
		(drill 0.254)
		(layers "F.Cu" "B.Cu")
		(net "GND")
	)
	(via
		(at 114.151156 9.567672)
		(size 0.508)
		(drill 0.254)
		(layers "F.Cu" "B.Cu")
		(net "GND")
	)
	(via
		(at 78.478888 6.435852)
		(size 0.508)
		(drill 0.254)
		(layers "F.Cu" "B.Cu")
		(net "GND")
	)
	(via
		(at 23.4188 -12.4206)
		(size 0.5588)
		(drill 0.3048)
		(layers "F.Cu" "B.Cu")
		(net "GND")
	)
	(via
		(at 130.0988 -33.782)
		(size 0.508)
		(drill 0.254)
		(layers "F.Cu" "B.Cu")
		(net "GND")
	)
	(via
		(at 28.1813 9.398)
		(size 0.508)
		(drill 0.254)
		(layers "F.Cu" "B.Cu")
		(net "GND")
	)
	(via
		(at 1.359662 -23.184104)
		(size 0.508)
		(drill 0.254)
		(layers "F.Cu" "B.Cu")
		(net "GND")
	)
	(via
		(at 143.4465 -33.6677)
		(size 0.508)
		(drill 0.254)
		(layers "F.Cu" "B.Cu")
		(net "GND")
	)
	(via
		(at 94.023688 6.435852)
		(size 0.508)
		(drill 0.254)
		(layers "F.Cu" "B.Cu")
		(net "GND")
	)
	(via
		(at 33.909 -15.621)
		(size 0.5588)
		(drill 0.3048)
		(layers "F.Cu" "B.Cu")
		(net "GND")
	)
	(via
		(at 87.546688 6.435852)
		(size 0.508)
		(drill 0.254)
		(layers "F.Cu" "B.Cu")
		(net "GND")
	)
	(via
		(at 15.6718 -32.8168)
		(size 0.7112)
		(drill 0.3556)
		(layers "F.Cu" "B.Cu")
		(net "GND")
	)
	(via
		(at 26.5684 9.3345)
		(size 0.508)
		(drill 0.254)
		(layers "F.Cu" "B.Cu")
		(net "GND")
	)
	(via
		(at 84.8106 -19.4056)
		(size 0.508)
		(drill 0.254)
		(layers "F.Cu" "B.Cu")
		(net "GND")
	)
	(via
		(at 17.6784 -34.1376)
		(size 0.5588)
		(drill 0.3048)
		(layers "F.Cu" "B.Cu")
		(net "GND")
	)
	(via
		(at 109.8296 4.5974)
		(size 0.508)
		(drill 0.254)
		(layers "F.Cu" "B.Cu")
		(net "GND")
	)
	(via
		(at 95.319088 6.435852)
		(size 0.508)
		(drill 0.254)
		(layers "F.Cu" "B.Cu")
		(net "GND")
	)
	(via
		(at 100.1268 -22.7584)
		(size 0.508)
		(drill 0.254)
		(layers "F.Cu" "B.Cu")
		(net "GND")
	)
	(via
		(at 109.001052 6.49224)
		(size 0.508)
		(drill 0.254)
		(layers "F.Cu" "B.Cu")
		(net "GND")
	)
	(via
		(at 21.1074 -19.304)
		(size 0.508)
		(drill 0.254)
		(layers "F.Cu" "B.Cu")
		(net "GND")
	)
	(via
		(at 24.6253 -34.1503)
		(size 0.5588)
		(drill 0.3048)
		(layers "F.Cu" "B.Cu")
		(net "GND")
	)
	(via
		(at 131.4958 -33.8582)
		(size 0.508)
		(drill 0.254)
		(layers "F.Cu" "B.Cu")
		(net "GND")
	)
	(via
		(at 121.3104 -1.8542)
		(size 0.508)
		(drill 0.254)
		(layers "F.Cu" "B.Cu")
		(net "GND")
	)
	(via
		(at 118.18874 6.476492)
		(size 0.508)
		(drill 0.254)
		(layers "F.Cu" "B.Cu")
		(net "GND")
	)
	(via
		(at 27.6606 -19.177)
		(size 0.5588)
		(drill 0.3048)
		(layers "F.Cu" "B.Cu")
		(net "GND")
	)
	(via
		(at 36.2712 -24.257)
		(size 0.508)
		(drill 0.254)
		(layers "F.Cu" "B.Cu")
		(net "GND")
	)
	(via
		(at 133.1722 -28.448)
		(size 0.508)
		(drill 0.254)
		(layers "F.Cu" "B.Cu")
		(net "GND")
	)
	(via
		(at 83.660488 6.435852)
		(size 0.508)
		(drill 0.254)
		(layers "F.Cu" "B.Cu")
		(net "GND")
	)
	(via
		(at 111.75111 9.567672)
		(size 0.508)
		(drill 0.254)
		(layers "F.Cu" "B.Cu")
		(net "GND")
	)
	(via
		(at 1.1938 -15.2908)
		(size 0.508)
		(drill 0.254)
		(layers "F.Cu" "B.Cu")
		(net "GND")
	)
	(via
		(at 21.6408 -23.8506)
		(size 0.508)
		(drill 0.254)
		(layers "F.Cu" "B.Cu")
		(net "GND")
	)
	(via
		(at 25.8064 -10.9728)
		(size 0.5588)
		(drill 0.3048)
		(layers "F.Cu" "B.Cu")
		(net "GND")
	)
	(via
		(at 16.7132 -34.1376)
		(size 0.5588)
		(drill 0.3048)
		(layers "F.Cu" "B.Cu")
		(net "GND")
	)
	(via
		(at 73.556114 9.466072)
		(size 0.508)
		(drill 0.254)
		(layers "F.Cu" "B.Cu")
		(net "GND")
	)
	(via
		(at 24.892 -10.9728)
		(size 0.5588)
		(drill 0.3048)
		(layers "F.Cu" "B.Cu")
		(net "GND")
	)
	(via
		(at 71.156068 9.466072)
		(size 0.508)
		(drill 0.254)
		(layers "F.Cu" "B.Cu")
		(net "GND")
	)
	(via
		(at 23.6982 -34.1503)
		(size 0.5588)
		(drill 0.3048)
		(layers "F.Cu" "B.Cu")
		(net "GND")
	)
	(via
		(at 87.956136 9.466072)
		(size 0.508)
		(drill 0.254)
		(layers "F.Cu" "B.Cu")
		(net "GND")
	)
	(via
		(at 59.156092 9.466072)
		(size 0.508)
		(drill 0.254)
		(layers "F.Cu" "B.Cu")
		(net "GND")
	)
	(via
		(at 58.3057 -1.397)
		(size 0.508)
		(drill 0.254)
		(layers "F.Cu" "B.Cu")
		(net "GND")
	)
	(via
		(at 80.755998 9.466072)
		(size 0.508)
		(drill 0.254)
		(layers "F.Cu" "B.Cu")
		(net "GND")
	)
	(via
		(at 83.156044 9.466072)
		(size 0.508)
		(drill 0.254)
		(layers "F.Cu" "B.Cu")
		(net "GND")
	)
	(via
		(at 15.5956 -34.1376)
		(size 0.5588)
		(drill 0.3048)
		(layers "F.Cu" "B.Cu")
		(net "GND")
	)
	(via
		(at 90.356182 9.466072)
		(size 0.508)
		(drill 0.254)
		(layers "F.Cu" "B.Cu")
		(net "GND")
	)
	(via
		(at 120.77954 6.476492)
		(size 0.508)
		(drill 0.254)
		(layers "F.Cu" "B.Cu")
		(net "GND")
	)
	(via
		(at 109.351064 9.567672)
		(size 0.508)
		(drill 0.254)
		(layers "F.Cu" "B.Cu")
		(net "GND")
	)
	(via
		(at 21.59 -19.8628)
		(size 0.508)
		(drill 0.254)
		(layers "F.Cu" "B.Cu")
		(net "GND")
	)
	(via
		(at 130.0988 9.525)
		(size 0.508)
		(drill 0.254)
		(layers "F.Cu" "B.Cu")
		(net "GND")
	)
	(via
		(at 136.0551 -20.7772)
		(size 0.508)
		(drill 0.254)
		(layers "F.Cu" "B.Cu")
		(net "GND")
	)
	(via
		(at 97.282 -18.4404)
		(size 0.508)
		(drill 0.254)
		(layers "F.Cu" "B.Cu")
		(net "GND")
	)
	(via
		(at 35.15614 9.466072)
		(size 0.508)
		(drill 0.254)
		(layers "F.Cu" "B.Cu")
		(net "GND")
	)
	(via
		(at 22.8346 -23.9776)
		(size 0.508)
		(drill 0.254)
		(layers "F.Cu" "B.Cu")
		(net "GND")
	)
	(via
		(at 90.137488 6.435852)
		(size 0.508)
		(drill 0.254)
		(layers "F.Cu" "B.Cu")
		(net "GND")
	)
	(via
		(at 51.955954 9.466072)
		(size 0.508)
		(drill 0.254)
		(layers "F.Cu" "B.Cu")
		(net "GND")
	)
	(via
		(at 19.7866 -27.4828)
		(size 0.508)
		(drill 0.254)
		(layers "F.Cu" "B.Cu")
		(net "GND")
	)
	(via
		(at 6.9215 -19.2786)
		(size 0.508)
		(drill 0.254)
		(layers "F.Cu" "B.Cu")
		(net "GND")
	)
	(via
		(at 96.614488 6.435852)
		(size 0.508)
		(drill 0.254)
		(layers "F.Cu" "B.Cu")
		(net "GND")
	)
	(via
		(at 104.902 -2.6543)
		(size 0.508)
		(drill 0.254)
		(layers "F.Cu" "B.Cu")
		(net "GND")
	)
	(via
		(at 124.2822 -27.2034)
		(size 0.508)
		(drill 0.254)
		(layers "F.Cu" "B.Cu")
		(net "GND")
	)
	(via
		(at 132.9436 -12.5476)
		(size 0.508)
		(drill 0.254)
		(layers "F.Cu" "B.Cu")
		(net "GND")
	)
	(via
		(at 37.556186 9.466072)
		(size 0.508)
		(drill 0.254)
		(layers "F.Cu" "B.Cu")
		(net "GND")
	)
	(via
		(at 11.6967 -34.0106)
		(size 0.508)
		(drill 0.254)
		(layers "F.Cu" "B.Cu")
		(net "GND")
	)
	(via
		(at 120.473978 -25.342342)
		(size 0.508)
		(drill 0.254)
		(layers "F.Cu" "B.Cu")
		(net "GND")
	)
	(via
		(at 92.728288 6.435852)
		(size 0.508)
		(drill 0.254)
		(layers "F.Cu" "B.Cu")
		(net "GND")
	)
	(via
		(at 124.2822 -29.0576)
		(size 0.508)
		(drill 0.254)
		(layers "F.Cu" "B.Cu")
		(net "GND")
	)
	(via
		(at 31.3944 9.4488)
		(size 0.508)
		(drill 0.254)
		(layers "F.Cu" "B.Cu")
		(net "GND")
	)
	(via
		(at 124.6886 -15.9512)
		(size 0.508)
		(drill 0.254)
		(layers "F.Cu" "B.Cu")
		(net "GND")
	)
	(via
		(at 133.4516 -3.2512)
		(size 0.508)
		(drill 0.254)
		(layers "F.Cu" "B.Cu")
		(net "GND")
	)
	(via
		(at 14.605 -34.1376)
		(size 0.5588)
		(drill 0.3048)
		(layers "F.Cu" "B.Cu")
		(net "GND")
	)
	(via
		(at 1.2954 -26.67)
		(size 0.508)
		(drill 0.254)
		(layers "F.Cu" "B.Cu")
		(net "GND")
	)
	(via
		(at 28.43784 -18.67281)
		(size 0.5588)
		(drill 0.3048)
		(layers "F.Cu" "B.Cu")
		(net "GND")
	)
	(via
		(at 86.251288 6.435852)
		(size 0.508)
		(drill 0.254)
		(layers "F.Cu" "B.Cu")
		(net "GND")
	)
	(via
		(at 90.7796 -16.4084)
		(size 0.508)
		(drill 0.254)
		(layers "F.Cu" "B.Cu")
		(net "GND")
	)
	(via
		(at 22.7838 -27.0256)
		(size 0.508)
		(drill 0.254)
		(layers "F.Cu" "B.Cu")
		(net "GND")
	)
	(via
		(at 22.2504 -26.4414)
		(size 0.508)
		(drill 0.254)
		(layers "F.Cu" "B.Cu")
		(net "GND")
	)
	(via
		(at 123.37034 6.476492)
		(size 0.508)
		(drill 0.254)
		(layers "F.Cu" "B.Cu")
		(net "GND")
	)
	(via
		(at 37.9984 4.299458)
		(size 0.508)
		(drill 0.254)
		(layers "F.Cu" "B.Cu")
		(net "GND")
	)
	(via
		(at 103.1494 4.6482)
		(size 0.508)
		(drill 0.254)
		(layers "F.Cu" "B.Cu")
		(net "GND")
	)
	(via
		(at 22.2504 -24.511)
		(size 0.508)
		(drill 0.254)
		(layers "F.Cu" "B.Cu")
		(net "GND")
	)
	(via
		(at 43.402504 1.292352)
		(size 0.508)
		(drill 0.254)
		(layers "F.Cu" "B.Cu")
		(net "GND")
	)
	(via
		(at 97.57283 9.2964)
		(size 0.508)
		(drill 0.254)
		(layers "F.Cu" "B.Cu")
		(net "GND")
	)
	(via
		(at 20.379944 9.2964)
		(size 0.5588)
		(drill 0.3048)
		(layers "F.Cu" "B.Cu")
		(net "GND")
	)
	(via
		(at 122.07494 6.476492)
		(size 0.508)
		(drill 0.254)
		(layers "F.Cu" "B.Cu")
		(net "GND")
	)
	(via
		(at 127.4191 -34.0106)
		(size 0.508)
		(drill 0.254)
		(layers "F.Cu" "B.Cu")
		(net "GND")
	)
	(via
		(at 45.0977 -4.0513)
		(size 0.5588)
		(drill 0.3048)
		(layers "F.Cu" "B.Cu")
		(net "GND")
	)
	(via
		(at 61.556138 9.466072)
		(size 0.508)
		(drill 0.254)
		(layers "F.Cu" "B.Cu")
		(net "GND")
	)
	(via
		(at 44.75607 9.466072)
		(size 0.508)
		(drill 0.254)
		(layers "F.Cu" "B.Cu")
		(net "GND")
	)
	(via
		(at 131.1275 -8.763)
		(size 0.508)
		(drill 0.254)
		(layers "F.Cu" "B.Cu")
		(net "GND")
	)
	(via
		(at 117.4242 -20.3962)
		(size 0.508)
		(drill 0.254)
		(layers "F.Cu" "B.Cu")
		(net "GND")
	)
	(via
		(at 145.2372 -31.3817)
		(size 0.508)
		(drill 0.254)
		(layers "F.Cu" "B.Cu")
		(net "GND")
	)
	(via
		(at 84.955888 6.435852)
		(size 0.508)
		(drill 0.254)
		(layers "F.Cu" "B.Cu")
		(net "GND")
	)
	(via
		(at 145.0848 -13.6017)
		(size 0.508)
		(drill 0.254)
		(layers "F.Cu" "B.Cu")
		(net "GND")
	)
	(via
		(at 127.569976 -21.502624)
		(size 0.508)
		(drill 0.254)
		(layers "F.Cu" "B.Cu")
		(net "GND")
	)
	(via
		(at 19.5072 -5.969)
		(size 0.508)
		(drill 0.254)
		(layers "F.Cu" "B.Cu")
		(net "GND")
	)
	(via
		(at 122.5296 -11.3538)
		(size 0.508)
		(drill 0.254)
		(layers "F.Cu" "B.Cu")
		(net "GND")
	)
	(via
		(at 117.8306 -6.1214)
		(size 0.508)
		(drill 0.254)
		(layers "F.Cu" "B.Cu")
		(net "GND")
	)
	(via
		(at 118.951248 9.567672)
		(size 0.508)
		(drill 0.254)
		(layers "F.Cu" "B.Cu")
		(net "GND")
	)
	(via
		(at 25.8572 -10.1346)
		(size 0.5588)
		(drill 0.3048)
		(layers "F.Cu" "B.Cu")
		(net "GND")
	)
	(via
		(at 22.098 -19.304)
		(size 0.508)
		(drill 0.254)
		(layers "F.Cu" "B.Cu")
		(net "GND")
	)
	(via
		(at 91.432888 6.435852)
		(size 0.508)
		(drill 0.254)
		(layers "F.Cu" "B.Cu")
		(net "GND")
	)
	(via
		(at 54.356 9.466072)
		(size 0.508)
		(drill 0.254)
		(layers "F.Cu" "B.Cu")
		(net "GND")
	)
	(via
		(at 129.369312 -12.915646)
		(size 0.508)
		(drill 0.254)
		(layers "F.Cu" "B.Cu")
		(net "GND")
	)
	(via
		(at 3.2639 -33.7947)
		(size 0.508)
		(drill 0.254)
		(layers "F.Cu" "B.Cu")
		(net "GND")
	)
	(segment
		(start 37.979858 12.514072)
		(end 37.979858 9.889744)
		(width 0.5588)
		(layer "B.Cu")
		(net "GND")
	)
	(segment
		(start 66.779648 9.889744)
		(end 66.355976 9.466072)
		(width 0.5588)
		(layer "B.Cu")
		(net "GND")
	)
	(segment
		(start 35.579812 9.889744)
		(end 35.15614 9.466072)
		(width 0.5588)
		(layer "B.Cu")
		(net "GND")
	)
	(segment
		(start 114.574828 10.912094)
		(end 114.574828 9.991344)
		(width 0.5588)
		(layer "B.Cu")
		(net "GND")
	)
	(segment
		(start 81.179924 12.514072)
		(end 81.179924 10.810748)
		(width 0.5588)
		(layer "B.Cu")
		(net "GND")
	)
	(segment
		(start 28.379674 9.596374)
		(end 28.379674 10.810494)
		(width 0.5588)
		(layer "B.Cu")
		(net "GND")
	)
	(segment
		(start 20.9169 -27.0002)
		(end 20.1422 -27.0002)
		(width 0.4064)
		(layer "B.Cu")
		(net "GND")
	)
	(segment
		(start 104.902 -2.6543)
		(end 105.12298 -2.87528)
		(width 0.3048)
		(layer "B.Cu")
		(net "GND")
	)
	(segment
		(start 124.174758 10.912094)
		(end 124.174758 9.991344)
		(width 0.5588)
		(layer "B.Cu")
		(net "GND")
	)
	(segment
		(start 69.179948 12.514072)
		(end 69.179948 10.810748)
		(width 0.5588)
		(layer "B.Cu")
		(net "GND")
	)
	(segment
		(start 124.6886 -15.9512)
		(end 125.68936 -14.95044)
		(width 0.3048)
		(layer "B.Cu")
		(net "GND")
	)
	(segment
		(start 45.179742 10.810494)
		(end 45.179742 9.889744)
		(width 0.5588)
		(layer "B.Cu")
		(net "GND")
	)
	(segment
		(start 52.379626 9.889744)
		(end 51.955954 9.466072)
		(width 0.5588)
		(layer "B.Cu")
		(net "GND")
	)
	(segment
		(start 126.575058 10.912348)
		(end 126.574804 10.912094)
		(width 0.5588)
		(layer "B.Cu")
		(net "GND")
	)
	(segment
		(start 112.175036 12.615672)
		(end 112.175036 10.912348)
		(width 0.5588)
		(layer "B.Cu")
		(net "GND")
	)
	(segment
		(start 85.979762 9.889744)
		(end 85.55609 9.466072)
		(width 0.5588)
		(layer "B.Cu")
		(net "GND")
	)
	(segment
		(start 40.37965 9.889744)
		(end 39.955978 9.466072)
		(width 0.5588)
		(layer "B.Cu")
		(net "GND")
	)
	(segment
		(start 59.579764 10.810494)
		(end 59.579764 9.889744)
		(width 0.5588)
		(layer "B.Cu")
		(net "GND")
	)
	(segment
		(start 25.53208 10.329672)
		(end 25.179782 10.68197)
		(width 0.5588)
		(layer "B.Cu")
		(net "GND")
	)
	(segment
		(start 66.779902 10.810748)
		(end 66.779648 10.810494)
		(width 0.5588)
		(layer "B.Cu")
		(net "GND")
	)
	(segment
		(start 54.779926 12.514072)
		(end 54.779926 10.810748)
		(width 0.5588)
		(layer "B.Cu")
		(net "GND")
	)
	(segment
		(start 122.4153 -8.17118)
		(end 122.4153 -8.8138)
		(width 0.3048)
		(layer "B.Cu")
		(net "GND")
	)
	(segment
		(start 33.18002 12.514072)
		(end 33.18002 10.810748)
		(width 0.5588)
		(layer "B.Cu")
		(net "GND")
	)
	(segment
		(start 30.77972 10.06348)
		(end 30.77972 10.810494)
		(width 0.5588)
		(layer "B.Cu")
		(net "GND")
	)
	(segment
		(start 71.57974 9.889744)
		(end 71.156068 9.466072)
		(width 0.5588)
		(layer "B.Cu")
		(net "GND")
	)
	(segment
		(start 45.179742 9.889744)
		(end 44.75607 9.466072)
		(width 0.5588)
		(layer "B.Cu")
		(net "GND")
	)
	(segment
		(start 124.175012 12.615672)
		(end 124.175012 10.912348)
		(width 0.5588)
		(layer "B.Cu")
		(net "GND")
	)
	(segment
		(start 25.598628 10.329672)
		(end 25.53208 10.329672)
		(width 0.5588)
		(layer "B.Cu")
		(net "GND")
	)
	(segment
		(start 130.1496 9.5758)
		(end 130.9624 9.5758)
		(width 0.5588)
		(layer "B.Cu")
		(net "GND")
	)
	(segment
		(start 131.0259 -8.8138)
		(end 130.37312 -8.8138)
		(width 0.3048)
		(layer "B.Cu")
		(net "GND")
	)
	(segment
		(start 78.779624 9.889744)
		(end 78.355952 9.466072)
		(width 0.5588)
		(layer "B.Cu")
		(net "GND")
	)
	(segment
		(start 49.979834 12.514072)
		(end 49.979834 9.889744)
		(width 0.5588)
		(layer "B.Cu")
		(net "GND")
	)
	(segment
		(start 66.779648 10.810494)
		(end 66.779648 9.889744)
		(width 0.5588)
		(layer "B.Cu")
		(net "GND")
	)
	(segment
		(start 30.77972 10.810494)
		(end 30.779974 10.810748)
		(width 0.5588)
		(layer "B.Cu")
		(net "GND")
	)
	(segment
		(start 19.7866 -27.3558)
		(end 19.7866 -27.4828)
		(width 0.4064)
		(layer "B.Cu")
		(net "GND")
	)
	(segment
		(start 122.5296 -11.3538)
		(end 122.5296 -11.526012)
		(width 0.4064)
		(layer "B.Cu")
		(net "GND")
	)
	(segment
		(start 18.9992 -10.2743)
		(end 18.6944 -10.5791)
		(width 0.4064)
		(layer "B.Cu")
		(net "GND")
	)
	(segment
		(start 83.579716 10.810494)
		(end 83.579716 9.889744)
		(width 0.5588)
		(layer "B.Cu")
		(net "GND")
	)
	(segment
		(start 109.77499 10.912348)
		(end 109.774736 10.912094)
		(width 0.5588)
		(layer "B.Cu")
		(net "GND")
	)
	(segment
		(start 127.569976 -21.502624)
		(end 127.6477 -21.4249)
		(width 0.4064)
		(layer "B.Cu")
		(net "GND")
	)
	(segment
		(start 112.175036 10.912348)
		(end 112.174782 10.912094)
		(width 0.5588)
		(layer "B.Cu")
		(net "GND")
	)
	(segment
		(start 130.9624 9.5758)
		(end 131.37515 9.98855)
		(width 0.5588)
		(layer "B.Cu")
		(net "GND")
	)
	(segment
		(start 112.174782 10.912094)
		(end 112.174782 9.991344)
		(width 0.5588)
		(layer "B.Cu")
		(net "GND")
	)
	(segment
		(start 122.5296 -11.526012)
		(end 122.979688 -11.9761)
		(width 0.4064)
		(layer "B.Cu")
		(net "GND")
	)
	(segment
		(start 19.0754 -10.2743)
		(end 18.9992 -10.2743)
		(width 0.4064)
		(layer "B.Cu")
		(net "GND")
	)
	(segment
		(start 47.579788 12.514072)
		(end 47.579788 9.889744)
		(width 0.5588)
		(layer "B.Cu")
		(net "GND")
	)
	(segment
		(start 33.18002 10.810748)
		(end 33.179766 10.810494)
		(width 0.5588)
		(layer "B.Cu")
		(net "GND")
	)
	(segment
		(start 31.3944 9.4488)
		(end 30.77972 10.06348)
		(width 0.5588)
		(layer "B.Cu")
		(net "GND")
	)
	(segment
		(start 88.379808 9.889744)
		(end 87.956136 9.466072)
		(width 0.5588)
		(layer "B.Cu")
		(net "GND")
	)
	(segment
		(start 33.179766 10.810494)
		(end 33.179766 9.889744)
		(width 0.5588)
		(layer "B.Cu")
		(net "GND")
	)
	(segment
		(start 122.4153 -8.8138)
		(end 122.3899 -8.8392)
		(width 0.3048)
		(layer "B.Cu")
		(net "GND")
	)
	(segment
		(start 26.5684 9.3599)
		(end 25.598628 10.329672)
		(width 0.5588)
		(layer "B.Cu")
		(net "GND")
	)
	(segment
		(start 40.379904 10.810748)
		(end 40.37965 10.810494)
		(width 0.5588)
		(layer "B.Cu")
		(net "GND")
	)
	(segment
		(start 64.379856 12.514072)
		(end 64.379856 9.889744)
		(width 0.5588)
		(layer "B.Cu")
		(net "GND")
	)
	(segment
		(start 127.6477 -21.4249)
		(end 127.6477 -18.5674)
		(width 0.4064)
		(layer "B.Cu")
		(net "GND")
	)
	(segment
		(start 16.256 -5.4356)
		(end 16.256 -4.8006)
		(width 0.508)
		(layer "B.Cu")
		(net "GND")
	)
	(segment
		(start 61.97981 12.514072)
		(end 61.97981 9.889744)
		(width 0.5588)
		(layer "B.Cu")
		(net "GND")
	)
	(segment
		(start 88.379808 12.514072)
		(end 88.379808 9.889744)
		(width 0.5588)
		(layer "B.Cu")
		(net "GND")
	)
	(segment
		(start 38.005258 4.2926)
		(end 38.0238 4.2926)
		(width 0.3048)
		(layer "B.Cu")
		(net "GND")
	)
	(segment
		(start 131.0767 -8.763)
		(end 131.0259 -8.8138)
		(width 0.3048)
		(layer "B.Cu")
		(net "GND")
	)
	(segment
		(start 17.6784 -14.3129)
		(end 17.6657 -14.3002)
		(width 0.508)
		(layer "B.Cu")
		(net "GND")
	)
	(segment
		(start 97.979992 12.514072)
		(end 97.979992 9.703562)
		(width 0.5588)
		(layer "B.Cu")
		(net "GND")
	)
	(segment
		(start 116.974874 10.912094)
		(end 116.974874 9.991344)
		(width 0.5588)
		(layer "B.Cu")
		(net "GND")
	)
	(segment
		(start 123.8504 -19.1008)
		(end 124.0282 -19.2786)
		(width 0.4064)
		(layer "B.Cu")
		(net "GND")
	)
	(segment
		(start 52.379626 10.810494)
		(end 52.379626 9.889744)
		(width 0.5588)
		(layer "B.Cu")
		(net "GND")
	)
	(segment
		(start 116.974874 9.991344)
		(end 116.551202 9.567672)
		(width 0.5588)
		(layer "B.Cu")
		(net "GND")
	)
	(segment
		(start 81.17967 9.889744)
		(end 80.755998 9.466072)
		(width 0.5588)
		(layer "B.Cu")
		(net "GND")
	)
	(segment
		(start 19.0627 -21.0058)
		(end 19.0627 -20.1803)
		(width 0.508)
		(layer "B.Cu")
		(net "GND")
	)
	(segment
		(start 45.179996 12.514072)
		(end 45.179996 10.810748)
		(width 0.5588)
		(layer "B.Cu")
		(net "GND")
	)
	(segment
		(start 93.1799 10.810748)
		(end 93.179646 10.810494)
		(width 0.5588)
		(layer "B.Cu")
		(net "GND")
	)
	(segment
		(start 28.379674 10.810494)
		(end 28.379928 10.810748)
		(width 0.5588)
		(layer "B.Cu")
		(net "GND")
	)
	(segment
		(start 123.3551 -18.5674)
		(end 123.8504 -19.0627)
		(width 0.4064)
		(layer "B.Cu")
		(net "GND")
	)
	(segment
		(start 126.574804 9.991344)
		(end 126.151132 9.567672)
		(width 0.5588)
		(layer "B.Cu")
		(net "GND")
	)
	(segment
		(start 38.44544 3.87096)
		(end 39.20236 3.87096)
		(width 0.3048)
		(layer "B.Cu")
		(net "GND")
	)
	(segment
		(start 119.37492 10.50036)
		(end 119.37492 9.991344)
		(width 0.5588)
		(layer "B.Cu")
		(net "GND")
	)
	(segment
		(start 66.779902 12.514072)
		(end 66.779902 10.810748)
		(width 0.5588)
		(layer "B.Cu")
		(net "GND")
	)
	(segment
		(start 83.57997 10.810748)
		(end 83.579716 10.810494)
		(width 0.5588)
		(layer "B.Cu")
		(net "GND")
	)
	(segment
		(start 18.0848 -15.0368)
		(end 18.0213 -15.0368)
		(width 0.508)
		(layer "B.Cu")
		(net "GND")
	)
	(segment
		(start 85.980016 10.810748)
		(end 85.979762 10.810494)
		(width 0.5588)
		(layer "B.Cu")
		(net "GND")
	)
	(segment
		(start 123.8504 -19.0627)
		(end 123.8504 -19.1008)
		(width 0.4064)
		(layer "B.Cu")
		(net "GND")
	)
	(segment
		(start 114.575082 12.615672)
		(end 114.575082 10.912348)
		(width 0.5588)
		(layer "B.Cu")
		(net "GND")
	)
	(segment
		(start 54.779672 10.810494)
		(end 54.779672 9.889744)
		(width 0.5588)
		(layer "B.Cu")
		(net "GND")
	)
	(segment
		(start 129.369312 -12.915646)
		(end 129.330958 -12.954)
		(width 0.508)
		(layer "B.Cu")
		(net "GND")
	)
	(segment
		(start 90.779854 9.889744)
		(end 90.356182 9.466072)
		(width 0.5588)
		(layer "B.Cu")
		(net "GND")
	)
	(segment
		(start 128.975104 9.925304)
		(end 128.975104 12.615672)
		(width 0.5588)
		(layer "B.Cu")
		(net "GND")
	)
	(segment
		(start 28.1813 9.398)
		(end 28.379674 9.596374)
		(width 0.5588)
		(layer "B.Cu")
		(net "GND")
	)
	(segment
		(start 52.37988 12.514072)
		(end 52.37988 10.810748)
		(width 0.5588)
		(layer "B.Cu")
		(net "GND")
	)
	(segment
		(start 20.955 -26.9621)
		(end 20.9169 -27.0002)
		(width 0.4064)
		(layer "B.Cu")
		(net "GND")
	)
	(segment
		(start 25.179782 10.68197)
		(end 25.179782 12.514072)
		(width 0.5588)
		(layer "B.Cu")
		(net "GND")
	)
	(segment
		(start 121.774966 9.991344)
		(end 121.351294 9.567672)
		(width 0.5588)
		(layer "B.Cu")
		(net "GND")
	)
	(segment
		(start 20.1422 -27.0002)
		(end 19.7866 -27.3558)
		(width 0.4064)
		(layer "B.Cu")
		(net "GND")
	)
	(segment
		(start 76.379832 12.514072)
		(end 76.379832 9.889744)
		(width 0.5588)
		(layer "B.Cu")
		(net "GND")
	)
	(segment
		(start 24.6634 -25.273)
		(end 24.7777 -25.1587)
		(width 0.4064)
		(layer "B.Cu")
		(net "GND")
	)
	(segment
		(start 54.779926 10.810748)
		(end 54.779672 10.810494)
		(width 0.5588)
		(layer "B.Cu")
		(net "GND")
	)
	(segment
		(start 109.774736 9.991344)
		(end 109.351064 9.567672)
		(width 0.5588)
		(layer "B.Cu")
		(net "GND")
	)
	(segment
		(start 114.574828 9.991344)
		(end 114.151156 9.567672)
		(width 0.5588)
		(layer "B.Cu")
		(net "GND")
	)
	(segment
		(start 45.179996 10.810748)
		(end 45.179742 10.810494)
		(width 0.5588)
		(layer "B.Cu")
		(net "GND")
	)
	(segment
		(start 85.979762 10.810494)
		(end 85.979762 9.889744)
		(width 0.5588)
		(layer "B.Cu")
		(net "GND")
	)
	(segment
		(start 17.6784 -14.6939)
		(end 17.6784 -14.3129)
		(width 0.508)
		(layer "B.Cu")
		(net "GND")
	)
	(segment
		(start 54.779672 9.889744)
		(end 54.356 9.466072)
		(width 0.5588)
		(layer "B.Cu")
		(net "GND")
	)
	(segment
		(start 95.579692 9.889744)
		(end 95.15602 9.466072)
		(width 0.5588)
		(layer "B.Cu")
		(net "GND")
	)
	(segment
		(start 128.6764 9.6266)
		(end 128.975104 9.925304)
		(width 0.5588)
		(layer "B.Cu")
		(net "GND")
	)
	(segment
		(start 125.68936 -14.95044)
		(end 126.59106 -14.95044)
		(width 0.3048)
		(layer "B.Cu")
		(net "GND")
	)
	(segment
		(start 57.179718 9.889744)
		(end 56.756046 9.466072)
		(width 0.5588)
		(layer "B.Cu")
		(net "GND")
	)
	(segment
		(start 93.179646 10.810494)
		(end 93.179646 9.889744)
		(width 0.5588)
		(layer "B.Cu")
		(net "GND")
	)
	(segment
		(start 49.979834 9.889744)
		(end 49.556162 9.466072)
		(width 0.5588)
		(layer "B.Cu")
		(net "GND")
	)
	(segment
		(start 17.0053 -10.6426)
		(end 18.2626 -10.6426)
		(width 0.508)
		(layer "B.Cu")
		(net "GND")
	)
	(segment
		(start 18.6944 -10.5791)
		(end 18.3261 -10.5791)
		(width 0.4064)
		(layer "B.Cu")
		(net "GND")
	)
	(segment
		(start 37.979858 9.889744)
		(end 37.556186 9.466072)
		(width 0.5588)
		(layer "B.Cu")
		(net "GND")
	)
	(segment
		(start 78.779878 12.514072)
		(end 78.779878 10.810748)
		(width 0.5588)
		(layer "B.Cu")
		(net "GND")
	)
	(segment
		(start 52.37988 10.810748)
		(end 52.379626 10.810494)
		(width 0.5588)
		(layer "B.Cu")
		(net "GND")
	)
	(segment
		(start 83.57997 12.514072)
		(end 83.57997 10.810748)
		(width 0.5588)
		(layer "B.Cu")
		(net "GND")
	)
	(segment
		(start 47.579788 9.889744)
		(end 47.156116 9.466072)
		(width 0.5588)
		(layer "B.Cu")
		(net "GND")
	)
	(segment
		(start 20.699476 -23.651464)
		(end 21.441664 -23.651464)
		(width 0.3048)
		(layer "B.Cu")
		(net "GND")
	)
	(segment
		(start 73.979786 12.514072)
		(end 73.979786 9.889744)
		(width 0.5588)
		(layer "B.Cu")
		(net "GND")
	)
	(segment
		(start 24.7777 -25.1587)
		(end 25.3238 -25.1587)
		(width 0.4064)
		(layer "B.Cu")
		(net "GND")
	)
	(segment
		(start 112.174782 9.991344)
		(end 111.75111 9.567672)
		(width 0.5588)
		(layer "B.Cu")
		(net "GND")
	)
	(segment
		(start 124.175012 10.912348)
		(end 124.174758 10.912094)
		(width 0.5588)
		(layer "B.Cu")
		(net "GND")
	)
	(segment
		(start 71.579994 12.514072)
		(end 71.579994 10.810748)
		(width 0.5588)
		(layer "B.Cu")
		(net "GND")
	)
	(segment
		(start 37.9984 4.299458)
		(end 38.005258 4.2926)
		(width 0.3048)
		(layer "B.Cu")
		(net "GND")
	)
	(segment
		(start 119.37492 9.991344)
		(end 118.951248 9.567672)
		(width 0.5588)
		(layer "B.Cu")
		(net "GND")
	)
	(segment
		(start 30.779974 10.810748)
		(end 30.779974 12.514072)
		(width 0.5588)
		(layer "B.Cu")
		(net "GND")
	)
	(segment
		(start 71.57974 10.810494)
		(end 71.57974 9.889744)
		(width 0.5588)
		(layer "B.Cu")
		(net "GND")
	)
	(segment
		(start 122.979688 -11.9761)
		(end 123.444 -11.9761)
		(width 0.4064)
		(layer "B.Cu")
		(net "GND")
	)
	(segment
		(start 21.441664 -23.651464)
		(end 21.6408 -23.8506)
		(width 0.3048)
		(layer "B.Cu")
		(net "GND")
	)
	(segment
		(start 126.6952 -12.3063)
		(end 126.6952 -12.1539)
		(width 0.508)
		(layer "B.Cu")
		(net "GND")
	)
	(segment
		(start 25.2984 -25.1333)
		(end 25.3238 -25.1587)
		(width 0.4064)
		(layer "B.Cu")
		(net "GND")
	)
	(segment
		(start 90.779854 12.514072)
		(end 90.779854 9.889744)
		(width 0.5588)
		(layer "B.Cu")
		(net "GND")
	)
	(segment
		(start 78.779624 10.810494)
		(end 78.779624 9.889744)
		(width 0.5588)
		(layer "B.Cu")
		(net "GND")
	)
	(segment
		(start 20.379944 9.2964)
		(end 20.379944 12.514072)
		(width 0.5588)
		(layer "B.Cu")
		(net "GND")
	)
	(segment
		(start 69.179694 9.889744)
		(end 68.756022 9.466072)
		(width 0.5588)
		(layer "B.Cu")
		(net "GND")
	)
	(segment
		(start 20.971002 -10.17905)
		(end 19.17065 -10.17905)
		(width 0.2032)
		(layer "B.Cu")
		(net "GND")
	)
	(segment
		(start 18.0213 -15.0368)
		(end 17.6784 -14.6939)
		(width 0.508)
		(layer "B.Cu")
		(net "GND")
	)
	(segment
		(start 69.179948 10.810748)
		(end 69.179694 10.810494)
		(width 0.5588)
		(layer "B.Cu")
		(net "GND")
	)
	(segment
		(start 121.3104 -1.8542)
		(end 121.9327 -2.4765)
		(width 0.4064)
		(layer "B.Cu")
		(net "GND")
	)
	(segment
		(start 16.8148 -10.4521)
		(end 17.0053 -10.6426)
		(width 0.508)
		(layer "B.Cu")
		(net "GND")
	)
	(segment
		(start 59.580018 10.810748)
		(end 59.579764 10.810494)
		(width 0.5588)
		(layer "B.Cu")
		(net "GND")
	)
	(segment
		(start 25.2984 -24.1173)
		(end 25.2984 -25.1333)
		(width 0.4064)
		(layer "B.Cu")
		(net "GND")
	)
	(segment
		(start 19.2151 -20.0279)
		(end 19.1008 -20.1422)
		(width 0.508)
		(layer "B.Cu")
		(net "GND")
	)
	(segment
		(start 57.179718 10.810494)
		(end 57.179718 9.889744)
		(width 0.5588)
		(layer "B.Cu")
		(net "GND")
	)
	(segment
		(start 19.2151 -19.3802)
		(end 19.2151 -20.0279)
		(width 0.508)
		(layer "B.Cu")
		(net "GND")
	)
	(segment
		(start 61.97981 9.889744)
		(end 61.556138 9.466072)
		(width 0.5588)
		(layer "B.Cu")
		(net "GND")
	)
	(segment
		(start 59.580018 12.514072)
		(end 59.580018 10.810748)
		(width 0.5588)
		(layer "B.Cu")
		(net "GND")
	)
	(segment
		(start 95.579692 10.810494)
		(end 95.579692 9.889744)
		(width 0.5588)
		(layer "B.Cu")
		(net "GND")
	)
	(segment
		(start 78.779878 10.810748)
		(end 78.779624 10.810494)
		(width 0.5588)
		(layer "B.Cu")
		(net "GND")
	)
	(segment
		(start 124.174758 9.991344)
		(end 123.751086 9.567672)
		(width 0.5588)
		(layer "B.Cu")
		(net "GND")
	)
	(segment
		(start 116.975128 10.912348)
		(end 116.974874 10.912094)
		(width 0.5588)
		(layer "B.Cu")
		(net "GND")
	)
	(segment
		(start 19.0627 -20.1803)
		(end 19.1008 -20.1422)
		(width 0.508)
		(layer "B.Cu")
		(net "GND")
	)
	(segment
		(start 18.5801 -14.224)
		(end 19.0373 -14.6812)
		(width 0.508)
		(layer "B.Cu")
		(net "GND")
	)
	(segment
		(start 16.256 -4.8006)
		(end 16.129 -4.6736)
		(width 0.508)
		(layer "B.Cu")
		(net "GND")
	)
	(segment
		(start 28.379928 10.810748)
		(end 28.379928 12.514072)
		(width 0.5588)
		(layer "B.Cu")
		(net "GND")
	)
	(segment
		(start 116.975128 12.615672)
		(end 116.975128 10.912348)
		(width 0.5588)
		(layer "B.Cu")
		(net "GND")
	)
	(segment
		(start 26.5684 9.3345)
		(end 26.5684 9.3599)
		(width 0.5588)
		(layer "B.Cu")
		(net "GND")
	)
	(segment
		(start 109.77499 12.615672)
		(end 109.77499 10.912348)
		(width 0.5588)
		(layer "B.Cu")
		(net "GND")
	)
	(segment
		(start 19.8501 -6.3119)
		(end 20.31619 -6.3119)
		(width 0.4064)
		(layer "B.Cu")
		(net "GND")
	)
	(segment
		(start 83.579716 9.889744)
		(end 83.156044 9.466072)
		(width 0.5588)
		(layer "B.Cu")
		(net "GND")
	)
	(segment
		(start 35.579812 12.514072)
		(end 35.579812 9.889744)
		(width 0.5588)
		(layer "B.Cu")
		(net "GND")
	)
	(segment
		(start 17.6657 -14.3002)
		(end 17.7419 -14.224)
		(width 0.508)
		(layer "B.Cu")
		(net "GND")
	)
	(segment
		(start 73.979786 9.889744)
		(end 73.556114 9.466072)
		(width 0.5588)
		(layer "B.Cu")
		(net "GND")
	)
	(segment
		(start 93.179646 9.889744)
		(end 92.755974 9.466072)
		(width 0.5588)
		(layer "B.Cu")
		(net "GND")
	)
	(segment
		(start 81.179924 10.810748)
		(end 81.17967 10.810494)
		(width 0.5588)
		(layer "B.Cu")
		(net "GND")
	)
	(segment
		(start 40.37965 10.810494)
		(end 40.37965 9.889744)
		(width 0.5588)
		(layer "B.Cu")
		(net "GND")
	)
	(segment
		(start 19.5072 -5.969)
		(end 19.8501 -6.3119)
		(width 0.4064)
		(layer "B.Cu")
		(net "GND")
	)
	(segment
		(start 121.9327 -2.4765)
		(end 123.2916 -2.4765)
		(width 0.4064)
		(layer "B.Cu")
		(net "GND")
	)
	(segment
		(start 38.0238 4.2926)
		(end 38.44544 3.87096)
		(width 0.3048)
		(layer "B.Cu")
		(net "GND")
	)
	(segment
		(start 109.774736 10.912094)
		(end 109.774736 9.991344)
		(width 0.5588)
		(layer "B.Cu")
		(net "GND")
	)
	(segment
		(start 93.1799 12.514072)
		(end 93.1799 10.810748)
		(width 0.5588)
		(layer "B.Cu")
		(net "GND")
	)
	(segment
		(start 129.330958 -12.954)
		(end 127.3429 -12.954)
		(width 0.508)
		(layer "B.Cu")
		(net "GND")
	)
	(segment
		(start 57.179972 10.810748)
		(end 57.179718 10.810494)
		(width 0.5588)
		(layer "B.Cu")
		(net "GND")
	)
	(segment
		(start 114.575082 10.912348)
		(end 114.574828 10.912094)
		(width 0.5588)
		(layer "B.Cu")
		(net "GND")
	)
	(segment
		(start 81.17967 10.810494)
		(end 81.17967 9.889744)
		(width 0.5588)
		(layer "B.Cu")
		(net "GND")
	)
	(segment
		(start 95.579946 10.810748)
		(end 95.579692 10.810494)
		(width 0.5588)
		(layer "B.Cu")
		(net "GND")
	)
	(segment
		(start 95.579946 12.514072)
		(end 95.579946 10.810748)
		(width 0.5588)
		(layer "B.Cu")
		(net "GND")
	)
	(segment
		(start 122.53468 -8.0518)
		(end 122.4153 -8.17118)
		(width 0.3048)
		(layer "B.Cu")
		(net "GND")
	)
	(segment
		(start 127.6477 -18.5674)
		(end 127.5207 -18.4404)
		(width 0.4064)
		(layer "B.Cu")
		(net "GND")
	)
	(segment
		(start 76.379832 9.889744)
		(end 75.95616 9.466072)
		(width 0.5588)
		(layer "B.Cu")
		(net "GND")
	)
	(segment
		(start 24.5364 -25.273)
		(end 24.6634 -25.273)
		(width 0.4064)
		(layer "B.Cu")
		(net "GND")
	)
	(segment
		(start 97.979992 9.703562)
		(end 97.57283 9.2964)
		(width 0.5588)
		(layer "B.Cu")
		(net "GND")
	)
	(segment
		(start 119.375174 12.615672)
		(end 119.37492 10.50036)
		(width 0.5588)
		(layer "B.Cu")
		(net "GND")
	)
	(segment
		(start 18.2626 -10.6426)
		(end 18.3261 -10.5791)
		(width 0.508)
		(layer "B.Cu")
		(net "GND")
	)
	(segment
		(start 64.379856 9.889744)
		(end 63.956184 9.466072)
		(width 0.5588)
		(layer "B.Cu")
		(net "GND")
	)
	(segment
		(start 105.12298 -2.87528)
		(end 106.8578 -2.87528)
		(width 0.3048)
		(layer "B.Cu")
		(net "GND")
	)
	(segment
		(start 130.0988 9.525)
		(end 130.1496 9.5758)
		(width 0.5588)
		(layer "B.Cu")
		(net "GND")
	)
	(segment
		(start 126.575058 12.615672)
		(end 126.575058 10.912348)
		(width 0.5588)
		(layer "B.Cu")
		(net "GND")
	)
	(segment
		(start 59.579764 9.889744)
		(end 59.156092 9.466072)
		(width 0.5588)
		(layer "B.Cu")
		(net "GND")
	)
	(segment
		(start 126.574804 10.912094)
		(end 126.574804 9.991344)
		(width 0.5588)
		(layer "B.Cu")
		(net "GND")
	)
	(segment
		(start 57.179972 12.514072)
		(end 57.179972 10.810748)
		(width 0.5588)
		(layer "B.Cu")
		(net "GND")
	)
	(segment
		(start 69.179694 10.810494)
		(end 69.179694 9.889744)
		(width 0.5588)
		(layer "B.Cu")
		(net "GND")
	)
	(segment
		(start 17.7419 -14.224)
		(end 18.5801 -14.224)
		(width 0.508)
		(layer "B.Cu")
		(net "GND")
	)
	(segment
		(start 40.379904 12.514072)
		(end 40.379904 10.810748)
		(width 0.5588)
		(layer "B.Cu")
		(net "GND")
	)
	(segment
		(start 33.179766 9.889744)
		(end 32.756094 9.466072)
		(width 0.5588)
		(layer "B.Cu")
		(net "GND")
	)
	(segment
		(start 85.980016 12.514072)
		(end 85.980016 10.810748)
		(width 0.5588)
		(layer "B.Cu")
		(net "GND")
	)
	(segment
		(start 71.579994 10.810748)
		(end 71.57974 10.810494)
		(width 0.5588)
		(layer "B.Cu")
		(net "GND")
	)
	(segment
		(start 20.31619 -6.3119)
		(end 20.324318 -6.320028)
		(width 0.4064)
		(layer "B.Cu")
		(net "GND")
	)
	(segment
		(start 19.17065 -10.17905)
		(end 19.0754 -10.2743)
		(width 0.2032)
		(layer "B.Cu")
		(net "GND")
	)
	(segment
		(start 121.774966 12.615672)
		(end 121.774966 9.991344)
		(width 0.5588)
		(layer "B.Cu")
		(net "GND")
	)
	(segment
		(start 131.1275 -8.763)
		(end 131.0767 -8.763)
		(width 0.3048)
		(layer "B.Cu")
		(net "GND")
	)
	(segment
		(start 127.3429 -12.954)
		(end 126.6952 -12.3063)
		(width 0.508)
		(layer "B.Cu")
		(net "GND")
	)
	(segment
		(start 131.37515 9.98855)
		(end 131.37515 12.615672)
		(width 0.5588)
		(layer "B.Cu")
		(net "GND")
	)
	(segment
		(start 119.805704 -28.124404)
		(end 119.2911 -27.6098)
		(width 0.254)
		(layer "F.Cu")
		(net "CRFILT")
	)
	(segment
		(start 121.42978 -28.11653)
		(end 120.46204 -28.11653)
		(width 0.254)
		(layer "F.Cu")
		(net "CRFILT")
	)
	(segment
		(start 120.46204 -28.11653)
		(end 120.454166 -28.124404)
		(width 0.254)
		(layer "F.Cu")
		(net "CRFILT")
	)
	(segment
		(start 119.2911 -27.6098)
		(end 119.2911 -26.7589)
		(width 0.254)
		(layer "F.Cu")
		(net "CRFILT")
	)
	(segment
		(start 120.454166 -28.124404)
		(end 119.805704 -28.124404)
		(width 0.254)
		(layer "F.Cu")
		(net "CRFILT")
	)
	(segment
		(start 119.2911 -26.7589)
		(end 119.4054 -26.6446)
		(width 0.254)
		(layer "F.Cu")
		(net "CRFILT")
	)
	(via
		(at 119.4054 -26.6446)
		(size 0.7112)
		(drill 0.3556)
		(layers "F.Cu" "B.Cu")
		(net "CRFILT")
	)
	(segment
		(start 125.1966 -23.5966)
		(end 125.274578 -23.674578)
		(width 0.1016)
		(layer "F.Cu")
		(net "CFG_SEL1")
	)
	(segment
		(start 125.274578 -23.674578)
		(end 125.274578 -25.27173)
		(width 0.1016)
		(layer "F.Cu")
		(net "CFG_SEL1")
	)
	(via
		(at 126.4285 -24.1554)
		(size 0.7112)
		(drill 0.3556)
		(layers "F.Cu" "B.Cu")
		(net "CFG_SEL1")
	)
	(via
		(at 125.1966 -23.5966)
		(size 0.508)
		(drill 0.254)
		(layers "F.Cu" "B.Cu")
		(net "CFG_SEL1")
	)
	(segment
		(start 125.5903 -23.9903)
		(end 126.2634 -23.9903)
		(width 0.1016)
		(layer "B.Cu")
		(net "CFG_SEL1")
	)
	(segment
		(start 125.1966 -23.5966)
		(end 125.5903 -23.9903)
		(width 0.1016)
		(layer "B.Cu")
		(net "CFG_SEL1")
	)
	(segment
		(start 126.4285 -24.9174)
		(end 126.1999 -25.146)
		(width 0.1016)
		(layer "B.Cu")
		(net "CFG_SEL1")
	)
	(segment
		(start 126.1999 -25.146)
		(end 126.1999 -25.908)
		(width 0.1016)
		(layer "B.Cu")
		(net "CFG_SEL1")
	)
	(segment
		(start 126.1999 -25.908)
		(end 125.857 -26.2509)
		(width 0.1016)
		(layer "B.Cu")
		(net "CFG_SEL1")
	)
	(segment
		(start 126.4285 -24.1554)
		(end 126.4285 -24.9174)
		(width 0.1016)
		(layer "B.Cu")
		(net "CFG_SEL1")
	)
	(segment
		(start 126.2634 -23.9903)
		(end 126.4285 -24.1554)
		(width 0.1016)
		(layer "B.Cu")
		(net "CFG_SEL1")
	)
	(zone
		(net "P3V3")
		(layer "F.Cu")
		(hatch none 0.5)
		(connect_pads
			(clearance 0.5)
		)
		(min_thickness 0.25)
		(fill yes
			(thermal_gap 0.5)
			(thermal_bridge_width 0.5)
			(island_removal_mode 0)
		)
		(polygon
			(pts
				(xy 32.82315 4.08305) (xy 32.6517 3.9116) (xy 32.6517 -0.1524) (xy 33.4264 -0.9271) (xy 33.4264 -5.0419)
				(xy 32.9565 -5.5118) (xy 32.9565 -7.2263) (xy 34.3154 -8.5852) (xy 34.3154 -12.1412) (xy 34.8488 -12.6746)
				(xy 34.8488 -20.828) (xy 34.163 -21.5138) (xy 34.163 -24.0538) (xy 34.8488 -24.0538) (xy 35.0012 -23.9014)
				(xy 35.0012 -23.2664) (xy 35.7378 -22.5298) (xy 38.2778 -22.5298) (xy 39.3192 -21.4884) (xy 39.3192 -15.7226)
				(xy 40.767 -14.2748) (xy 40.767 -12.954) (xy 40.005 -12.192) (xy 40.005 -8.6614) (xy 39.04615 -7.70255)
				(xy 39.04615 -5.81025) (xy 38.5572 -5.3213) (xy 38.5572 1.2319) (xy 38.4937 1.2954) (xy 38.1508 1.2954)
				(xy 38.0873 1.3589) (xy 38.0873 2.1336) (xy 38.0238 2.1971) (xy 37.6809 2.1971) (xy 35.79495 4.08305)
			)
		)
		(polygon
			(pts
				(xy 38.0365 0.635) (xy 37.8333 0.635) (xy 37.8333 0.1397) (xy 38.0365 0.1397)
			)
		)
		(polygon
			(pts
				(xy 38.0365 1.2446) (xy 37.8333 1.2446) (xy 37.8333 1.0414) (xy 38.0365 1.0414)
			)
		)
		(polygon
			(pts
				(xy 37.6301 1.7399) (xy 37.4269 1.7399) (xy 37.4269 1.5367) (xy 37.6301 1.5367)
			)
		)
	)
	(zone
		(layer "F.Cu")
		(hatch none 0.5)
		(connect_pads
			(clearance 0)
		)
		(min_thickness 0.25)
		(keepout
			(tracks allowed)
			(vias allowed)
			(pads allowed)
			(copperpour allowed)
			(footprints not_allowed)
		)
		(placement
			(enabled no)
			(sheetname "")
		)
		(fill
			(thermal_gap 0.5)
			(thermal_bridge_width 0.5)
			(island_removal_mode 0)
		)
		(polygon
			(pts
				(xy 117.08003 -7.709916) (xy 136.249918 -7.709916) (xy 136.249918 -13.310108) (xy 117.08003 -13.310108)
			)
		)
	)
	(zone
		(layer "F.Cu")
		(hatch none 0.5)
		(connect_pads
			(clearance 0)
		)
		(min_thickness 0.25)
		(keepout
			(tracks allowed)
			(vias allowed)
			(pads allowed)
			(copperpour allowed)
			(footprints not_allowed)
		)
		(placement
			(enabled no)
			(sheetname "")
		)
		(fill
			(thermal_gap 0.5)
			(thermal_bridge_width 0.5)
			(island_removal_mode 0)
		)
		(polygon
			(pts
				(arc
					(start 133.500114 -25.584912)
					(mid 140.5001 -18.584926)
					(end 147.500086 -25.584912)
				)
				(arc
					(start 147.500086 -25.584912)
					(mid 140.5001 -32.584898)
					(end 133.500114 -25.584912)
				)
			)
		)
	)
	(zone
		(layer "F.Cu")
		(hatch none 0.5)
		(connect_pads
			(clearance 0)
		)
		(min_thickness 0.25)
		(keepout
			(tracks allowed)
			(vias allowed)
			(pads allowed)
			(copperpour allowed)
			(footprints not_allowed)
		)
		(placement
			(enabled no)
			(sheetname "")
		)
		(fill
			(thermal_gap 0.5)
			(thermal_bridge_width 0.5)
			(island_removal_mode 0)
		)
		(polygon
			(pts
				(xy 14.549882 3.50012) (xy 14.549882 6.530086) (xy 99.199954 6.530086) (xy 107.750102 6.530086)
				(xy 133.199886 6.530086) (xy 133.199886 3.50012)
			)
		)
	)
	(zone
		(layer "F.Cu")
		(hatch none 0.5)
		(connect_pads
			(clearance 0)
		)
		(min_thickness 0.25)
		(keepout
			(tracks allowed)
			(vias allowed)
			(pads allowed)
			(copperpour allowed)
			(footprints allowed)
		)
		(placement
			(enabled no)
			(sheetname "")
		)
		(fill
			(thermal_gap 0.5)
			(thermal_bridge_width 0.5)
			(island_removal_mode 0)
		)
		(polygon
			(pts
				(xy 25.146 -16.129) (xy 25.146 -15.1892) (xy 25.7556 -14.5796) (xy 26.6446 -14.5796) (xy 26.924 -14.859)
				(xy 26.924 -15.9004) (xy 26.2636 -16.5608) (xy 25.5778 -16.5608)
			)
		)
	)
	(zone
		(net "GND")
		(layer "F.Cu")
		(hatch none 0.5)
		(connect_pads
			(clearance 0.5)
		)
		(min_thickness 0.25)
		(fill yes
			(thermal_gap 0.5)
			(thermal_bridge_width 0.5)
			(island_removal_mode 0)
		)
		(polygon
			(pts
				(xy 27.1018 -17.0434) (xy 27.1018 -19.0754) (xy 27.4828 -19.4564) (xy 28.702 -19.4564) (xy 29.1846 -18.9738)
				(xy 29.1846 -17.2466) (xy 28.9814 -17.0434)
			)
		)
		(polygon
			(pts
				(xy 28.2702 -17.8308) (xy 28.067 -17.8308) (xy 28.067 -18.034) (xy 28.2702 -18.034)
			)
		)
		(polygon
			(pts
				(xy 27.9146 -17.8054) (xy 27.7114 -17.8054) (xy 27.7114 -18.0086) (xy 27.9146 -18.0086)
			)
		)
	)
	(zone
		(net "P12V")
		(layer "F.Cu")
		(hatch none 0.5)
		(connect_pads
			(clearance 0.5)
		)
		(min_thickness 0.25)
		(fill yes
			(thermal_gap 0.5)
			(thermal_bridge_width 0.5)
			(island_removal_mode 0)
		)
		(polygon
			(pts
				(xy 15.3416 13.5382) (xy 15.3162 13.5128) (xy 15.3162 -0.2286) (xy 9.4742 -6.0706) (xy 9.4742 -20.8026)
				(xy 11.69035 -23.01875) (xy 14.12875 -23.01875) (xy 14.351 -22.7965) (xy 15.9004 -22.7965) (xy 16.0147 -22.6822)
				(xy 16.0147 -20.8153) (xy 15.7226 -20.5232) (xy 12.954 -20.5232) (xy 11.9888 -19.558) (xy 11.9888 -16.51)
				(xy 12.5476 -15.9512) (xy 14.2367 -15.9512) (xy 15.9893 -17.7038) (xy 16.5354 -17.7038) (xy 17.8308 -16.4084)
				(xy 17.8308 -15.8496) (xy 17.3482 -15.367) (xy 17.3482 -5.9182) (xy 16.5354 -5.1054) (xy 16.5354 -4.0132)
				(xy 19.1262 -1.4224) (xy 19.1262 9.2202) (xy 19.8374 9.9314) (xy 19.8374 13.4874) (xy 19.812 13.5128)
				(xy 19.3294 13.5128) (xy 19.304 13.4874) (xy 19.304 10.7188) (xy 19.2532 10.668) (xy 19.1008 10.668)
				(xy 19.05 10.7188) (xy 19.05 13.462) (xy 18.9992 13.5128) (xy 18.5166 13.5128) (xy 18.4912 13.4874)
				(xy 18.4912 10.7188) (xy 18.4658 10.6934) (xy 18.288 10.6934) (xy 18.2626 10.7188) (xy 18.2626 13.4874)
				(xy 18.2372 13.5128) (xy 17.7292 13.5128) (xy 17.7038 13.4874) (xy 17.7038 10.7188) (xy 17.6784 10.6934)
				(xy 17.4752 10.6934) (xy 17.4498 10.7188) (xy 17.4498 13.4874) (xy 17.4244 13.5128) (xy 16.9164 13.5128)
				(xy 16.891 13.4874) (xy 16.891 10.7188) (xy 16.8656 10.6934) (xy 16.6878 10.6934) (xy 16.6624 10.7188)
				(xy 16.6624 13.462) (xy 16.6116 13.5128) (xy 16.129 13.5128) (xy 16.1036 13.4874) (xy 16.1036 10.7315)
				(xy 16.0655 10.6934) (xy 15.9004 10.6934) (xy 15.8496 10.7442) (xy 15.8496 13.5128) (xy 15.8242 13.5382)
			)
		)
		(polygon
			(pts
				(xy 16.2941 -13.7541) (xy 16.0909 -13.7541) (xy 16.0909 -13.9573) (xy 16.2941 -13.9573)
			)
		)
		(polygon
			(pts
				(xy 16.2941 -12.3571) (xy 16.0909 -12.3571) (xy 16.0909 -12.5603) (xy 16.2941 -12.5603)
			)
		)
	)
	(zone
		(layer "F.Cu")
		(hatch none 0.5)
		(connect_pads
			(clearance 0)
		)
		(min_thickness 0.25)
		(keepout
			(tracks allowed)
			(vias allowed)
			(pads allowed)
			(copperpour allowed)
			(footprints allowed)
		)
		(placement
			(enabled no)
			(sheetname "")
		)
		(fill
			(thermal_gap 0.5)
			(thermal_bridge_width 0.5)
			(island_removal_mode 0)
		)
		(polygon
			(pts
				(xy 13.249402 8.671814) (xy 13.249402 15.484348) (xy 134.399782 15.484348) (xy 134.4422 15.44193)
				(xy 134.4422 8.509) (xy 76.5048 8.509) (xy 13.3096 8.509) (xy 13.249402 8.569198)
			)
		)
	)
	(zone
		(layer "F.Cu")
		(hatch none 0.5)
		(connect_pads
			(clearance 0)
		)
		(min_thickness 0.25)
		(keepout
			(tracks allowed)
			(vias allowed)
			(pads allowed)
			(copperpour allowed)
			(footprints not_allowed)
		)
		(placement
			(enabled no)
			(sheetname "")
		)
		(fill
			(thermal_gap 0.5)
			(thermal_bridge_width 0.5)
			(island_removal_mode 0)
		)
		(polygon
			(pts
				(arc
					(start 13.999972 -25.584912)
					(mid 6.999986 -32.584898)
					(end 0 -25.584912)
				)
				(arc
					(start 0 -25.584912)
					(mid 6.999986 -18.584926)
					(end 13.999972 -25.584912)
				)
			)
		)
	)
	(zone
		(net "GND")
		(layer "F.Cu")
		(hatch none 0.5)
		(connect_pads
			(clearance 0.5)
		)
		(min_thickness 0.25)
		(fill yes
			(thermal_gap 0.5)
			(thermal_bridge_width 0.5)
			(island_removal_mode 0)
		)
		(polygon
			(pts
				(xy 44.0055 -2.4765) (xy 43.92295 -2.55905) (xy 43.92295 -4.2799) (xy 44.07535 -4.4323) (xy 45.1231 -4.4323)
				(xy 45.90415 -3.65125) (xy 45.90415 -2.5781) (xy 45.80255 -2.4765)
			)
		)
		(polygon
			(pts
				(xy 44.5897 -3.6195) (xy 44.3865 -3.6195) (xy 44.3865 -3.8227) (xy 44.5897 -3.8227)
			)
		)
		(polygon
			(pts
				(xy 44.9326 -3.2893) (xy 44.7294 -3.2893) (xy 44.7294 -3.4925) (xy 44.9326 -3.4925)
			)
		)
	)
	(zone
		(layer "F.Cu")
		(hatch none 0.5)
		(connect_pads
			(clearance 0)
		)
		(min_thickness 0.25)
		(keepout
			(tracks allowed)
			(vias allowed)
			(pads allowed)
			(copperpour allowed)
			(footprints not_allowed)
		)
		(placement
			(enabled no)
			(sheetname "")
		)
		(fill
			(thermal_gap 0.5)
			(thermal_bridge_width 0.5)
			(island_removal_mode 0)
		)
		(polygon
			(pts
				(xy 11.500104 0) (xy 11.500104 -12.590018) (xy 0 -12.590018)
				(arc
					(start 0 -0.999998)
					(mid 0.292893 -0.292893)
					(end 0.999998 0)
				)
				(arc
					(start 3.885692 0)
					(mid 4.268375 -0.07612)
					(end 4.592828 -0.292862)
				)
				(arc
					(start 5.007102 -0.707136)
					(mid 5.223884 -1.031573)
					(end 5.299964 -1.414272)
				)
				(arc
					(start 5.299964 -7.590028)
					(mid 6.999986 -9.29005)
					(end 8.700008 -7.590028)
				)
				(arc
					(start 8.700008 -1.414272)
					(mid 8.776128 -1.031589)
					(end 8.99287 -0.707136)
				)
				(arc
					(start 9.407144 -0.292862)
					(mid 9.731581 -0.07608)
					(end 10.11428 0)
				)
			)
		)
	)
	(zone
		(net "GND")
		(layer "F.Cu")
		(hatch none 0.5)
		(connect_pads
			(clearance 0.5)
		)
		(min_thickness 0.25)
		(fill yes
			(thermal_gap 0.5)
			(thermal_bridge_width 0.5)
			(island_removal_mode 0)
		)
		(polygon
			(pts
				(xy 100.6348 4.9276) (xy 100.4824 4.7752) (xy 100.4824 4.2418) (xy 100.9142 3.81) (xy 101.6 3.81)
				(xy 102.5525 2.8575) (xy 106.7943 2.8575) (xy 107.1626 3.2258) (xy 109.3978 3.2258) (xy 110.0582 3.8862)
				(xy 112.5728 3.8862) (xy 112.7506 4.064) (xy 112.7506 4.3434) (xy 112.5474 4.5466) (xy 110.3884 4.5466)
				(xy 110.0582 4.8768) (xy 109.601 4.8768) (xy 108.88345 4.15925) (xy 107.15625 4.15925) (xy 106.68 3.683)
				(xy 104.5591 3.683) (xy 104.3305 3.9116) (xy 104.3178 3.9116) (xy 103.3018 4.9276)
			)
		)
		(polygon
			(pts
				(xy 109.1692 3.9624) (xy 108.966 3.9624) (xy 108.966 3.7592) (xy 109.1692 3.7592)
			)
		)
		(polygon
			(pts
				(xy 108.6104 3.9624) (xy 108.4072 3.9624) (xy 108.4072 3.7592) (xy 108.6104 3.7592)
			)
		)
		(polygon
			(pts
				(xy 108.1278 3.9624) (xy 107.9246 3.9624) (xy 107.9246 3.7592) (xy 108.1278 3.7592)
			)
		)
		(polygon
			(pts
				(xy 107.569 3.9624) (xy 107.3658 3.9624) (xy 107.3658 3.7592) (xy 107.569 3.7592)
			)
		)
	)
	(zone
		(net "P3V3_VR")
		(layer "F.Cu")
		(hatch none 0.5)
		(connect_pads
			(clearance 0.5)
		)
		(min_thickness 0.25)
		(fill yes
			(thermal_gap 0.5)
			(thermal_bridge_width 0.5)
			(island_removal_mode 0)
		)
		(polygon
			(pts
				(xy 25.3746 1.8415) (xy 25.1333 1.6002) (xy 25.1333 -1.143) (xy 25.9969 -2.0066) (xy 31.0134 -2.0066)
				(xy 31.1912 -1.8288) (xy 31.1912 1.4224) (xy 31.0896 1.524) (xy 26.5303 1.524) (xy 26.2128 1.8415)
			)
		)
		(polygon
			(pts
				(xy 28.9306 -0.8382) (xy 28.7274 -0.8382) (xy 28.7274 -1.0414) (xy 28.9306 -1.0414)
			)
		)
		(polygon
			(pts
				(xy 28.067 -0.8382) (xy 27.8638 -0.8382) (xy 27.8638 -1.0414) (xy 28.067 -1.0414)
			)
		)
	)
	(zone
		(layer "F.Cu")
		(hatch none 0.5)
		(connect_pads
			(clearance 0)
		)
		(min_thickness 0.25)
		(keepout
			(tracks allowed)
			(vias allowed)
			(pads allowed)
			(copperpour allowed)
			(footprints not_allowed)
		)
		(placement
			(enabled no)
			(sheetname "")
		)
		(fill
			(thermal_gap 0.5)
			(thermal_bridge_width 0.5)
			(island_removal_mode 0)
		)
		(polygon
			(pts
				(xy 14.549882 6.530086) (xy 14.549882 13.750544) (xy 14.549882 14.029944) (xy 15.050008 14.53007)
				(xy 40.679878 14.53007) (xy 41.180004 14.029944) (xy 41.180004 13.750544)
				(arc
					(start 41.180004 9.329928)
					(mid 42.380154 8.129778)
					(end 43.58005 9.329928)
				)
				(xy 43.58005 13.750544) (xy 43.58005 14.029944) (xy 44.079922 14.53007) (xy 98.49993 14.53007) (xy 99.000056 14.029944)
				(xy 99.000056 13.750544)
				(arc
					(start 99.000056 6.729984)
					(mid 99.058605 6.588635)
					(end 99.199954 6.530086)
				)
			)
		)
	)
	(zone
		(layer "F.Cu")
		(hatch none 0.5)
		(connect_pads
			(clearance 0)
		)
		(min_thickness 0.25)
		(keepout
			(tracks allowed)
			(vias allowed)
			(pads allowed)
			(copperpour allowed)
			(footprints not_allowed)
		)
		(placement
			(enabled no)
			(sheetname "")
		)
		(fill
			(thermal_gap 0.5)
			(thermal_bridge_width 0.5)
			(island_removal_mode 0)
		)
		(polygon
			(pts
				(arc
					(start 2.707132 -34.90722)
					(mid 3.031569 -35.124002)
					(end 3.414268 -35.200082)
				)
				(xy 28.079954 -35.200082) (xy 28.079954 -28.02001)
				(arc
					(start 13.562838 -28.02001)
					(mid 5.762969 -32.474797)
					(end 0 -25.584912)
				)
				(arc
					(start 0 -31.785814)
					(mid 0.07612 -32.168497)
					(end 0.292862 -32.49295)
				)
			)
		)
	)
	(zone
		(net "GND")
		(layer "F.Cu")
		(hatch none 0.5)
		(connect_pads
			(clearance 0.5)
		)
		(min_thickness 0.25)
		(fill yes
			(thermal_gap 0.5)
			(thermal_bridge_width 0.5)
			(island_removal_mode 0)
		)
		(polygon
			(pts
				(xy 25.9588 4.4958) (xy 25.8572 4.3942) (xy 25.8572 3.7084) (xy 25.6794 3.5306) (xy 20.3962 3.5306)
				(xy 19.8882 3.0226) (xy 19.8882 -3.6576) (xy 21.4503 -5.2197) (xy 32.5501 -5.2197) (xy 33.1089 -4.6609)
				(xy 33.1089 -1.143) (xy 32.8168 -0.8509) (xy 31.6103 -0.8509) (xy 31.5214 -0.9398) (xy 31.5214 -2.1463)
				(xy 31.3182 -2.3495) (xy 27.3431 -2.3495) (xy 27.3304 -2.3622) (xy 25.8572 -2.3622) (xy 24.765 -1.27)
				(xy 24.765 2.0066) (xy 25.019 2.2606) (xy 27.3304 2.2606) (xy 27.559 2.4892) (xy 27.559 3.6322)
				(xy 26.6954 4.4958)
			)
		)
		(polygon
			(pts
				(xy 28.9306 -3.1242) (xy 28.7274 -3.1242) (xy 28.7274 -3.3274) (xy 28.9306 -3.3274)
			)
		)
		(polygon
			(pts
				(xy 28.067 -3.1242) (xy 27.8638 -3.1242) (xy 27.8638 -3.3274) (xy 28.067 -3.3274)
			)
		)
		(polygon
			(pts
				(xy 26.5049 3.9878) (xy 26.3017 3.9878) (xy 26.3017 3.7846) (xy 26.5049 3.7846)
			)
		)
	)
	(zone
		(net "P3V3_MB")
		(layer "F.Cu")
		(hatch none 0.5)
		(connect_pads
			(clearance 0.5)
		)
		(min_thickness 0.25)
		(fill yes
			(thermal_gap 0.5)
			(thermal_bridge_width 0.5)
			(island_removal_mode 0)
		)
		(polygon
			(pts
				(xy 23.3172 13.5382) (xy 23.2918 13.5128) (xy 23.2918 10.4648) (xy 23.28545 10.45845) (xy 23.28545 10.35685)
				(xy 23.01875 10.09015) (xy 23.01875 7.38505) (xy 23.9141 6.4897) (xy 23.9141 5.2832) (xy 24.3967 4.8006)
				(xy 26.7716 4.8006) (xy 27.8511 3.7211) (xy 27.8511 2.6416) (xy 28.2321 2.2606) (xy 31.8516 2.2606)
				(xy 32.0548 2.4638) (xy 32.0548 5.969) (xy 31.81985 6.20395) (xy 29.30525 6.20395) (xy 27.6606 7.8486)
				(xy 26.0096 7.8486) (xy 25.20315 8.65505) (xy 25.20315 8.6614) (xy 25.1079 8.75665) (xy 25.1079 9.7282)
				(xy 24.6634 10.1727) (xy 24.6634 13.4874) (xy 24.6126 13.5382) (xy 24.13 13.5382) (xy 24.1046 13.5128)
				(xy 24.1046 10.7696) (xy 24.0538 10.7188) (xy 23.876 10.7188) (xy 23.8506 10.7442) (xy 23.8506 13.462)
				(xy 23.7744 13.5382)
			)
		)
	)
	(zone
		(net "P12V")
		(layer "F.Cu")
		(hatch none 0.5)
		(connect_pads
			(clearance 0.5)
		)
		(min_thickness 0.25)
		(fill yes
			(thermal_gap 0.5)
			(thermal_bridge_width 0.5)
			(island_removal_mode 0)
		)
		(polygon
			(pts
				(xy 16.764 -24.7269) (xy 16.6243 -24.8666) (xy 16.6116 -24.8666) (xy 16.5481 -24.9301) (xy 16.5481 -25.6413)
				(xy 15.8496 -26.3398) (xy 15.8496 -27.2034) (xy 15.9004 -27.2542) (xy 15.9004 -27.2796) (xy 17.3482 -28.7274)
				(xy 18.6182 -28.7274) (xy 18.923 -28.4226) (xy 18.923 -27.813) (xy 19.6342 -27.1018) (xy 19.6342 -27.0256)
				(xy 19.8374 -26.8224) (xy 19.8374 -26.1112) (xy 18.4531 -24.7269)
			)
		)
		(polygon
			(pts
				(xy 18.0594 -27.9654) (xy 17.8562 -27.9654) (xy 17.8562 -28.1686) (xy 18.0594 -28.1686)
			)
		)
	)
	(zone
		(layer "F.Cu")
		(hatch none 0.5)
		(connect_pads
			(clearance 0)
		)
		(min_thickness 0.25)
		(keepout
			(tracks allowed)
			(vias allowed)
			(pads allowed)
			(copperpour allowed)
			(footprints not_allowed)
		)
		(placement
			(enabled no)
			(sheetname "")
		)
		(fill
			(thermal_gap 0.5)
			(thermal_bridge_width 0.5)
			(island_removal_mode 0)
		)
		(polygon
			(pts
				(xy 117.08003 -7.709916) (xy 117.08003 -4.379976) (xy 28.079954 -4.379976) (xy 28.079954 -7.709916)
				(xy 11.500104 -7.709916) (xy 11.500104 0)
				(arc
					(start 14.349984 0)
					(mid 14.491333 0.058549)
					(end 14.549882 0.199898)
				)
				(xy 14.549882 3.50012) (xy 133.199886 3.50012)
				(arc
					(start 133.199886 0.199898)
					(mid 133.258599 0.058533)
					(end 133.400038 0)
				)
				(xy 136.249918 0) (xy 136.249918 -7.709916)
			)
		)
	)
	(zone
		(net "P3V3_STBY")
		(layer "F.Cu")
		(hatch none 0.5)
		(connect_pads
			(clearance 0.5)
		)
		(min_thickness 0.25)
		(fill yes
			(thermal_gap 0.5)
			(thermal_bridge_width 0.5)
			(island_removal_mode 0)
		)
		(polygon
			(pts
				(xy 41.3004 -12.8524) (xy 41.1226 -13.0302) (xy 41.1226 -14.478) (xy 39.8018 -15.7988) (xy 39.8018 -21.5392)
				(xy 37.8968 -23.4442) (xy 37.8968 -25.0444) (xy 38.989 -26.1366) (xy 38.989 -28.3464) (xy 39.4462 -28.8036)
				(xy 41.0464 -28.8036) (xy 41.783 -28.067) (xy 41.783 -16.9672) (xy 42.926 -15.8242) (xy 42.926 -13.4366)
				(xy 42.3418 -12.8524)
			)
		)
		(polygon
			(pts
				(xy 38.5826 -24.9428) (xy 38.3794 -24.9428) (xy 38.3794 -25.146) (xy 38.5826 -25.146)
			)
		)
		(polygon
			(pts
				(xy 38.5826 -24.3332) (xy 38.3794 -24.3332) (xy 38.3794 -24.5364) (xy 38.5826 -24.5364)
			)
		)
		(polygon
			(pts
				(xy 39.1668 -24.003) (xy 38.9636 -24.003) (xy 38.9636 -24.2062) (xy 39.1668 -24.2062)
			)
		)
		(polygon
			(pts
				(xy 38.3032 -24.003) (xy 38.1 -24.003) (xy 38.1 -24.2062) (xy 38.3032 -24.2062)
			)
		)
		(polygon
			(pts
				(xy 39.1668 -23.1394) (xy 38.9636 -23.1394) (xy 38.9636 -23.3426) (xy 39.1668 -23.3426)
			)
		)
	)
	(zone
		(layer "F.Cu")
		(hatch none 0.5)
		(connect_pads
			(clearance 0)
		)
		(min_thickness 0.25)
		(keepout
			(tracks allowed)
			(vias allowed)
			(pads allowed)
			(copperpour allowed)
			(footprints not_allowed)
		)
		(placement
			(enabled no)
			(sheetname "")
		)
		(fill
			(thermal_gap 0.5)
			(thermal_bridge_width 0.5)
			(island_removal_mode 0)
		)
		(polygon
			(pts
				(xy 117.08003 -24.699976) (xy 117.08003 -35.200082) (xy 28.079954 -35.200082) (xy 28.079954 -24.699976)
			)
		)
	)
	(zone
		(layer "F.Cu")
		(hatch none 0.5)
		(connect_pads
			(clearance 0)
		)
		(min_thickness 0.25)
		(keepout
			(tracks allowed)
			(vias allowed)
			(pads allowed)
			(copperpour allowed)
			(footprints not_allowed)
		)
		(placement
			(enabled no)
			(sheetname "")
		)
		(fill
			(thermal_gap 0.5)
			(thermal_bridge_width 0.5)
			(island_removal_mode 0)
		)
		(polygon
			(pts
				(xy 11.500104 -7.709916) (xy 11.500104 -13.310108) (xy 28.079954 -13.310108) (xy 28.079954 -7.709916)
			)
		)
	)
	(zone
		(layer "F.Cu")
		(hatch none 0.5)
		(connect_pads
			(clearance 0)
		)
		(min_thickness 0.25)
		(keepout
			(tracks allowed)
			(vias allowed)
			(pads allowed)
			(copperpour allowed)
			(footprints not_allowed)
		)
		(placement
			(enabled no)
			(sheetname "")
		)
		(fill
			(thermal_gap 0.5)
			(thermal_bridge_width 0.5)
			(island_removal_mode 0)
		)
		(polygon
			(pts
				(xy 117.08003 -15.230094) (xy 28.079954 -15.230094) (xy 28.079954 -4.379976) (xy 117.08003 -4.379976)
			)
		)
	)
	(zone
		(net "P3V3_STBY")
		(layer "F.Cu")
		(hatch none 0.5)
		(connect_pads
			(clearance 0.5)
		)
		(min_thickness 0.25)
		(fill yes
			(thermal_gap 0.5)
			(thermal_bridge_width 0.5)
			(island_removal_mode 0)
		)
		(polygon
			(pts
				(xy 113.5888 -19.2278) (xy 108.1532 -24.6634) (xy 106.68 -24.6634) (xy 106.172 -24.1554) (xy 106.172 -20.7772)
				(xy 105.918 -20.5232) (xy 105.0544 -20.5232) (xy 104.6988 -20.8788) (xy 104.6988 -24.1046) (xy 103.378 -25.4254)
				(xy 97.4852 -25.4254) (xy 96.647 -24.5872) (xy 96.647 -24.13) (xy 97.0788 -23.6982) (xy 97.0788 -22.3266)
				(xy 96.901 -22.1488) (xy 96.7232 -22.1488) (xy 96.3422 -22.5298) (xy 93.726 -22.5298) (xy 93.3958 -22.1996)
				(xy 93.3958 -19.6596) (xy 93.2434 -19.5072) (xy 92.6846 -19.5072) (xy 92.583 -19.6088) (xy 92.583 -22.5044)
				(xy 91.0463 -24.0411) (xy 89.6239 -24.0411) (xy 89.6112 -24.0538) (xy 84.3534 -24.0538) (xy 83.0326 -22.733)
				(xy 65.4812 -22.733) (xy 65.2526 -22.9616) (xy 65.2526 -23.7998) (xy 65.3796 -23.9268) (xy 66.9798 -23.9268)
				(xy 67.564 -23.3426) (xy 80.645 -23.3426) (xy 80.8482 -23.5458) (xy 80.8482 -24.8158) (xy 80.9752 -24.9428)
				(xy 95.885 -24.9428) (xy 97.028 -26.0858) (xy 108.204 -26.0858) (xy 114.3254 -19.9644) (xy 116.7892 -19.9644)
				(xy 116.84 -19.9136) (xy 116.84 -19.3294) (xy 116.7384 -19.2278)
			)
		)
		(polygon
			(pts
				(xy 88.519 -24.511) (xy 88.3158 -24.511) (xy 88.3158 -24.7142) (xy 88.519 -24.7142)
			)
		)
		(polygon
			(pts
				(xy 87.9602 -24.511) (xy 87.757 -24.511) (xy 87.757 -24.7142) (xy 87.9602 -24.7142)
			)
		)
		(polygon
			(pts
				(xy 81.5848 -24.0792) (xy 81.3816 -24.0792) (xy 81.3816 -24.2824) (xy 81.5848 -24.2824)
			)
		)
		(polygon
			(pts
				(xy 65.9892 -23.2664) (xy 65.786 -23.2664) (xy 65.786 -23.4696) (xy 65.9892 -23.4696)
			)
		)
		(polygon
			(pts
				(xy 105.5116 -22.4028) (xy 105.3084 -22.4028) (xy 105.3084 -22.606) (xy 105.5116 -22.606)
			)
		)
		(polygon
			(pts
				(xy 105.5116 -21.7932) (xy 105.3084 -21.7932) (xy 105.3084 -21.9964) (xy 105.5116 -21.9964)
			)
		)
	)
	(zone
		(layer "F.Cu")
		(hatch none 0.5)
		(connect_pads
			(clearance 0)
		)
		(min_thickness 0.25)
		(keepout
			(tracks allowed)
			(vias allowed)
			(pads allowed)
			(copperpour allowed)
			(footprints allowed)
		)
		(placement
			(enabled no)
			(sheetname "")
		)
		(fill
			(thermal_gap 0.5)
			(thermal_bridge_width 0.5)
			(island_removal_mode 0)
		)
		(polygon
			(pts
				(xy 36.2966 -26.8986) (xy 37.9349 -26.8986) (xy 38.735 -27.6987) (xy 38.735 -30.2006) (xy 38.481 -30.4546)
				(xy 37.5793 -30.4546) (xy 36.322 -29.1973) (xy 36.322 -26.924)
			)
		)
	)
	(zone
		(net "GND")
		(layer "F.Cu")
		(hatch none 0.5)
		(connect_pads
			(clearance 0.5)
		)
		(min_thickness 0.25)
		(fill yes
			(thermal_gap 0.5)
			(thermal_bridge_width 0.5)
			(island_removal_mode 0)
		)
		(polygon
			(pts
				(xy 1.27 -12.8778) (xy 0.762254 -13.385546)
				(arc
					(start 0.762254 -31.786322)
					(mid 0.764081 -31.814987)
					(end 0.769366 -31.843218)
				)
				(arc
					(start 0.769366 -31.843218)
					(mid 0.78649 -31.887871)
					(end 0.8128 -31.9278)
				)
				(arc
					(start 3.2512 -34.3662)
					(mid 3.291528 -34.398813)
					(end 3.3401 -34.417)
				)
				(xy 3.3528 -34.417) (xy 3.3655 -34.4297) (xy 25.7556 -34.4297) (xy 25.8318 -34.3535) (xy 25.8318 -32.4358)
				(xy 25.7556 -32.3596) (xy 12.3444 -32.3596) (xy 11.6586 -31.6738) (xy 11.6586 -23.7109) (xy 8.89 -20.9423)
				(xy 8.89 -14.1224) (xy 7.6454 -12.8778)
			)
		)
		(polygon
			(pts
				(xy 18.1356 -33.0962) (xy 17.9324 -33.0962) (xy 17.9324 -33.2994) (xy 18.1356 -33.2994)
			)
		)
		(polygon
			(pts
				(xy 17.272 -33.0962) (xy 17.0688 -33.0962) (xy 17.0688 -33.2994) (xy 17.272 -33.2994)
			)
		)
		(polygon
			(pts
				(xy 16.9418 -33.0962) (xy 16.7386 -33.0962) (xy 16.7386 -33.2994) (xy 16.9418 -33.2994)
			)
		)
		(polygon
			(pts
				(xy 16.0782 -33.0962) (xy 15.875 -33.0962) (xy 15.875 -33.2994) (xy 16.0782 -33.2994)
			)
		)
		(polygon
			(pts
				(xy 15.6972 -33.0962) (xy 15.494 -33.0962) (xy 15.494 -33.2994) (xy 15.6972 -33.2994)
			)
		)
		(polygon
			(pts
				(xy 14.8336 -33.0962) (xy 14.6304 -33.0962) (xy 14.6304 -33.2994) (xy 14.8336 -33.2994)
			)
		)
		(polygon
			(pts
				(xy 14.5034 -33.0962) (xy 14.3002 -33.0962) (xy 14.3002 -33.2994) (xy 14.5034 -33.2994)
			)
		)
		(polygon
			(pts
				(xy 13.6398 -33.0962) (xy 13.4366 -33.0962) (xy 13.4366 -33.2994) (xy 13.6398 -33.2994)
			)
		)
	)
	(zone
		(net "P3V3_VIN")
		(layer "F.Cu")
		(hatch none 0.5)
		(connect_pads
			(clearance 0.5)
		)
		(min_thickness 0.25)
		(fill yes
			(thermal_gap 0.5)
			(thermal_bridge_width 0.5)
			(island_removal_mode 0)
		)
		(polygon
			(pts
				(xy 18.3007 -6.6675) (xy 17.907 -7.0612) (xy 17.907 -13.9954) (xy 18.1356 -14.224) (xy 18.1356 -14.2748)
				(xy 18.4658 -14.605) (xy 19.8374 -14.605) (xy 19.8628 -14.6304) (xy 22.5044 -14.6304) (xy 22.8346 -14.3002)
				(xy 22.8346 -7.4168) (xy 22.0853 -6.6675)
			)
		)
		(polygon
			(pts
				(xy 19.3675 -13.7541) (xy 19.1643 -13.7541) (xy 19.1643 -13.9573) (xy 19.3675 -13.9573)
			)
		)
		(polygon
			(pts
				(xy 18.2245 -13.7541) (xy 18.0213 -13.7541) (xy 18.0213 -13.9573) (xy 18.2245 -13.9573)
			)
		)
		(polygon
			(pts
				(xy 19.3675 -12.3571) (xy 19.1643 -12.3571) (xy 19.1643 -12.5603) (xy 19.3675 -12.5603)
			)
		)
		(polygon
			(pts
				(xy 18.2245 -12.3571) (xy 18.0213 -12.3571) (xy 18.0213 -12.5603) (xy 18.2245 -12.5603)
			)
		)
	)
	(zone
		(layer "F.Cu")
		(hatch none 0.5)
		(connect_pads
			(clearance 0)
		)
		(min_thickness 0.25)
		(keepout
			(tracks allowed)
			(vias allowed)
			(pads allowed)
			(copperpour allowed)
			(footprints not_allowed)
		)
		(placement
			(enabled no)
			(sheetname "")
		)
		(fill
			(thermal_gap 0.5)
			(thermal_bridge_width 0.5)
			(island_removal_mode 0)
		)
		(polygon
			(pts
				(xy 117.08003 -28.02001) (xy 131.579874 -28.02001) (xy 131.579874 -35.200082) (xy 117.08003 -35.200082)
			)
		)
	)
	(zone
		(layer "F.Cu")
		(hatch none 0.5)
		(connect_pads
			(clearance 0)
		)
		(min_thickness 0.25)
		(keepout
			(tracks allowed)
			(vias allowed)
			(pads allowed)
			(copperpour allowed)
			(footprints allowed)
		)
		(placement
			(enabled no)
			(sheetname "")
		)
		(fill
			(thermal_gap 0.5)
			(thermal_bridge_width 0.5)
			(island_removal_mode 0)
		)
		(polygon
			(pts
				(xy 14.2367 -20.3835) (xy 16.5608 -18.0594) (xy 17.018 -18.0594) (xy 21.0058 -22.0472) (xy 21.0058 -27.1272)
				(xy 19.812 -28.321) (xy 17.6911 -28.321) (xy 17.64665 -28.27655) (xy 13.7414 -28.27655) (xy 13.7414 -20.8661)
				(xy 14.224 -20.3835)
			)
		)
	)
	(zone
		(net "GND")
		(layer "F.Cu")
		(hatch none 0.5)
		(connect_pads
			(clearance 0.5)
		)
		(min_thickness 0.25)
		(fill yes
			(thermal_gap 0.5)
			(thermal_bridge_width 0.5)
			(island_removal_mode 0)
		)
		(polygon
			(pts
				(xy 24.003 -6.5278) (xy 23.1394 -7.3914) (xy 23.1394 -14.1986) (xy 23.4188 -14.478) (xy 24.7396 -14.478)
				(xy 25.146 -14.0716) (xy 25.146 -13.0556) (xy 25.7937 -12.4079) (xy 25.7937 -11.4935) (xy 26.2128 -11.0744)
				(xy 26.2128 -8.4328) (xy 26.0604 -8.2804) (xy 26.0604 -6.731) (xy 25.8572 -6.5278)
			)
		)
		(polygon
			(pts
				(xy 24.9936 -12.3444) (xy 24.7904 -12.3444) (xy 24.7904 -12.5476) (xy 24.9936 -12.5476)
			)
		)
		(polygon
			(pts
				(xy 24.9936 -11.4808) (xy 24.7904 -11.4808) (xy 24.7904 -11.684) (xy 24.9936 -11.684)
			)
		)
		(polygon
			(pts
				(xy 25.146 -7.5692) (xy 24.9428 -7.5692) (xy 24.9428 -7.7724) (xy 25.146 -7.7724)
			)
		)
		(polygon
			(pts
				(xy 25.146 -6.7056) (xy 24.9428 -6.7056) (xy 24.9428 -6.9088) (xy 25.146 -6.9088)
			)
		)
	)
	(zone
		(layer "F.Cu")
		(hatch none 0.5)
		(connect_pads
			(clearance 0)
		)
		(min_thickness 0.25)
		(keepout
			(tracks allowed)
			(vias allowed)
			(pads allowed)
			(copperpour allowed)
			(footprints allowed)
		)
		(placement
			(enabled no)
			(sheetname "")
		)
		(fill
			(thermal_gap 0.5)
			(thermal_bridge_width 0.5)
			(island_removal_mode 0)
		)
		(polygon
			(pts
				(xy 19.4056 -28.5242) (xy 19.4056 -26.2636) (xy 19.6342 -26.035) (xy 21.1328 -26.035) (xy 21.1836 -26.0858)
				(xy 21.1836 -28.321) (xy 21.1836 -28.4988) (xy 21.1328 -28.5496) (xy 21.082 -28.5496) (xy 20.955 -28.5496)
				(xy 19.431 -28.5496)
			)
		)
	)
	(zone
		(net "P3V3_STBY")
		(layer "F.Cu")
		(hatch none 0.5)
		(connect_pads
			(clearance 0.5)
		)
		(min_thickness 0.25)
		(fill yes
			(thermal_gap 0.5)
			(thermal_bridge_width 0.5)
			(island_removal_mode 0)
		)
		(polygon
			(pts
				(xy 42.1259 -2.1082) (xy 41.7068 -2.5273) (xy 41.7068 -3.8608) (xy 39.3573 -6.2103) (xy 39.3573 -6.4135)
				(xy 39.3446 -6.4262) (xy 39.3446 -7.5184) (xy 39.8018 -7.9756) (xy 40.8432 -7.9756) (xy 43.6118 -5.207)
				(xy 43.6118 -2.2479) (xy 43.4721 -2.1082)
			)
		)
		(polygon
			(pts
				(xy 43.0657 -4.2291) (xy 42.8625 -4.2291) (xy 42.8625 -4.4323) (xy 43.0657 -4.4323)
			)
		)
		(polygon
			(pts
				(xy 43.0657 -3.6195) (xy 42.8625 -3.6195) (xy 42.8625 -3.8227) (xy 43.0657 -3.8227)
			)
		)
		(polygon
			(pts
				(xy 42.6466 -3.2893) (xy 42.4434 -3.2893) (xy 42.4434 -3.4925) (xy 42.6466 -3.4925)
			)
		)
		(polygon
			(pts
				(xy 42.6466 -2.4257) (xy 42.4434 -2.4257) (xy 42.4434 -2.6289) (xy 42.6466 -2.6289)
			)
		)
	)
	(zone
		(layer "F.Cu")
		(hatch none 0.5)
		(connect_pads
			(clearance 0)
		)
		(min_thickness 0.25)
		(keepout
			(tracks allowed)
			(vias allowed)
			(pads allowed)
			(copperpour allowed)
			(footprints allowed)
		)
		(placement
			(enabled no)
			(sheetname "")
		)
		(fill
			(thermal_gap 0.5)
			(thermal_bridge_width 0.5)
			(island_removal_mode 0)
		)
		(polygon
			(pts
				(xy 131.6736 -22.86) (xy 131.6736 -20.0152) (xy 132.1816 -19.5072) (xy 133.9088 -19.5072) (xy 134.1628 -19.7612)
				(xy 134.1628 -21.5392) (xy 132.461 -23.241) (xy 132.0546 -23.241)
			)
		)
	)
	(zone
		(net "GND")
		(layer "F.Cu")
		(hatch none 0.5)
		(connect_pads
			(clearance 0.5)
		)
		(min_thickness 0.25)
		(fill yes
			(thermal_gap 0.5)
			(thermal_bridge_width 0.5)
			(island_removal_mode 0)
		)
		(polygon
			(pts
				(xy 135.6868 -13.0556) (xy 135.4328 -13.3096) (xy 135.4328 -20.6248) (xy 133.9088 -22.1488) (xy 133.9088 -27.2288)
				(xy 132.8547 -28.2829) (xy 132.8547 -29.21) (xy 133.4389 -29.7942) (xy 134.2263 -29.7942) (xy 134.6454 -30.2133)
				(xy 134.6454 -33.0581) (xy 134.112 -33.5915) (xy 127.1397 -33.5915) (xy 126.9873 -33.7439) (xy 126.9873 -34.1122)
				(xy 127.3048 -34.4297) (xy 144.1069 -34.4297) (xy 146.7231 -31.8135) (xy 146.7231 -13.8938) (xy 145.8849 -13.0556)
			)
		)
		(polygon
			(pts
				(xy 134.0358 -29.1084) (xy 133.8326 -29.1084) (xy 133.8326 -29.3116) (xy 134.0358 -29.3116)
			)
		)
	)
	(zone
		(net "GND")
		(layer "F.Cu")
		(hatch none 0.5)
		(connect_pads
			(clearance 0.5)
		)
		(min_thickness 0.25)
		(fill yes
			(thermal_gap 0.5)
			(thermal_bridge_width 0.5)
			(island_removal_mode 0)
		)
		(polygon
			(pts
				(xy 32.1056 -15.3162) (xy 30.5054 -16.9164) (xy 30.5054 -19.939) (xy 30.7594 -20.193) (xy 34.1376 -20.193)
				(xy 34.3408 -19.9898) (xy 34.3408 -15.5702) (xy 34.0868 -15.3162)
			)
		)
	)
	(zone
		(layer "F.Cu")
		(hatch none 0.5)
		(connect_pads
			(clearance 0)
		)
		(min_thickness 0.25)
		(keepout
			(tracks allowed)
			(vias allowed)
			(pads allowed)
			(copperpour allowed)
			(footprints not_allowed)
		)
		(placement
			(enabled no)
			(sheetname "")
		)
		(fill
			(thermal_gap 0.5)
			(thermal_bridge_width 0.5)
			(island_removal_mode 0)
		)
		(polygon
			(pts
				(arc
					(start 147.500086 -25.584912)
					(mid 140.5001 -32.584898)
					(end 133.500114 -25.584912)
				)
				(arc
					(start 133.500114 -25.584912)
					(mid 140.5001 -18.584926)
					(end 147.500086 -25.584912)
				)
			)
		)
	)
	(zone
		(net "P12V_SLOT2")
		(layer "F.Cu")
		(hatch none 0.5)
		(connect_pads
			(clearance 0.5)
		)
		(min_thickness 0.25)
		(fill yes
			(thermal_gap 0.5)
			(thermal_bridge_width 0.5)
			(island_removal_mode 0)
		)
		(polygon
			(pts
				(xy 12.9286 -16.5862) (xy 12.5222 -16.9926) (xy 12.5222 -19.3294) (xy 13.2334 -20.0406) (xy 14.0208 -20.0406)
				(xy 15.22095 -18.84045) (xy 15.22095 -18.75155) (xy 14.2113 -17.7419) (xy 14.2113 -17.1577) (xy 13.6398 -16.5862)
			)
		)
	)
	(zone
		(layer "F.Cu")
		(hatch none 0.5)
		(connect_pads
			(clearance 0)
		)
		(min_thickness 0.25)
		(keepout
			(tracks allowed)
			(vias allowed)
			(pads allowed)
			(copperpour allowed)
			(footprints not_allowed)
		)
		(placement
			(enabled no)
			(sheetname "")
		)
		(fill
			(thermal_gap 0.5)
			(thermal_bridge_width 0.5)
			(island_removal_mode 0)
		)
		(polygon
			(pts
				(arc
					(start 138.800078 -7.590028)
					(mid 140.5001 -9.29005)
					(end 142.200122 -7.590028)
				)
				(arc
					(start 142.200122 -1.414272)
					(mid 142.276242 -1.031589)
					(end 142.492984 -0.707136)
				)
				(arc
					(start 142.907004 -0.292862)
					(mid 143.231441 -0.07608)
					(end 143.61414 0)
				)
				(arc
					(start 146.500088 0)
					(mid 147.207193 -0.292893)
					(end 147.500086 -0.999998)
				)
				(xy 147.500086 -12.590018) (xy 136.249918 -12.590018) (xy 136.249918 0)
				(arc
					(start 137.385806 0)
					(mid 137.768489 -0.07612)
					(end 138.092942 -0.292862)
				)
				(arc
					(start 138.507216 -0.707136)
					(mid 138.723998 -1.031573)
					(end 138.800078 -1.414272)
				)
			)
		)
	)
	(zone
		(net "P12V_SLOT3")
		(layer "F.Cu")
		(hatch none 0.5)
		(connect_pads
			(clearance 0.5)
		)
		(min_thickness 0.25)
		(fill yes
			(thermal_gap 0.5)
			(thermal_bridge_width 0.5)
			(island_removal_mode 0)
		)
		(polygon
			(pts
				(xy 12.7 -24.2824) (xy 12.446 -24.5364) (xy 12.446 -31.369) (xy 13.0556 -31.9786) (xy 26.1874 -31.9786)
				(xy 26.3017 -32.0929) (xy 26.3017 -32.2961) (xy 26.3144 -32.3088) (xy 26.3144 -33.8582) (xy 26.8859 -34.4297)
				(xy 32.7787 -34.4297) (xy 34.036 -33.1724) (xy 34.036 -28.067) (xy 33.7312 -27.7622) (xy 33.7312 -26.9494)
				(xy 33.401 -26.6192) (xy 30.8356 -26.6192) (xy 30.4927 -26.9621) (xy 30.4927 -28.1051) (xy 28.194 -30.4038)
				(xy 16.002 -30.4038) (xy 15.9258 -30.3276) (xy 15.9004 -30.3276) (xy 15.4051 -29.8323) (xy 15.4051 -29.6037)
				(xy 15.3924 -29.591) (xy 15.3924 -26.16835) (xy 15.9766 -25.58415) (xy 15.9766 -24.2824)
			)
		)
		(polygon
			(pts
				(xy 18.1356 -30.8102) (xy 17.9324 -30.8102) (xy 17.9324 -31.0134) (xy 18.1356 -31.0134)
			)
		)
		(polygon
			(pts
				(xy 17.272 -30.8102) (xy 17.0688 -30.8102) (xy 17.0688 -31.0134) (xy 17.272 -31.0134)
			)
		)
		(polygon
			(pts
				(xy 16.9418 -30.8102) (xy 16.7386 -30.8102) (xy 16.7386 -31.0134) (xy 16.9418 -31.0134)
			)
		)
		(polygon
			(pts
				(xy 16.0782 -30.8102) (xy 15.875 -30.8102) (xy 15.875 -31.0134) (xy 16.0782 -31.0134)
			)
		)
		(polygon
			(pts
				(xy 15.6972 -30.8102) (xy 15.494 -30.8102) (xy 15.494 -31.0134) (xy 15.6972 -31.0134)
			)
		)
		(polygon
			(pts
				(xy 14.8336 -30.8102) (xy 14.6304 -30.8102) (xy 14.6304 -31.0134) (xy 14.8336 -31.0134)
			)
		)
		(polygon
			(pts
				(xy 14.5034 -30.8102) (xy 14.3002 -30.8102) (xy 14.3002 -31.0134) (xy 14.5034 -31.0134)
			)
		)
		(polygon
			(pts
				(xy 13.6398 -30.8102) (xy 13.4366 -30.8102) (xy 13.4366 -31.0134) (xy 13.6398 -31.0134)
			)
		)
	)
	(zone
		(layer "F.Cu")
		(hatch none 0.5)
		(connect_pads
			(clearance 0)
		)
		(min_thickness 0.25)
		(keepout
			(tracks allowed)
			(vias allowed)
			(pads allowed)
			(copperpour allowed)
			(footprints allowed)
		)
		(placement
			(enabled no)
			(sheetname "")
		)
		(fill
			(thermal_gap 0.5)
			(thermal_bridge_width 0.5)
			(island_removal_mode 0)
		)
		(polygon
			(pts
				(xy 80.5688 -22.098) (xy 80.5688 -19.6596) (xy 81.5086 -18.7198) (xy 82.6262 -18.7198) (xy 82.9056 -18.9992)
				(xy 82.9056 -21.8186) (xy 82.423 -22.3012) (xy 80.772 -22.3012)
			)
		)
	)
	(zone
		(layer "F.Cu")
		(hatch none 0.5)
		(connect_pads
			(clearance 0)
		)
		(min_thickness 0.25)
		(keepout
			(tracks allowed)
			(vias allowed)
			(pads allowed)
			(copperpour allowed)
			(footprints allowed)
		)
		(placement
			(enabled no)
			(sheetname "")
		)
		(fill
			(thermal_gap 0.5)
			(thermal_bridge_width 0.5)
			(island_removal_mode 0)
		)
		(polygon
			(pts
				(xy 120.015 -32.004) (xy 120.015 -23.9014) (xy 120.015 -23.622) (xy 120.1674 -23.4696) (xy 128.905 -23.4696)
				(xy 129.1844 -23.749) (xy 129.1844 -26.6446) (xy 132.8928 -26.6446) (xy 133.1722 -26.924) (xy 133.1722 -27.4066)
				(xy 132.842 -27.7368) (xy 129.1844 -27.7368) (xy 129.1844 -32.0802) (xy 129.1844 -33.0454) (xy 128.397 -33.8328)
				(xy 120.7262 -33.8328) (xy 120.4976 -33.8328) (xy 120.4849 -33.8201) (xy 118.4021 -33.8201) (xy 117.8814 -33.2994)
				(xy 117.8814 -32.1564) (xy 118.0338 -32.004)
			)
		)
	)
	(zone
		(net "GND")
		(layer "F.Cu")
		(hatch none 0.5)
		(connect_pads
			(clearance 0.5)
		)
		(min_thickness 0.25)
		(fill yes
			(thermal_gap 0.5)
			(thermal_bridge_width 0.5)
			(island_removal_mode 0)
		)
		(polygon
			(pts
				(xy 35.3568 -23.0886) (xy 35.179 -23.2664) (xy 35.179 -24.1554) (xy 36.2204 -25.1968) (xy 37.4142 -25.1968)
				(xy 37.6682 -24.9428) (xy 37.6682 -23.2664) (xy 37.4904 -23.0886)
			)
		)
		(polygon
			(pts
				(xy 37.0586 -24.3332) (xy 36.8554 -24.3332) (xy 36.8554 -24.5364) (xy 37.0586 -24.5364)
			)
		)
		(polygon
			(pts
				(xy 36.8808 -24.003) (xy 36.6776 -24.003) (xy 36.6776 -24.2062) (xy 36.8808 -24.2062)
			)
		)
		(polygon
			(pts
				(xy 35.9156 -23.8252) (xy 35.7124 -23.8252) (xy 35.7124 -24.0284) (xy 35.9156 -24.0284)
			)
		)
		(polygon
			(pts
				(xy 35.9156 -23.2156) (xy 35.7124 -23.2156) (xy 35.7124 -23.4188) (xy 35.9156 -23.4188)
			)
		)
	)
	(zone
		(net "GND")
		(layer "F.Cu")
		(hatch none 0.5)
		(connect_pads
			(clearance 0.5)
		)
		(min_thickness 0.25)
		(fill yes
			(thermal_gap 0.5)
			(thermal_bridge_width 0.5)
			(island_removal_mode 0)
		)
		(polygon
			(pts
				(xy 39.2938 1.27) (xy 38.9636 0.9398) (xy 38.9636 -4.4577) (xy 39.0271 -4.5212) (xy 40.5892 -4.5212)
				(xy 41.2877 -3.8227) (xy 41.2877 -2.3622) (xy 42.3291 -1.3208) (xy 42.3291 -0.6604) (xy 42.2656 -0.5969)
				(xy 41.3893 -0.5969) (xy 41.3131 -0.6731) (xy 40.9829 -0.6731) (xy 40.5384 -0.2286) (xy 40.5384 0.3302)
				(xy 39.5986 1.27)
			)
		)
		(polygon
			(pts
				(xy 39.5605 -0.2667) (xy 39.3573 -0.2667) (xy 39.3573 -0.4699) (xy 39.5605 -0.4699)
			)
		)
	)
	(zone
		(layer "F.Cu")
		(hatch none 0.5)
		(connect_pads
			(clearance 0)
		)
		(min_thickness 0.25)
		(keepout
			(tracks allowed)
			(vias allowed)
			(pads allowed)
			(copperpour allowed)
			(footprints allowed)
		)
		(placement
			(enabled no)
			(sheetname "")
		)
		(fill
			(thermal_gap 0.5)
			(thermal_bridge_width 0.5)
			(island_removal_mode 0)
		)
		(polygon
			(pts
				(xy 13.081 -18.669) (xy 13.081 -18.5801) (xy 15.9639 -15.6972) (xy 16.4846 -15.6972) (xy 17.1958 -16.4084)
				(xy 17.1958 -18.0467) (xy 15.3924 -19.8501) (xy 14.2621 -19.8501)
			)
		)
	)
	(zone
		(layer "F.Cu")
		(hatch none 0.5)
		(connect_pads
			(clearance 0)
		)
		(min_thickness 0.25)
		(keepout
			(tracks allowed)
			(vias allowed)
			(pads allowed)
			(copperpour allowed)
			(footprints not_allowed)
		)
		(placement
			(enabled no)
			(sheetname "")
		)
		(fill
			(thermal_gap 0.5)
			(thermal_bridge_width 0.5)
			(island_removal_mode 0)
		)
		(polygon
			(pts
				(arc
					(start 107.95 6.729984)
					(mid 107.891451 6.588635)
					(end 107.750102 6.530086)
				)
				(xy 133.199886 6.530086) (xy 133.199886 13.750544) (xy 133.199886 14.029944) (xy 132.700014 14.53007)
				(xy 108.450126 14.53007) (xy 107.95 14.029944) (xy 107.95 13.750544)
			)
		)
	)
	(zone
		(net "P12V_SLOT2")
		(layer "F.Cu")
		(hatch none 0.5)
		(connect_pads
			(clearance 0.5)
		)
		(min_thickness 0.25)
		(fill yes
			(thermal_gap 0.5)
			(thermal_bridge_width 0.5)
			(island_removal_mode 0)
		)
		(polygon
			(pts
				(xy 27.3304 -5.7912) (xy 26.4668 -6.6548) (xy 26.4668 -7.874) (xy 27.3558 -8.763) (xy 27.3304 -8.7884)
				(xy 27.3304 -10.6426) (xy 26.3144 -11.6586) (xy 26.2382 -11.6586) (xy 26.2382 -12.573) (xy 25.781 -13.0302)
				(xy 25.781 -16.1544) (xy 26.289 -16.6624) (xy 28.9306 -16.6624) (xy 29.5148 -16.0782) (xy 29.5148 -15.3162)
				(xy 30.1498 -14.6812) (xy 32.4866 -14.6812) (xy 33.8582 -13.3096) (xy 33.8582 -8.8392) (xy 32.7406 -7.7216)
				(xy 32.7406 -6.2865) (xy 32.2453 -5.7912)
			)
		)
		(polygon
			(pts
				(xy 28.2702 -15.5448) (xy 28.067 -15.5448) (xy 28.067 -15.748) (xy 28.2702 -15.748)
			)
		)
		(polygon
			(pts
				(xy 27.9146 -15.5194) (xy 27.7114 -15.5194) (xy 27.7114 -15.7226) (xy 27.9146 -15.7226)
			)
		)
		(polygon
			(pts
				(xy 27.051 -15.5194) (xy 26.8478 -15.5194) (xy 26.8478 -15.7226) (xy 27.051 -15.7226)
			)
		)
		(polygon
			(pts
				(xy 27.2796 -12.3444) (xy 27.0764 -12.3444) (xy 27.0764 -12.5476) (xy 27.2796 -12.5476)
			)
		)
		(polygon
			(pts
				(xy 27.2796 -11.4808) (xy 27.0764 -11.4808) (xy 27.0764 -11.684) (xy 27.2796 -11.684)
			)
		)
		(polygon
			(pts
				(xy 27.432 -7.5692) (xy 27.2288 -7.5692) (xy 27.2288 -7.7724) (xy 27.432 -7.7724)
			)
		)
		(polygon
			(pts
				(xy 27.432 -6.7056) (xy 27.2288 -6.7056) (xy 27.2288 -6.9088) (xy 27.432 -6.9088)
			)
		)
	)
	(zone
		(layer "F.Cu")
		(hatch none 0.5)
		(connect_pads
			(clearance 0)
		)
		(min_thickness 0.25)
		(keepout
			(tracks allowed)
			(vias allowed)
			(pads allowed)
			(copperpour allowed)
			(footprints not_allowed)
		)
		(placement
			(enabled no)
			(sheetname "")
		)
		(fill
			(thermal_gap 0.5)
			(thermal_bridge_width 0.5)
			(island_removal_mode 0)
		)
		(polygon
			(pts
				(arc
					(start 13.999972 -25.584912)
					(mid 6.999986 -18.584926)
					(end 0 -25.584912)
				)
				(xy 0 -12.590018) (xy 11.500104 -12.590018) (xy 11.500104 -13.310108) (xy 28.079954 -13.310108)
				(xy 28.079954 -15.230094) (xy 117.08003 -15.230094) (xy 117.08003 -13.310108) (xy 136.249918 -13.310108)
				(xy 136.249918 -12.590018) (xy 147.500086 -12.590018)
				(arc
					(start 147.500086 -31.785814)
					(mid 147.423966 -32.168497)
					(end 147.207224 -32.49295)
				)
				(arc
					(start 144.792954 -34.90722)
					(mid 144.468517 -35.124002)
					(end 144.085818 -35.200082)
				)
				(xy 131.579874 -35.200082) (xy 131.579874 -28.02001) (xy 117.08003 -28.02001) (xy 117.08003 -24.699976)
				(xy 28.079954 -24.699976) (xy 28.079954 -28.02001)
				(arc
					(start 13.562838 -28.02001)
					(mid 13.889828 -26.821925)
					(end 13.999972 -25.584912)
				)
			)
		)
	)
	(zone
		(layer "F.Cu")
		(hatch none 0.5)
		(connect_pads
			(clearance 0)
		)
		(min_thickness 0.25)
		(keepout
			(tracks allowed)
			(vias allowed)
			(pads allowed)
			(copperpour allowed)
			(footprints allowed)
		)
		(placement
			(enabled no)
			(sheetname "")
		)
		(fill
			(thermal_gap 0.5)
			(thermal_bridge_width 0.5)
			(island_removal_mode 0)
		)
		(polygon
			(pts
				(xy 51.7652 -21.7678) (xy 51.7652 -19.3548) (xy 53.2892 -17.8308) (xy 56.9214 -17.8308) (xy 57.6326 -18.542)
				(xy 57.6326 -19.6596) (xy 55.118 -22.1742) (xy 52.1716 -22.1742)
			)
		)
	)
	(zone
		(net "P3V3_STBY")
		(layer "F.Cu")
		(hatch none 0.5)
		(connect_pads
			(clearance 0.5)
		)
		(min_thickness 0.25)
		(fill yes
			(thermal_gap 0.5)
			(thermal_bridge_width 0.5)
			(island_removal_mode 0)
		)
		(polygon
			(pts
				(xy 114.9604 4.191) (xy 114.3762 3.6068) (xy 111.7854 3.6068) (xy 111.3028 3.1242) (xy 111.3028 1.8796)
				(xy 109.601 0.1778) (xy 104.5972 0.1778) (xy 101.4222 3.3528) (xy 100.2538 3.3528) (xy 100.1268 3.2258)
				(xy 100.1268 -1.5113) (xy 100.4189 -1.8034) (xy 101.1174 -1.8034) (xy 101.219 -1.7018) (xy 101.219 -0.9144)
				(xy 101.8159 -0.3175) (xy 102.7938 -0.3175) (xy 103.9622 -1.4859) (xy 107.5182 -1.4859) (xy 111.9378 -5.9055)
				(xy 113.2967 -5.9055) (xy 113.3094 -5.9182) (xy 113.7412 -5.4864) (xy 113.7412 -5.3848) (xy 114.046 -5.08)
				(xy 114.046 -4.3688) (xy 113.3348 -3.6576) (xy 112.3442 -3.6576) (xy 111.6584 -2.9718) (xy 111.6584 0.1524)
				(xy 111.7727 0.2667) (xy 114.8969 0.2667) (xy 116.205 -1.0414) (xy 116.205 -3.0988) (xy 118.5164 -5.4102)
				(xy 119.2784 -5.4102) (xy 119.4562 -5.2324) (xy 119.4562 -4.7498) (xy 118.7577 -4.0513) (xy 118.7577 -0.0508)
				(xy 119.6213 0.8128) (xy 123.1646 0.8128) (xy 123.1646 0.762) (xy 124.0282 -0.1016) (xy 124.1298 0)
				(xy 124.1298 0.9906) (xy 123.6472 1.4732) (xy 123.6472 2.159) (xy 123.7996 2.3114) (xy 124.9172 2.3114)
				(xy 125.0696 2.4638) (xy 125.0696 2.8702) (xy 125.5014 3.302) (xy 126.0856 3.302) (xy 126.5682 2.8194)
				(xy 127.1524 2.8194) (xy 127.4318 2.54) (xy 127.4318 1.6256) (xy 127.3302 1.524) (xy 127.3302 0.7366)
				(xy 127.4318 0.635) (xy 128.1176 0.635) (xy 128.778 1.2954) (xy 128.778 3.0734) (xy 129.032 3.3274)
				(xy 130.5306 3.3274) (xy 130.8227 3.0353) (xy 130.8227 2.4257) (xy 130.7084 2.3114) (xy 130.7084 -1.905)
				(xy 131.1656 -2.3622) (xy 131.1656 -2.9464) (xy 131.2926 -3.0734) (xy 132.0546 -3.0734) (xy 132.1816 -2.9464)
				(xy 132.1816 -0.9398) (xy 131.3942 -0.1524) (xy 131.3942 3.5306) (xy 130.7338 4.191)
			)
		)
		(polygon
			(pts
				(xy 118.9736 -4.572) (xy 118.7704 -4.572) (xy 118.7704 -4.7752) (xy 118.9736 -4.7752)
			)
		)
		(polygon
			(pts
				(xy 111.0488 -1.651) (xy 110.8456 -1.651) (xy 110.8456 -1.8542) (xy 111.0488 -1.8542)
			)
		)
		(polygon
			(pts
				(xy 111.0488 -1.0922) (xy 110.8456 -1.0922) (xy 110.8456 -1.2954) (xy 111.0488 -1.2954)
			)
		)
		(polygon
			(pts
				(xy 109.5756 -0.3302) (xy 109.3724 -0.3302) (xy 109.3724 -0.5334) (xy 109.5756 -0.5334)
			)
		)
		(polygon
			(pts
				(xy 109.0168 -0.3302) (xy 108.8136 -0.3302) (xy 108.8136 -0.5334) (xy 109.0168 -0.5334)
			)
		)
		(polygon
			(pts
				(xy 108.5342 -0.3302) (xy 108.331 -0.3302) (xy 108.331 -0.5334) (xy 108.5342 -0.5334)
			)
		)
		(polygon
			(pts
				(xy 107.9754 -0.3302) (xy 107.7722 -0.3302) (xy 107.7722 -0.5334) (xy 107.9754 -0.5334)
			)
		)
		(polygon
			(pts
				(xy 106.9594 -0.3048) (xy 106.7562 -0.3048) (xy 106.7562 -0.508) (xy 106.9594 -0.508)
			)
		)
		(polygon
			(pts
				(xy 106.4006 -0.3048) (xy 106.1974 -0.3048) (xy 106.1974 -0.508) (xy 106.4006 -0.508)
			)
		)
		(polygon
			(pts
				(xy 114.9858 1.1176) (xy 114.7826 1.1176) (xy 114.7826 0.9144) (xy 114.9858 0.9144)
			)
		)
		(polygon
			(pts
				(xy 114.427 1.1176) (xy 114.2238 1.1176) (xy 114.2238 0.9144) (xy 114.427 0.9144)
			)
		)
		(polygon
			(pts
				(xy 113.1062 1.2192) (xy 112.903 1.2192) (xy 112.903 1.016) (xy 113.1062 1.016)
			)
		)
		(polygon
			(pts
				(xy 112.5474 1.2192) (xy 112.3442 1.2192) (xy 112.3442 1.016) (xy 112.5474 1.016)
			)
		)
		(polygon
			(pts
				(xy 128.2954 1.2954) (xy 128.0922 1.2954) (xy 128.0922 1.0922) (xy 128.2954 1.0922)
			)
		)
		(polygon
			(pts
				(xy 127.7366 1.2954) (xy 127.5334 1.2954) (xy 127.5334 1.0922) (xy 127.7366 1.0922)
			)
		)
		(polygon
			(pts
				(xy 128.016 1.778) (xy 127.8128 1.778) (xy 127.8128 1.5748) (xy 128.016 1.5748)
			)
		)
		(polygon
			(pts
				(xy 128.016 2.3368) (xy 127.8128 2.3368) (xy 127.8128 2.1336) (xy 128.016 2.1336)
			)
		)
		(polygon
			(pts
				(xy 124.5362 3.0226) (xy 124.333 3.0226) (xy 124.333 2.8194) (xy 124.5362 2.8194)
			)
		)
		(polygon
			(pts
				(xy 112.7252 3.0988) (xy 112.522 3.0988) (xy 112.522 2.8956) (xy 112.7252 2.8956)
			)
		)
		(polygon
			(pts
				(xy 112.1156 3.0988) (xy 111.9124 3.0988) (xy 111.9124 2.8956) (xy 112.1156 2.8956)
			)
		)
		(polygon
			(pts
				(xy 127.127 3.4036) (xy 126.9238 3.4036) (xy 126.9238 3.2004) (xy 127.127 3.2004)
			)
		)
		(polygon
			(pts
				(xy 126.5682 3.4036) (xy 126.365 3.4036) (xy 126.365 3.2004) (xy 126.5682 3.2004)
			)
		)
	)
	(zone
		(layers "F.Cu" "B.Cu" "In1.Cu" "In2.Cu" "In3.Cu" "In4.Cu")
		(name "Package Keepin")
		(hatch none 0.5)
		(connect_pads
			(clearance 0)
		)
		(min_thickness 0.25)
		(keepout
			(tracks allowed)
			(vias allowed)
			(pads allowed)
			(copperpour allowed)
			(footprints allowed)
		)
		(placement
			(enabled no)
			(sheetname "")
		)
		(fill
			(thermal_gap 0.5)
			(thermal_bridge_width 0.5)
			(island_removal_mode 0)
		)
		(polygon
			(pts
				(arc
					(start 144.232122 -7.590028)
					(mid 140.5001 -11.32205)
					(end 136.768078 -7.590028)
				)
				(xy 136.768078 -2.032)
				(arc
					(start 133.39953 -2.032)
					(mid 131.821668 -1.378218)
					(end 131.167886 0.199644)
				)
				(xy 131.167886 12.49807) (xy 109.982 12.49807)
				(arc
					(start 109.982 6.72973)
					(mid 109.328292 5.151794)
					(end 107.750356 4.498086)
				)
				(arc
					(start 99.1997 4.498086)
					(mid 97.621764 5.151794)
					(end 96.968056 6.72973)
				)
				(xy 96.968056 12.49807) (xy 45.61205 12.49807)
				(arc
					(start 45.61205 9.329928)
					(mid 42.380154 6.098032)
					(end 39.148004 9.329928)
				)
				(xy 39.148004 12.49807) (xy 16.581882 12.49807)
				(arc
					(start 16.581882 0.199644)
					(mid 15.928174 -1.378292)
					(end 14.350238 -2.032)
				)
				(xy 10.732008 -2.032)
				(arc
					(start 10.732008 -7.590028)
					(mid 6.999986 -11.32205)
					(end 3.267964 -7.590028)
				)
				(xy 3.267964 -2.032) (xy 2.032 -2.032) (xy 2.032 -31.358332) (xy 3.84175 -33.168082) (xy 143.658336 -33.168082)
				(xy 145.468086 -31.358332) (xy 145.468086 -2.032) (xy 144.232122 -2.032)
			)
		)
	)
	(zone
		(layers "F.Cu" "B.Cu" "In1.Cu" "In2.Cu" "In3.Cu" "In4.Cu")
		(name "Route Keepin")
		(hatch none 0.5)
		(connect_pads
			(clearance 0)
		)
		(min_thickness 0.25)
		(keepout
			(tracks allowed)
			(vias allowed)
			(pads allowed)
			(copperpour allowed)
			(footprints allowed)
		)
		(placement
			(enabled no)
			(sheetname "")
		)
		(fill
			(thermal_gap 0.5)
			(thermal_bridge_width 0.5)
			(island_removal_mode 0)
		)
		(polygon
			(pts
				(arc
					(start 142.962122 -7.590028)
					(mid 140.5001 -10.05205)
					(end 138.038078 -7.590028)
				)
				(arc
					(start 138.038078 -1.414272)
					(mid 138.020044 -1.32314)
					(end 137.968482 -1.24587)
				)
				(arc
					(start 137.554208 -0.831596)
					(mid 137.476929 -0.780053)
					(end 137.385806 -0.762)
				)
				(arc
					(start 133.399784 -0.762)
					(mid 132.719784 -0.480282)
					(end 132.437886 0.199644)
				)
				(xy 132.437886 13.714476) (xy 132.384292 13.76807) (xy 108.765848 13.76807) (xy 108.712 13.714222)
				(arc
					(start 108.712 6.729984)
					(mid 108.430267 6.049819)
					(end 107.750102 5.768086)
				)
				(arc
					(start 99.199954 5.768086)
					(mid 98.519789 6.049819)
					(end 98.238056 6.729984)
				)
				(xy 98.238056 13.714222) (xy 98.184208 13.76807) (xy 44.395644 13.76807) (xy 44.34205 13.714476)
				(arc
					(start 44.34205 9.329928)
					(mid 42.380154 7.368032)
					(end 40.418004 9.329928)
				)
				(xy 40.418004 13.714222) (xy 40.364156 13.76807) (xy 15.36573 13.76807) (xy 15.311882 13.714222)
				(arc
					(start 15.311882 0.199898)
					(mid 15.030149 -0.480267)
					(end 14.349984 -0.762)
				)
				(arc
					(start 10.11428 -0.762)
					(mid 10.023148 -0.780034)
					(end 9.945878 -0.831596)
				)
				(arc
					(start 9.531604 -1.24587)
					(mid 9.480061 -1.323149)
					(end 9.462008 -1.414272)
				)
				(arc
					(start 9.462008 -7.590028)
					(mid 6.999986 -10.05205)
					(end 4.537964 -7.590028)
				)
				(arc
					(start 4.537964 -1.414272)
					(mid 4.51993 -1.32314)
					(end 4.468368 -1.24587)
				)
				(arc
					(start 4.054094 -0.831596)
					(mid 3.976815 -0.780053)
					(end 3.885692 -0.762)
				)
				(arc
					(start 0.999998 -0.762)
					(mid 0.831708 -0.831708)
					(end 0.762 -0.999998)
				)
				(arc
					(start 0.762 -31.785814)
					(mid 0.780034 -31.876946)
					(end 0.831596 -31.954216)
				)
				(arc
					(start 3.245866 -34.368486)
					(mid 3.323145 -34.420029)
					(end 3.414268 -34.438082)
				)
				(arc
					(start 144.085818 -34.438082)
					(mid 144.17695 -34.420048)
					(end 144.25422 -34.368486)
				)
				(arc
					(start 146.66849 -31.954216)
					(mid 146.720033 -31.876937)
					(end 146.738086 -31.785814)
				)
				(arc
					(start 146.738086 -0.999998)
					(mid 146.668378 -0.831708)
					(end 146.500088 -0.762)
				)
				(arc
					(start 143.61414 -0.762)
					(mid 143.523008 -0.780034)
					(end 143.445738 -0.831596)
				)
				(arc
					(start 143.031972 -1.24587)
					(mid 142.980341 -1.323002)
					(end 142.962122 -1.414018)
				)
			)
		)
	)
	(zone
		(net "P12V")
		(layer "B.Cu")
		(hatch none 0.5)
		(connect_pads
			(clearance 0.5)
		)
		(min_thickness 0.25)
		(fill yes
			(thermal_gap 0.5)
			(thermal_bridge_width 0.5)
			(island_removal_mode 0)
		)
		(polygon
			(pts
				(xy 16.8402 -24.5491) (xy 15.8623 -25.527) (xy 15.8623 -25.7048) (xy 16.8656 -26.7081) (xy 16.8656 -27.4701)
				(xy 18.3007 -28.9052) (xy 18.3896 -28.9052) (xy 19.3802 -27.9146) (xy 19.3802 -27.178) (xy 19.7866 -26.7716)
				(xy 19.7866 -26.1874) (xy 18.1483 -24.5491)
			)
		)
	)
	(zone
		(layer "B.Cu")
		(hatch none 0.5)
		(connect_pads
			(clearance 0)
		)
		(min_thickness 0.25)
		(keepout
			(tracks allowed)
			(vias allowed)
			(pads allowed)
			(copperpour allowed)
			(footprints not_allowed)
		)
		(placement
			(enabled no)
			(sheetname "")
		)
		(fill
			(thermal_gap 0.5)
			(thermal_bridge_width 0.5)
			(island_removal_mode 0)
		)
		(polygon
			(pts
				(xy 14.549882 6.530086)
				(arc
					(start 99.199954 6.530086)
					(mid 99.058605 6.588635)
					(end 99.000056 6.729984)
				)
				(xy 99.000056 13.750544) (xy 43.58005 13.750544)
				(arc
					(start 43.58005 9.329928)
					(mid 42.380154 8.130032)
					(end 41.180004 9.329928)
				)
				(xy 41.180004 13.750544) (xy 14.549882 13.750544)
			)
		)
	)
	(zone
		(net "GND")
		(layer "B.Cu")
		(hatch none 0.5)
		(connect_pads
			(clearance 0.5)
		)
		(min_thickness 0.25)
		(fill yes
			(thermal_gap 0.5)
			(thermal_bridge_width 0.5)
			(island_removal_mode 0)
		)
		(polygon
			(pts
				(xy 27.0256 3.7338) (xy 26.924 3.6322) (xy 26.924 2.4384) (xy 27.0129 2.3495) (xy 31.0515 2.3495)
				(xy 31.1658 2.4638) (xy 31.1658 3.5814) (xy 31.0134 3.7338)
			)
		)
	)
	(zone
		(net "P3V3_VR")
		(layer "B.Cu")
		(hatch none 0.5)
		(connect_pads
			(clearance 0.5)
		)
		(min_thickness 0.25)
		(fill yes
			(thermal_gap 0.5)
			(thermal_bridge_width 0.5)
			(island_removal_mode 0)
		)
		(polygon
			(pts
				(xy 20.6121 3.302) (xy 20.2565 2.9464) (xy 20.2565 -0.2413) (xy 20.9169 -0.9017) (xy 24.9174 -0.9017)
				(xy 25.9715 -1.9558) (xy 31.0388 -1.9558) (xy 31.115 -1.8796) (xy 31.115 1.9431) (xy 31.0642 1.9939)
				(xy 26.2255 1.9939) (xy 26.1493 2.0701) (xy 26.0985 2.0701) (xy 24.8666 3.302)
			)
		)
	)
	(zone
		(layer "B.Cu")
		(hatch none 0.5)
		(connect_pads
			(clearance 0)
		)
		(min_thickness 0.25)
		(keepout
			(tracks allowed)
			(vias allowed)
			(pads allowed)
			(copperpour allowed)
			(footprints allowed)
		)
		(placement
			(enabled no)
			(sheetname "")
		)
		(fill
			(thermal_gap 0.5)
			(thermal_bridge_width 0.5)
			(island_removal_mode 0)
		)
		(polygon
			(pts
				(xy 19.7358 -21.844) (xy 24.1554 -21.844) (xy 24.3332 -22.0218) (xy 24.3332 -25.6286) (xy 24.0284 -25.9334)
				(xy 23.5712 -25.9334) (xy 23.2918 -25.654) (xy 23.2918 -23.0632) (xy 23.1648 -22.9362) (xy 21.2852 -22.9362)
				(xy 21.1328 -23.0886) (xy 21.1328 -24.8412) (xy 21.1328 -26.4414) (xy 19.7104 -27.8638) (xy 12.8778 -27.8638)
				(xy 12.446 -27.432) (xy 12.446 -23.9776) (xy 14.5542 -21.8694) (xy 19.7104 -21.8694)
			)
		)
	)
	(zone
		(layer "B.Cu")
		(hatch none 0.5)
		(connect_pads
			(clearance 0)
		)
		(min_thickness 0.25)
		(keepout
			(tracks allowed)
			(vias allowed)
			(pads allowed)
			(copperpour allowed)
			(footprints not_allowed)
		)
		(placement
			(enabled no)
			(sheetname "")
		)
		(fill
			(thermal_gap 0.5)
			(thermal_bridge_width 0.5)
			(island_removal_mode 0)
		)
		(polygon
			(pts
				(xy 122.700034 -13.08989) (xy 122.700034 4.029964) (xy 133.199886 4.029964)
				(arc
					(start 133.199886 0.199898)
					(mid 133.258599 0.058533)
					(end 133.400038 0)
				)
				(xy 135.999982 0) (xy 135.999982 -13.08989)
			)
		)
	)
	(zone
		(net "P3V3_USB_HUB")
		(layer "B.Cu")
		(hatch none 0.5)
		(connect_pads
			(clearance 0.5)
		)
		(min_thickness 0.25)
		(fill yes
			(thermal_gap 0.5)
			(thermal_bridge_width 0.5)
			(island_removal_mode 0)
		)
		(polygon
			(pts
				(xy 127.7366 -26.3906) (xy 127.4699 -26.6573) (xy 127.4699 -29.6799) (xy 126.2634 -30.8864) (xy 121.5898 -30.8864)
				(xy 121.412 -30.7086) (xy 121.412 -29.7688) (xy 121.3866 -29.7434) (xy 120.8786 -29.7434) (xy 120.65 -29.972)
				(xy 120.65 -31.5214) (xy 121.5898 -32.4612) (xy 129.032 -32.4612) (xy 129.4892 -32.004) (xy 129.4892 -31.3817)
				(xy 129.19075 -31.08325) (xy 129.19075 -30.33395) (xy 129.54 -29.9847) (xy 129.54 -27.4066) (xy 128.524 -26.3906)
			)
		)
		(polygon
			(pts
				(xy 123.952 -31.8008) (xy 123.7488 -31.8008) (xy 123.7488 -32.004) (xy 123.952 -32.004)
			)
		)
		(polygon
			(pts
				(xy 123.0884 -31.8008) (xy 122.8852 -31.8008) (xy 122.8852 -32.004) (xy 123.0884 -32.004)
			)
		)
		(polygon
			(pts
				(xy 125.603 -31.3182) (xy 125.3998 -31.3182) (xy 125.3998 -31.5214) (xy 125.603 -31.5214)
			)
		)
		(polygon
			(pts
				(xy 124.9934 -31.3182) (xy 124.7902 -31.3182) (xy 124.7902 -31.5214) (xy 124.9934 -31.5214)
			)
		)
		(polygon
			(pts
				(xy 128.7272 -29.7942) (xy 128.524 -29.7942) (xy 128.524 -29.9974) (xy 128.7272 -29.9974)
			)
		)
		(polygon
			(pts
				(xy 128.143 -29.3116) (xy 127.9398 -29.3116) (xy 127.9398 -29.5148) (xy 128.143 -29.5148)
			)
		)
		(polygon
			(pts
				(xy 128.7272 -28.9306) (xy 128.524 -28.9306) (xy 128.524 -29.1338) (xy 128.7272 -29.1338)
			)
		)
		(polygon
			(pts
				(xy 128.143 -28.702) (xy 127.9398 -28.702) (xy 127.9398 -28.9052) (xy 128.143 -28.9052)
			)
		)
		(polygon
			(pts
				(xy 128.2192 -27.6098) (xy 128.016 -27.6098) (xy 128.016 -27.813) (xy 128.2192 -27.813)
			)
		)
		(polygon
			(pts
				(xy 128.2192 -27.0002) (xy 128.016 -27.0002) (xy 128.016 -27.2034) (xy 128.2192 -27.2034)
			)
		)
	)
	(zone
		(net "P3V3")
		(layer "B.Cu")
		(hatch none 0.5)
		(connect_pads
			(clearance 0.5)
		)
		(min_thickness 0.25)
		(fill yes
			(thermal_gap 0.5)
			(thermal_bridge_width 0.5)
			(island_removal_mode 0)
		)
		(polygon
			(pts
				(xy 34.671 -0.5461) (xy 34.4043 -0.8128) (xy 34.4043 -2.4638) (xy 35.1663 -3.2258) (xy 38.1254 -3.2258)
				(xy 38.5826 -2.7686) (xy 38.5826 -1.2827) (xy 38.5064 -1.2065) (xy 36.4109 -1.2065) (xy 35.7505 -0.5461)
			)
		)
		(polygon
			(pts
				(xy 38.1762 -1.7145) (xy 37.973 -1.7145) (xy 37.973 -1.9177) (xy 38.1762 -1.9177)
			)
		)
		(polygon
			(pts
				(xy 35.1536 -1.2954) (xy 34.9504 -1.2954) (xy 34.9504 -1.4986) (xy 35.1536 -1.4986)
			)
		)
		(polygon
			(pts
				(xy 35.1536 -0.6858) (xy 34.9504 -0.6858) (xy 34.9504 -0.889) (xy 35.1536 -0.889)
			)
		)
	)
	(zone
		(net "P3V3_MB")
		(layer "B.Cu")
		(hatch none 0.5)
		(connect_pads
			(clearance 0.5)
		)
		(min_thickness 0.25)
		(fill yes
			(thermal_gap 0.5)
			(thermal_bridge_width 0.5)
			(island_removal_mode 0)
		)
		(polygon
			(pts
				(xy 23.3172 13.5382) (xy 23.3172 9.8552) (xy 22.9616 9.4996) (xy 22.9616 8.9535) (xy 22.8346 8.8265)
				(xy 22.8346 7.4168) (xy 23.5458 6.7056) (xy 25.9207 6.7056) (xy 26.0731 6.858) (xy 26.0731 8.0772)
				(xy 24.70785 9.44245) (xy 24.70785 9.81075) (xy 24.6634 9.8552) (xy 24.6634 13.5128) (xy 24.638 13.5382)
				(xy 24.13 13.5382) (xy 24.1046 13.5128) (xy 24.1046 10.7442) (xy 24.0792 10.7188) (xy 23.876 10.7188)
				(xy 23.8506 10.7442) (xy 23.8506 13.5128) (xy 23.8252 13.5382)
			)
		)
	)
	(zone
		(layer "B.Cu")
		(hatch none 0.5)
		(connect_pads
			(clearance 0)
		)
		(min_thickness 0.25)
		(keepout
			(tracks allowed)
			(vias allowed)
			(pads allowed)
			(copperpour allowed)
			(footprints not_allowed)
		)
		(placement
			(enabled no)
			(sheetname "")
		)
		(fill
			(thermal_gap 0.5)
			(thermal_bridge_width 0.5)
			(island_removal_mode 0)
		)
		(polygon
			(pts
				(arc
					(start 135.50011 -25.584912)
					(mid 140.5001 -30.584902)
					(end 145.50009 -25.584912)
				)
				(xy 145.50009 -13.08989) (xy 147.500086 -13.08989)
				(arc
					(start 147.500086 -0.999998)
					(mid 147.207193 -0.292893)
					(end 146.500088 0)
				)
				(arc
					(start 143.61414 0)
					(mid 143.231457 -0.07612)
					(end 142.907004 -0.292862)
				)
				(arc
					(start 142.492984 -0.707136)
					(mid 142.276202 -1.031573)
					(end 142.200122 -1.414272)
				)
				(arc
					(start 142.200122 -7.590028)
					(mid 140.5001 -9.29005)
					(end 138.800078 -7.590028)
				)
				(arc
					(start 138.800078 -1.414272)
					(mid 138.723958 -1.031589)
					(end 138.507216 -0.707136)
				)
				(arc
					(start 138.092942 -0.292862)
					(mid 137.768505 -0.07608)
					(end 137.385806 0)
				)
				(xy 135.999982 0) (xy 135.999982 -13.08989) (xy 135.50011 -13.08989)
			)
		)
	)
	(zone
		(net "GND")
		(layer "B.Cu")
		(hatch none 0.5)
		(connect_pads
			(clearance 0.5)
		)
		(min_thickness 0.25)
		(fill yes
			(thermal_gap 0.5)
			(thermal_bridge_width 0.5)
			(island_removal_mode 0)
		)
		(polygon
			(pts
				(xy 25.1714 -7.9756) (xy 24.6634 -8.4836) (xy 23.114 -8.4836) (xy 23.114 -14.224) (xy 23.3934 -14.5034)
				(xy 24.9174 -14.5034) (xy 25.1841 -14.2367) (xy 25.1841 -12.9159) (xy 26.2128 -11.8872) (xy 26.2128 -8.1534)
				(xy 26.035 -7.9756)
			)
		)
		(polygon
			(pts
				(xy 25.273 -8.7122) (xy 25.0698 -8.7122) (xy 25.0698 -8.9154) (xy 25.273 -8.9154)
			)
		)
	)
	(zone
		(net "P12V_SLOT2")
		(layer "B.Cu")
		(hatch none 0.5)
		(connect_pads
			(clearance 0.5)
		)
		(min_thickness 0.25)
		(fill yes
			(thermal_gap 0.5)
			(thermal_bridge_width 0.5)
			(island_removal_mode 0)
		)
		(polygon
			(pts
				(xy 12.8778 -16.637) (xy 12.573 -16.9418) (xy 12.573 -19.7612) (xy 12.9794 -20.1676) (xy 13.7668 -20.1676)
				(xy 14.2748 -19.6596) (xy 14.2748 -16.9418) (xy 13.97 -16.637)
			)
		)
	)
	(zone
		(layer "B.Cu")
		(hatch none 0.5)
		(connect_pads
			(clearance 0)
		)
		(min_thickness 0.25)
		(keepout
			(tracks allowed)
			(vias allowed)
			(pads allowed)
			(copperpour allowed)
			(footprints allowed)
		)
		(placement
			(enabled no)
			(sheetname "")
		)
		(fill
			(thermal_gap 0.5)
			(thermal_bridge_width 0.5)
			(island_removal_mode 0)
		)
		(polygon
			(pts
				(xy 22.7076 -28.3464) (xy 24.6888 -28.3464) (xy 25.0444 -28.702) (xy 25.0444 -29.591) (xy 24.4856 -30.1498)
				(xy 22.2504 -30.1498) (xy 21.971 -29.8704) (xy 21.971 -29.083)
			)
		)
	)
	(zone
		(layer "B.Cu")
		(hatch none 0.5)
		(connect_pads
			(clearance 0)
		)
		(min_thickness 0.25)
		(keepout
			(tracks allowed)
			(vias allowed)
			(pads allowed)
			(copperpour allowed)
			(footprints not_allowed)
		)
		(placement
			(enabled no)
			(sheetname "")
		)
		(fill
			(thermal_gap 0.5)
			(thermal_bridge_width 0.5)
			(island_removal_mode 0)
		)
		(polygon
			(pts
				(arc
					(start 1.999996 -25.584912)
					(mid 6.999986 -30.584902)
					(end 11.999976 -25.584912)
				)
				(xy 11.999976 -13.08989) (xy 1.999996 -13.08989)
			)
		)
	)
	(zone
		(net "P3V3_STBY")
		(layer "B.Cu")
		(hatch none 0.5)
		(connect_pads
			(clearance 0.5)
		)
		(min_thickness 0.25)
		(fill yes
			(thermal_gap 0.5)
			(thermal_bridge_width 0.5)
			(island_removal_mode 0)
		)
		(polygon
			(pts
				(xy 132.6642 -4.3942) (xy 132.3086 -4.7498) (xy 132.3086 -8.382) (xy 130.4798 -10.2108) (xy 130.4798 -10.6426)
				(xy 131.445 -11.6078) (xy 131.445 -23.1902) (xy 132.6388 -24.384) (xy 132.6388 -25.8064) (xy 130.8608 -27.5844)
				(xy 130.0988 -27.5844) (xy 129.9718 -27.7114) (xy 129.9718 -28.5496) (xy 130.0988 -28.6766) (xy 131.5974 -28.6766)
				(xy 133.6802 -26.5938) (xy 133.6802 -24.003) (xy 132.5626 -22.8854) (xy 132.5626 -19.7104) (xy 133.2484 -19.0246)
				(xy 133.2484 -18.5674) (xy 132.6896 -18.0086) (xy 132.6896 -14.8082) (xy 134.4422 -13.0556) (xy 134.4422 -4.826)
				(xy 134.0104 -4.3942)
			)
		)
		(polygon
			(pts
				(xy 131.1656 -10.6172) (xy 130.9624 -10.6172) (xy 130.9624 -10.8204) (xy 131.1656 -10.8204)
			)
		)
		(polygon
			(pts
				(xy 131.1656 -10.0584) (xy 130.9624 -10.0584) (xy 130.9624 -10.2616) (xy 131.1656 -10.2616)
			)
		)
		(polygon
			(pts
				(xy 133.0706 -7.9756) (xy 132.8674 -7.9756) (xy 132.8674 -8.1788) (xy 133.0706 -8.1788)
			)
		)
	)
	(zone
		(net "GND")
		(layer "B.Cu")
		(hatch none 0.5)
		(connect_pads
			(clearance 0.5)
		)
		(min_thickness 0.25)
		(fill yes
			(thermal_gap 0.5)
			(thermal_bridge_width 0.5)
			(island_removal_mode 0)
		)
		(polygon
			(pts
				(xy 32.0929 1.4605) (xy 31.8516 1.2192) (xy 31.8516 -1.651) (xy 31.1277 -2.3749) (xy 27.3431 -2.3749)
				(xy 27.1653 -2.5527) (xy 27.1653 -5.0292) (xy 27.3558 -5.2197) (xy 31.4833 -5.2197) (xy 32.2707 -4.4323)
				(xy 32.2707 -1.9939) (xy 32.7279 -1.5367) (xy 34.0106 -1.5367) (xy 34.1757 -1.3716) (xy 34.1757 -0.889)
				(xy 34.0614 -0.7747) (xy 33.2105 -0.7747) (xy 32.69615 -0.26035) (xy 32.69615 1.36525) (xy 32.6009 1.4605)
			)
		)
		(polygon
			(pts
				(xy 32.6009 -0.8001) (xy 32.3977 -0.8001) (xy 32.3977 -1.0033) (xy 32.6009 -1.0033)
			)
		)
		(polygon
			(pts
				(xy 32.1818 0.9525) (xy 31.9786 0.9525) (xy 31.9786 0.7493) (xy 32.1818 0.7493)
			)
		)
	)
	(zone
		(layer "B.Cu")
		(hatch none 0.5)
		(connect_pads
			(clearance 0)
		)
		(min_thickness 0.25)
		(keepout
			(tracks allowed)
			(vias allowed)
			(pads allowed)
			(copperpour allowed)
			(footprints allowed)
		)
		(placement
			(enabled no)
			(sheetname "")
		)
		(fill
			(thermal_gap 0.5)
			(thermal_bridge_width 0.5)
			(island_removal_mode 0)
		)
		(polygon
			(pts
				(xy 13.209016 8.631682) (xy 13.209016 15.57528) (xy 134.500366 15.57528) (xy 134.500366 8.631682)
				(xy 134.500366 8.567166) (xy 134.500366 8.509) (xy 76.2254 8.509) (xy 76.1746 8.4582) (xy 75.311 8.4582)
				(xy 13.2588 8.4582) (xy 13.209016 8.507984)
			)
		)
	)
	(zone
		(layer "B.Cu")
		(hatch none 0.5)
		(connect_pads
			(clearance 0)
		)
		(min_thickness 0.25)
		(keepout
			(tracks allowed)
			(vias allowed)
			(pads allowed)
			(copperpour allowed)
			(footprints not_allowed)
		)
		(placement
			(enabled no)
			(sheetname "")
		)
		(fill
			(thermal_gap 0.5)
			(thermal_bridge_width 0.5)
			(island_removal_mode 0)
		)
		(polygon
			(pts
				(xy 133.199886 13.750544) (xy 107.95 13.750544)
				(arc
					(start 107.95 6.729984)
					(mid 107.891451 6.588635)
					(end 107.750102 6.530086)
				)
				(xy 133.199886 6.530086)
			)
		)
	)
	(zone
		(net "GND")
		(layer "B.Cu")
		(hatch none 0.5)
		(connect_pads
			(clearance 0.5)
		)
		(min_thickness 0.25)
		(fill yes
			(thermal_gap 0.5)
			(thermal_bridge_width 0.5)
			(island_removal_mode 0)
		)
		(polygon
			(pts
				(xy 1.0414 -13.1064) (xy 0.7874 -13.3604) (xy 0.7874 -31.8008) (xy 3.4036 -34.417) (xy 26.543 -34.417)
				(xy 26.7462 -34.2138) (xy 26.7462 -32.5628) (xy 26.5176 -32.3342) (xy 12.5984 -32.3342) (xy 12.0142 -31.75)
				(xy 12.0142 -13.1318) (xy 11.9888 -13.1064)
			)
		)
		(polygon
			(pts
				(xy 26.4414 -33.4264) (xy 26.2382 -33.4264) (xy 26.2382 -33.6296) (xy 26.4414 -33.6296)
			)
		)
		(polygon
			(pts
				(xy 26.4414 -32.8676) (xy 26.2382 -32.8676) (xy 26.2382 -33.0708) (xy 26.4414 -33.0708)
			)
		)
	)
	(zone
		(layer "B.Cu")
		(hatch none 0.5)
		(connect_pads
			(clearance 0)
		)
		(min_thickness 0.25)
		(keepout
			(tracks allowed)
			(vias allowed)
			(pads allowed)
			(copperpour allowed)
			(footprints allowed)
		)
		(placement
			(enabled no)
			(sheetname "")
		)
		(fill
			(thermal_gap 0.5)
			(thermal_bridge_width 0.5)
			(island_removal_mode 0)
		)
		(polygon
			(pts
				(xy 51.0794 -18.6309) (xy 52.8828 -18.6309) (xy 53.1495 -18.8976) (xy 53.1495 -20.193) (xy 52.705 -20.6375)
				(xy 51.054 -20.6375) (xy 50.8381 -20.4216) (xy 50.8381 -18.8722)
			)
		)
	)
	(zone
		(net "P3V3_SW")
		(layer "B.Cu")
		(hatch none 0.5)
		(connect_pads
			(clearance 0.5)
		)
		(min_thickness 0.25)
		(fill yes
			(thermal_gap 0.5)
			(thermal_bridge_width 0.5)
			(island_removal_mode 0)
		)
		(polygon
			(pts
				(xy 18.034 -2.3876) (xy 16.7894 -3.6322) (xy 16.7894 -4.8006) (xy 16.9418 -4.953) (xy 17.5006 -4.953)
				(xy 18.1356 -5.588) (xy 21.4376 -5.588) (xy 22.4536 -6.604) (xy 22.4536 -9.4996) (xy 22.5298 -9.5758)
				(xy 22.7838 -9.5758) (xy 22.86 -9.4996) (xy 22.86 -7.6962) (xy 22.8727 -7.6835) (xy 23.2918 -7.6835)
				(xy 25.48255 -5.49275) (xy 25.48255 -2.95275) (xy 24.9174 -2.3876)
			)
		)
		(polygon
			(pts
				(xy 18.923 -5.1816) (xy 18.7198 -5.1816) (xy 18.7198 -5.3848) (xy 18.923 -5.3848)
			)
		)
		(polygon
			(pts
				(xy 18.923 -4.318) (xy 18.7198 -4.318) (xy 18.7198 -4.5212) (xy 18.923 -4.5212)
			)
		)
		(polygon
			(pts
				(xy 18.0594 -4.318) (xy 17.8562 -4.318) (xy 17.8562 -4.5212) (xy 18.0594 -4.5212)
			)
		)
	)
	(zone
		(net "P12V")
		(layer "B.Cu")
		(hatch none 0.5)
		(connect_pads
			(clearance 0.5)
		)
		(min_thickness 0.25)
		(fill yes
			(thermal_gap 0.5)
			(thermal_bridge_width 0.5)
			(island_removal_mode 0)
		)
		(polygon
			(pts
				(xy 15.3416 13.5382) (xy 15.3162 13.5128) (xy 15.3162 10.6934) (xy 15.367 10.6426) (xy 15.367 -0.3302)
				(xy 11.5824 -4.1148) (xy 11.5824 -11.811) (xy 12.9032 -13.1318) (xy 12.9032 -15.1384) (xy 14.5034 -16.7386)
				(xy 14.5034 -19.9898) (xy 13.9065 -20.5867) (xy 12.6111 -20.5867) (xy 12.5476 -20.6502) (xy 12.5476 -22.8473)
				(xy 12.6365 -22.9362) (xy 19.7358 -22.9362) (xy 19.7866 -22.8854) (xy 19.7866 -22.2504) (xy 19.4056 -21.8694)
				(xy 18.9738 -21.8694) (xy 18.4404 -21.336) (xy 18.4404 -16.6878) (xy 16.129 -14.3764) (xy 16.129 -12.8016)
				(xy 15.9766 -12.6492) (xy 15.367 -12.6492) (xy 15.19555 -12.47775) (xy 14.34465 -12.47775) (xy 13.462 -11.5951)
				(xy 13.462 -5.6388) (xy 18.161 -0.9398) (xy 18.161 4.1656) (xy 19.8374 5.842) (xy 19.8374 10.7061)
				(xy 19.8628 10.7315) (xy 19.8628 13.5255) (xy 19.3167 13.5255) (xy 19.304 13.5128) (xy 19.304 10.7188)
				(xy 19.2532 10.668) (xy 19.1008 10.668) (xy 19.0627 10.7061) (xy 19.0627 13.5001) (xy 19.0373 13.5255)
				(xy 18.5039 13.5255) (xy 18.4912 13.5128) (xy 18.4912 10.7188) (xy 18.4658 10.6934) (xy 18.288 10.6934)
				(xy 18.2626 10.7188) (xy 18.2626 13.5128) (xy 18.2499 13.5255) (xy 17.7038 13.5255) (xy 17.7038 10.7188)
				(xy 17.6784 10.6934) (xy 17.4879 10.6934) (xy 17.4625 10.7188) (xy 17.4625 13.4747) (xy 17.4244 13.5128)
				(xy 16.9164 13.5128) (xy 16.891 13.4874) (xy 16.891 10.7188) (xy 16.8656 10.6934) (xy 16.6878 10.6934)
				(xy 16.6624 10.7188) (xy 16.6624 13.462) (xy 16.6116 13.5128) (xy 16.129 13.5128) (xy 16.1036 13.4874)
				(xy 16.1036 10.7315) (xy 16.0655 10.6934) (xy 15.9004 10.6934) (xy 15.8496 10.7442) (xy 15.8496 13.5128)
				(xy 15.8242 13.5382)
			)
		)
		(polygon
			(pts
				(xy 17.9578 -21.209) (xy 17.7546 -21.209) (xy 17.7546 -21.4122) (xy 17.9578 -21.4122)
			)
		)
		(polygon
			(pts
				(xy 17.9578 -20.5994) (xy 17.7546 -20.5994) (xy 17.7546 -20.8026) (xy 17.9578 -20.8026)
			)
		)
		(polygon
			(pts
				(xy 18.1102 -19.5834) (xy 17.907 -19.5834) (xy 17.907 -19.7866) (xy 18.1102 -19.7866)
			)
		)
		(polygon
			(pts
				(xy 18.1102 -18.9738) (xy 17.907 -18.9738) (xy 17.907 -19.177) (xy 18.1102 -19.177)
			)
		)
		(polygon
			(pts
				(xy 15.5829 -13.6144) (xy 15.3797 -13.6144) (xy 15.3797 -13.8176) (xy 15.5829 -13.8176)
			)
		)
	)
	(zone
		(layer "B.Cu")
		(hatch none 0.5)
		(connect_pads
			(clearance 0)
		)
		(min_thickness 0.25)
		(keepout
			(tracks allowed)
			(vias allowed)
			(pads allowed)
			(copperpour allowed)
			(footprints not_allowed)
		)
		(placement
			(enabled no)
			(sheetname "")
		)
		(fill
			(thermal_gap 0.5)
			(thermal_bridge_width 0.5)
			(island_removal_mode 0)
		)
		(polygon
			(pts
				(arc
					(start 14.349984 0)
					(mid 14.491333 0.058549)
					(end 14.549882 0.199898)
				)
				(xy 14.549882 4.029964) (xy 26.900124 4.029964) (xy 26.900124 -26.699972)
				(arc
					(start 11.869928 -26.699972)
					(mid 11.967325 -26.137397)
					(end 11.999976 -25.567386)
				)
				(xy 11.999976 -13.08989) (xy 11.500104 -13.08989) (xy 11.500104 0)
			)
		)
	)
	(zone
		(net "P3V3_STBY")
		(layer "B.Cu")
		(hatch none 0.5)
		(connect_pads
			(clearance 0.5)
		)
		(min_thickness 0.25)
		(fill yes
			(thermal_gap 0.5)
			(thermal_bridge_width 0.5)
			(island_removal_mode 0)
		)
		(polygon
			(pts
				(xy 32.5628 5.969) (xy 32.3596 5.7658) (xy 32.3596 2.3368) (xy 32.9946 1.7018) (xy 32.9946 0.8509)
				(xy 33.0708 0.7747) (xy 33.6677 0.7747) (xy 33.8836 0.9906) (xy 33.8836 5.6134) (xy 33.528 5.969)
			)
		)
		(polygon
			(pts
				(xy 33.7058 1.5621) (xy 33.5026 1.5621) (xy 33.5026 1.3589) (xy 33.7058 1.3589)
			)
		)
		(polygon
			(pts
				(xy 33.3756 5.2832) (xy 33.1724 5.2832) (xy 33.1724 5.08) (xy 33.3756 5.08)
			)
		)
		(polygon
			(pts
				(xy 33.3756 5.842) (xy 33.1724 5.842) (xy 33.1724 5.6388) (xy 33.3756 5.6388)
			)
		)
	)
	(zone
		(layer "B.Cu")
		(hatch none 0.5)
		(connect_pads
			(clearance 0)
		)
		(min_thickness 0.25)
		(keepout
			(tracks allowed)
			(vias allowed)
			(pads allowed)
			(copperpour allowed)
			(footprints not_allowed)
		)
		(placement
			(enabled no)
			(sheetname "")
		)
		(fill
			(thermal_gap 0.5)
			(thermal_bridge_width 0.5)
			(island_removal_mode 0)
		)
		(polygon
			(pts
				(arc
					(start 135.50011 -25.584912)
					(mid 140.5001 -30.584902)
					(end 145.50009 -25.584912)
				)
				(xy 145.50009 -13.08989) (xy 135.50011 -13.08989)
			)
		)
	)
	(zone
		(layer "B.Cu")
		(hatch none 0.5)
		(connect_pads
			(clearance 0)
		)
		(min_thickness 0.25)
		(keepout
			(tracks allowed)
			(vias allowed)
			(pads allowed)
			(copperpour allowed)
			(footprints not_allowed)
		)
		(placement
			(enabled no)
			(sheetname "")
		)
		(fill
			(thermal_gap 0.5)
			(thermal_bridge_width 0.5)
			(island_removal_mode 0)
		)
		(polygon
			(pts
				(xy 147.500086 -13.08989) (xy 145.50009 -13.08989)
				(arc
					(start 145.50009 -25.584912)
					(mid 141.061156 -30.553578)
					(end 135.62584 -26.699972)
				)
				(arc
					(start 11.873992 -26.699972)
					(mid 6.438912 -30.553261)
					(end 1.999996 -25.584912)
				)
				(xy 1.999996 -13.08989) (xy 0 -13.08989)
				(arc
					(start 0 -31.785814)
					(mid 0.07612 -32.168497)
					(end 0.292862 -32.49295)
				)
				(arc
					(start 2.707132 -34.90722)
					(mid 3.031569 -35.124002)
					(end 3.414268 -35.200082)
				)
				(arc
					(start 144.085818 -35.200082)
					(mid 144.468501 -35.123962)
					(end 144.792954 -34.90722)
				)
				(arc
					(start 147.207224 -32.49295)
					(mid 147.424006 -32.168513)
					(end 147.500086 -31.785814)
				)
			)
		)
	)
	(zone
		(net "P3V3_VIN")
		(layer "B.Cu")
		(hatch none 0.5)
		(connect_pads
			(clearance 0.5)
		)
		(min_thickness 0.25)
		(fill yes
			(thermal_gap 0.5)
			(thermal_bridge_width 0.5)
			(island_removal_mode 0)
		)
		(polygon
			(pts
				(xy 21.021802 -6.026658) (xy 20.931124 -6.117336) (xy 20.931124 -6.831076) (xy 20.7518 -7.0104)
				(xy 20.2438 -7.0104) (xy 20.1422 -7.112) (xy 20.1422 -7.4803) (xy 20.3073 -7.6454) (xy 21.717 -7.6454)
				(xy 21.846032 -7.774432) (xy 21.846032 -11.811) (xy 21.845016 -11.812016) (xy 21.845016 -12.165584)
				(xy 21.7424 -12.2682) (xy 20.066 -12.2682) (xy 19.7612 -12.573) (xy 19.7612 -14.6939) (xy 20.0533 -14.986)
				(xy 22.225 -14.986) (xy 22.7838 -14.4272) (xy 22.7838 -10.141966) (xy 22.7076 -10.065766) (xy 22.345396 -10.065766)
				(xy 22.232874 -9.953244) (xy 22.232874 -6.688074) (xy 21.571458 -6.026658)
			)
		)
		(polygon
			(pts
				(xy 21.632418 -6.523228) (xy 21.429218 -6.523228) (xy 21.429218 -6.726428) (xy 21.632418 -6.726428)
			)
		)
	)
	(zone
		(layer "B.Cu")
		(hatch none 0.5)
		(connect_pads
			(clearance 0)
		)
		(min_thickness 0.25)
		(keepout
			(tracks allowed)
			(vias allowed)
			(pads allowed)
			(copperpour allowed)
			(footprints not_allowed)
		)
		(placement
			(enabled no)
			(sheetname "")
		)
		(fill
			(thermal_gap 0.5)
			(thermal_bridge_width 0.5)
			(island_removal_mode 0)
		)
		(polygon
			(pts
				(arc
					(start 1.999996 -25.584912)
					(mid 6.999986 -30.584902)
					(end 11.999976 -25.584912)
				)
				(xy 11.999976 -13.08989) (xy 11.500104 -13.08989) (xy 11.500104 0)
				(arc
					(start 10.11428 0)
					(mid 9.731597 -0.07612)
					(end 9.407144 -0.292862)
				)
				(arc
					(start 8.99287 -0.707136)
					(mid 8.776088 -1.031573)
					(end 8.700008 -1.414272)
				)
				(arc
					(start 8.700008 -7.590028)
					(mid 6.999986 -9.29005)
					(end 5.299964 -7.590028)
				)
				(arc
					(start 5.299964 -1.414272)
					(mid 5.223844 -1.031589)
					(end 5.007102 -0.707136)
				)
				(arc
					(start 4.592828 -0.292862)
					(mid 4.268391 -0.07608)
					(end 3.885692 0)
				)
				(arc
					(start 0.999998 0)
					(mid 0.292893 -0.292893)
					(end 0 -0.999998)
				)
				(xy 0 -13.08989) (xy 1.999996 -13.08989)
			)
		)
	)
	(zone
		(layer "B.Cu")
		(hatch none 0.5)
		(connect_pads
			(clearance 0)
		)
		(min_thickness 0.25)
		(keepout
			(tracks allowed)
			(vias allowed)
			(pads allowed)
			(copperpour allowed)
			(footprints allowed)
		)
		(placement
			(enabled no)
			(sheetname "")
		)
		(fill
			(thermal_gap 0.5)
			(thermal_bridge_width 0.5)
			(island_removal_mode 0)
		)
		(polygon
			(pts
				(xy 46.5582 -13.1191) (xy 48.3616 -13.1191) (xy 48.6283 -13.3858) (xy 48.6283 -14.6812) (xy 48.1838 -15.1257)
				(xy 46.5328 -15.1257) (xy 46.3169 -14.9098) (xy 46.3169 -13.3604)
			)
		)
	)
	(zone
		(layer "B.Cu")
		(hatch none 0.5)
		(connect_pads
			(clearance 0)
		)
		(min_thickness 0.25)
		(keepout
			(tracks allowed)
			(vias allowed)
			(pads allowed)
			(copperpour allowed)
			(footprints allowed)
		)
		(placement
			(enabled no)
			(sheetname "")
		)
		(fill
			(thermal_gap 0.5)
			(thermal_bridge_width 0.5)
			(island_removal_mode 0)
		)
		(polygon
			(pts
				(xy 17.9578 -27.051) (xy 18.796 -27.8892) (xy 18.796 -28.8036) (xy 17.1577 -30.4419) (xy 16.4973 -30.4419)
				(xy 15.5194 -29.464) (xy 15.2654 -29.21) (xy 15.2654 -27.5844) (xy 16.0909 -26.7589) (xy 17.6657 -26.7589)
			)
		)
	)
	(zone
		(layer "B.Cu")
		(hatch none 0.5)
		(connect_pads
			(clearance 0)
		)
		(min_thickness 0.25)
		(keepout
			(tracks allowed)
			(vias allowed)
			(pads allowed)
			(copperpour allowed)
			(footprints not_allowed)
		)
		(placement
			(enabled no)
			(sheetname "")
		)
		(fill
			(thermal_gap 0.5)
			(thermal_bridge_width 0.5)
			(island_removal_mode 0)
		)
		(polygon
			(pts
				(xy 28.90012 -26.699972) (xy 28.90012 -14.37005) (xy 26.900124 -14.37005) (xy 26.900124 -26.699972)
			)
		)
	)
	(zone
		(net "GND")
		(layer "B.Cu")
		(hatch none 0.5)
		(connect_pads
			(clearance 0.5)
		)
		(min_thickness 0.25)
		(fill yes
			(thermal_gap 0.5)
			(thermal_bridge_width 0.5)
			(island_removal_mode 0)
		)
		(polygon
			(pts
				(xy 39.31285 -0.12065) (xy 39.0017 -0.4318) (xy 39.0017 -2.6289) (xy 39.2811 -2.9083) (xy 41.0337 -2.9083)
				(xy 41.1099 -2.8321) (xy 41.1099 -0.6223) (xy 40.60825 -0.12065)
			)
		)
		(polygon
			(pts
				(xy 39.7002 -1.7145) (xy 39.497 -1.7145) (xy 39.497 -1.9177) (xy 39.7002 -1.9177)
			)
		)
		(polygon
			(pts
				(xy 39.7002 -1.1049) (xy 39.497 -1.1049) (xy 39.497 -1.3081) (xy 39.7002 -1.3081)
			)
		)
	)
	(zone
		(net "P12V_ATX")
		(layer "B.Cu")
		(hatch none 0.5)
		(connect_pads
			(clearance 0.5)
		)
		(min_thickness 0.25)
		(fill yes
			(thermal_gap 0.5)
			(thermal_bridge_width 0.5)
			(island_removal_mode 0)
		)
		(polygon
			(pts
				(xy 38.4302 -15.4686) (xy 37.4142 -16.4846) (xy 37.3634 -16.4846) (xy 31.0388 -22.8092) (xy 30.7721 -22.8092)
				(xy 26.1493 -27.432) (xy 26.1493 -28.067) (xy 24.8666 -29.3497) (xy 16.764 -29.3497) (xy 16.1671 -28.7528)
				(xy 15.9893 -28.7528) (xy 14.351 -30.3911) (xy 14.351 -30.988) (xy 15.0876 -31.7246) (xy 31.2166 -31.7246)
				(xy 31.5976 -31.3436) (xy 36.0426 -31.3436) (xy 36.1061 -31.2801) (xy 39.8145 -31.2801) (xy 40.4368 -30.6578)
				(xy 40.4368 -28.6766) (xy 45.593 -23.5204) (xy 45.593 -16.6878) (xy 44.3738 -15.4686)
			)
		)
	)
	(zone
		(net "GND")
		(layer "B.Cu")
		(hatch none 0.5)
		(connect_pads
			(clearance 0.5)
		)
		(min_thickness 0.25)
		(fill yes
			(thermal_gap 0.5)
			(thermal_bridge_width 0.5)
			(island_removal_mode 0)
		)
		(polygon
			(pts
				(xy 134.8994 -13.1572) (xy 132.96265 -15.09395) (xy 132.96265 -17.82445) (xy 133.3627 -18.2245)
				(xy 133.3627 -19.0881) (xy 132.6261 -19.8247) (xy 132.6261 -20.1168) (xy 132.8293 -20.32) (xy 132.8293 -22.3012)
				(xy 133.985 -23.4569) (xy 133.985 -26.9113) (xy 131.8895 -29.0068) (xy 130.0607 -29.0068) (xy 129.9591 -29.1084)
				(xy 129.9591 -30.1244) (xy 129.5527 -30.5308) (xy 129.5527 -30.8356) (xy 130.0099 -31.2928) (xy 130.0099 -33.3883)
				(xy 129.5527 -33.8455) (xy 127.762 -33.8455) (xy 127.4445 -33.528) (xy 127.0635 -33.528) (xy 126.9746 -33.6169)
				(xy 126.9746 -34.0995) (xy 127.2794 -34.4043) (xy 144.1196 -34.4043) (xy 146.7231 -31.8008) (xy 146.7231 -13.716)
				(xy 146.1643 -13.1572)
			)
		)
		(polygon
			(pts
				(xy 131.0132 -29.7942) (xy 130.81 -29.7942) (xy 130.81 -29.9974) (xy 131.0132 -29.9974)
			)
		)
	)
	(zone
		(layer "B.Cu")
		(hatch none 0.5)
		(connect_pads
			(clearance 0)
		)
		(min_thickness 0.25)
		(keepout
			(tracks not_allowed)
			(vias allowed)
			(pads allowed)
			(copperpour not_allowed)
			(footprints allowed)
		)
		(placement
			(enabled no)
			(sheetname "")
		)
		(fill
			(thermal_gap 0.5)
			(thermal_bridge_width 0.5)
			(island_removal_mode 0)
		)
		(polygon
			(pts
				(arc
					(start 5.299964 -7.590028)
					(mid 6.999986 -9.29005)
					(end 8.700008 -7.590028)
				)
				(arc
					(start 8.700008 -1.414272)
					(mid 8.776128 -1.031589)
					(end 8.99287 -0.707136)
				)
				(arc
					(start 9.407144 -0.292862)
					(mid 9.731581 -0.07608)
					(end 10.11428 0)
				)
				(xy 11.500104 0) (xy 11.500104 -13.08989) (xy 0 -13.08989)
				(arc
					(start 0 -0.999998)
					(mid 0.292893 -0.292893)
					(end 0.999998 0)
				)
				(arc
					(start 3.885692 0)
					(mid 4.268375 -0.07612)
					(end 4.592828 -0.292862)
				)
				(arc
					(start 5.007102 -0.707136)
					(mid 5.223884 -1.031573)
					(end 5.299964 -1.414272)
				)
			)
		)
	)
	(zone
		(layer "B.Cu")
		(hatch none 0.5)
		(connect_pads
			(clearance 0)
		)
		(min_thickness 0.25)
		(keepout
			(tracks not_allowed)
			(vias allowed)
			(pads allowed)
			(copperpour not_allowed)
			(footprints allowed)
		)
		(placement
			(enabled no)
			(sheetname "")
		)
		(fill
			(thermal_gap 0.5)
			(thermal_bridge_width 0.5)
			(island_removal_mode 0)
		)
		(polygon
			(pts
				(arc
					(start 147.500086 -0.999998)
					(mid 147.207193 -0.292893)
					(end 146.500088 0)
				)
				(arc
					(start 143.61414 0)
					(mid 143.231457 -0.07612)
					(end 142.907004 -0.292862)
				)
				(arc
					(start 142.492984 -0.707136)
					(mid 142.276202 -1.031573)
					(end 142.200122 -1.414272)
				)
				(arc
					(start 142.200122 -7.590028)
					(mid 140.5001 -9.29005)
					(end 138.800078 -7.590028)
				)
				(arc
					(start 138.800078 -1.414272)
					(mid 138.723958 -1.031589)
					(end 138.507216 -0.707136)
				)
				(arc
					(start 138.092942 -0.292862)
					(mid 137.768505 -0.07608)
					(end 137.385806 0)
				)
				(xy 135.999982 0) (xy 135.999982 -13.08989) (xy 147.500086 -13.08989)
			)
		)
	)
	(zone
		(layer "B.Cu")
		(hatch none 0.5)
		(connect_pads
			(clearance 0)
		)
		(min_thickness 0.25)
		(keepout
			(tracks allowed)
			(vias allowed)
			(pads allowed)
			(copperpour allowed)
			(footprints not_allowed)
		)
		(placement
			(enabled no)
			(sheetname "")
		)
		(fill
			(thermal_gap 0.5)
			(thermal_bridge_width 0.5)
			(island_removal_mode 0)
		)
		(polygon
			(pts
				(xy 104.000046 -26.690066) (xy 135.50011 -26.690066) (xy 135.50011 -13.08989) (xy 104.000046 -13.08989)
			)
		)
	)
	(zone
		(layer "B.Cu")
		(hatch none 0.5)
		(connect_pads
			(clearance 0)
		)
		(min_thickness 0.25)
		(keepout
			(tracks allowed)
			(vias allowed)
			(pads allowed)
			(copperpour allowed)
			(footprints allowed)
		)
		(placement
			(enabled no)
			(sheetname "")
		)
		(fill
			(thermal_gap 0.5)
			(thermal_bridge_width 0.5)
			(island_removal_mode 0)
		)
		(polygon
			(pts
				(xy 26.6192 -7.3152) (xy 26.6192 -12.7508) (xy 26.6065 -12.7635) (xy 26.9113 -12.7635) (xy 27.2288 -13.081)
				(xy 27.2288 -16.3576) (xy 27.2034 -16.383) (xy 25.0952 -16.383) (xy 23.5204 -14.8082) (xy 19.8628 -14.8082)
				(xy 19.0246 -14.8082) (xy 18.1356 -13.9192) (xy 18.1356 -7.0358) (xy 18.1356 -5.715) (xy 15.9512 -5.715)
				(xy 15.621 -5.3848) (xy 15.621 -4.445) (xy 17.6657 -2.4003) (xy 18.6055 -2.4003) (xy 18.669 -2.3368)
				(xy 19.1516 -2.3368) (xy 24.7142 -2.3368) (xy 26.6192 -4.2418)
			)
		)
	)
	(zone
		(net "GND")
		(layer "B.Cu")
		(hatch none 0.5)
		(connect_pads
			(clearance 0.5)
		)
		(min_thickness 0.25)
		(fill yes
			(thermal_gap 0.5)
			(thermal_bridge_width 0.5)
			(island_removal_mode 0)
		)
		(polygon
			(pts
				(xy 123.2154 -25.8572) (xy 121.666 -27.4066) (xy 121.666 -30.4038) (xy 121.793 -30.5308) (xy 126.0856 -30.5308)
				(xy 127.1524 -29.464) (xy 127.1524 -27.051) (xy 126.8476 -26.7462) (xy 125.5014 -26.7462) (xy 124.6124 -25.8572)
			)
		)
		(polygon
			(pts
				(xy 125.603 -29.7942) (xy 125.3998 -29.7942) (xy 125.3998 -29.9974) (xy 125.603 -29.9974)
			)
		)
		(polygon
			(pts
				(xy 124.9934 -29.7942) (xy 124.7902 -29.7942) (xy 124.7902 -29.9974) (xy 124.9934 -29.9974)
			)
		)
		(polygon
			(pts
				(xy 122.4534 -29.6926) (xy 122.2502 -29.6926) (xy 122.2502 -29.8958) (xy 122.4534 -29.8958)
			)
		)
		(polygon
			(pts
				(xy 123.952 -29.5148) (xy 123.7488 -29.5148) (xy 123.7488 -29.718) (xy 123.952 -29.718)
			)
		)
		(polygon
			(pts
				(xy 123.0884 -29.5148) (xy 122.8852 -29.5148) (xy 122.8852 -29.718) (xy 123.0884 -29.718)
			)
		)
		(polygon
			(pts
				(xy 126.619 -29.3116) (xy 126.4158 -29.3116) (xy 126.4158 -29.5148) (xy 126.619 -29.5148)
			)
		)
		(polygon
			(pts
				(xy 126.619 -28.702) (xy 126.4158 -28.702) (xy 126.4158 -28.9052) (xy 126.619 -28.9052)
			)
		)
		(polygon
			(pts
				(xy 122.428 -27.813) (xy 122.2248 -27.813) (xy 122.2248 -28.0162) (xy 122.428 -28.0162)
			)
		)
		(polygon
			(pts
				(xy 126.6952 -27.6098) (xy 126.492 -27.6098) (xy 126.492 -27.813) (xy 126.6952 -27.813)
			)
		)
		(polygon
			(pts
				(xy 126.238 -27.305) (xy 126.0348 -27.305) (xy 126.0348 -27.5082) (xy 126.238 -27.5082)
			)
		)
		(polygon
			(pts
				(xy 125.6792 -27.305) (xy 125.476 -27.305) (xy 125.476 -27.5082) (xy 125.6792 -27.5082)
			)
		)
		(polygon
			(pts
				(xy 122.428 -27.2034) (xy 122.2248 -27.2034) (xy 122.2248 -27.4066) (xy 122.428 -27.4066)
			)
		)
		(polygon
			(pts
				(xy 126.6952 -27.0002) (xy 126.492 -27.0002) (xy 126.492 -27.2034) (xy 126.6952 -27.2034)
			)
		)
		(polygon
			(pts
				(xy 124.6886 -26.3652) (xy 124.4854 -26.3652) (xy 124.4854 -26.5684) (xy 124.6886 -26.5684)
			)
		)
		(polygon
			(pts
				(xy 124.079 -26.3652) (xy 123.8758 -26.3652) (xy 123.8758 -26.5684) (xy 124.079 -26.5684)
			)
		)
	)
	(zone
		(layer "B.Cu")
		(hatch none 0.5)
		(connect_pads
			(clearance 0)
		)
		(min_thickness 0.25)
		(keepout
			(tracks allowed)
			(vias allowed)
			(pads allowed)
			(copperpour allowed)
			(footprints not_allowed)
		)
		(placement
			(enabled no)
			(sheetname "")
		)
		(fill
			(thermal_gap 0.5)
			(thermal_bridge_width 0.5)
			(island_removal_mode 0)
		)
		(polygon
			(pts
				(xy 14.549882 6.530086) (xy 99.199954 6.530086) (xy 107.750102 6.530086) (xy 133.199886 6.530086)
				(xy 133.199886 4.029964) (xy 122.700034 4.029964) (xy 122.700034 -13.10005) (xy 84.000086 -13.10005)
				(xy 84.000086 -14.37005) (xy 26.900124 -14.37005) (xy 26.900124 4.029964) (xy 14.549882 4.029964)
			)
		)
	)
	(zone
		(layer "B.Cu")
		(hatch none 0.5)
		(connect_pads
			(clearance 0)
		)
		(min_thickness 0.25)
		(keepout
			(tracks allowed)
			(vias allowed)
			(pads allowed)
			(copperpour allowed)
			(footprints allowed)
		)
		(placement
			(enabled no)
			(sheetname "")
		)
		(fill
			(thermal_gap 0.5)
			(thermal_bridge_width 0.5)
			(island_removal_mode 0)
		)
		(polygon
			(pts
				(xy 36.3093 -5.4483) (xy 38.9382 -5.4483) (xy 39.9669 -6.477) (xy 39.9669 -9.0678) (xy 38.6715 -10.3632)
				(xy 35.9664 -10.3632) (xy 35.1282 -9.525) (xy 35.1282 -6.6294)
			)
		)
	)
	(zone
		(layer "B.Cu")
		(hatch none 0.5)
		(connect_pads
			(clearance 0)
		)
		(min_thickness 0.25)
		(keepout
			(tracks allowed)
			(vias allowed)
			(pads allowed)
			(copperpour allowed)
			(footprints not_allowed)
		)
		(placement
			(enabled no)
			(sheetname "")
		)
		(fill
			(thermal_gap 0.5)
			(thermal_bridge_width 0.5)
			(island_removal_mode 0)
		)
		(polygon
			(pts
				(xy 28.90012 -26.699972) (xy 104.000046 -26.699972) (xy 104.000046 -13.10005) (xy 84.000086 -13.10005)
				(xy 84.000086 -14.37005) (xy 28.90012 -14.37005)
			)
		)
	)
	(zone
		(net "P12V")
		(layer "In1.Cu")
		(hatch none 0.5)
		(connect_pads
			(clearance 0.5)
		)
		(min_thickness 0.25)
		(fill yes
			(thermal_gap 0.5)
			(thermal_bridge_width 0.5)
			(island_removal_mode 0)
		)
		(polygon
			(pts
				(xy 15.420848 9.4107) (xy 15.312898 9.30275) (xy 15.312898 0.199898) (xy 15.311882 0.155702) (xy 15.311882 -0.115824)
				(arc
					(start 15.224506 -0.2032)
					(mid 15.030894 -0.481012)
					(end 14.753082 -0.674624)
				)
				(xy 14.665706 -0.762) (xy 14.39418 -0.762) (xy 14.349984 -0.763016) (xy 13.133832 -0.763016) (xy 12.9794 -0.917448)
				(xy 12.9794 -2.491994) (xy 10.6553 -4.816094) (xy 10.6553 -10.861294) (xy 9.3472 -12.169394) (xy 9.3472 -20.799806)
				(xy 10.9347 -22.387306) (xy 10.9347 -27.289506) (xy 11.864594 -28.2194) (xy 18.145506 -28.2194)
				(xy 19.5961 -26.768806) (xy 19.5961 -25.986994) (xy 18.361406 -24.7523) (xy 16.563594 -24.7523)
				(xy 16.4973 -24.818594) (xy 16.4973 -25.694894) (xy 15.992094 -26.2001) (xy 14.030706 -26.2001)
				(xy 13.6271 -25.796494) (xy 13.6271 -24.063706) (xy 14.399006 -23.2918) (xy 16.850106 -23.2918)
				(xy 16.9926 -23.149306) (xy 16.9926 -21.757894) (xy 15.732506 -20.4978) (xy 13.116306 -20.4978)
				(xy 12.1158 -19.497294) (xy 12.1158 -16.583406) (xy 12.709906 -15.9893) (xy 14.277594 -15.9893)
				(xy 15.992094 -17.7038) (xy 16.481806 -17.7038) (xy 17.8435 -16.342106) (xy 17.8435 -15.890494)
				(xy 14.8336 -12.880594) (xy 14.8336 -5.826506) (xy 19.1897 -1.470406) (xy 19.1897 9.230106) (xy 19.009106 9.4107)
			)
		)
	)
	(zone
		(net "GND")
		(layer "In1.Cu")
		(hatch none 0.5)
		(connect_pads
			(clearance 0.5)
		)
		(min_thickness 0.25)
		(fill yes
			(thermal_gap 0.5)
			(thermal_bridge_width 0.5)
			(island_removal_mode 0)
		)
		(polygon
			(pts
				(xy 15.312898 10.73277) (xy 15.312898 9.793986) (xy 15.423134 9.793986) (xy 15.42542 9.7917) (xy 19.167094 9.7917)
				(xy 19.5707 9.388094) (xy 19.5707 -1.628394) (xy 15.2146 -5.984494) (xy 15.2146 -12.722606) (xy 18.2245 -15.732506)
				(xy 18.2245 -16.500094) (xy 16.639794 -18.0848) (xy 15.834106 -18.0848) (xy 14.119606 -16.3703)
				(xy 12.867894 -16.3703) (xy 12.4968 -16.741394) (xy 12.4968 -19.339306) (xy 13.274294 -20.1168)
				(xy 15.890494 -20.1168) (xy 17.3736 -21.599906) (xy 17.3736 -23.307294) (xy 17.008094 -23.6728)
				(xy 14.556994 -23.6728) (xy 14.0081 -24.221694) (xy 14.0081 -25.638506) (xy 14.188694 -25.8191)
				(xy 15.834106 -25.8191) (xy 16.1163 -25.536906) (xy 16.1163 -24.660606) (xy 16.405606 -24.3713)
				(xy 18.519394 -24.3713) (xy 19.9771 -25.829006) (xy 19.9771 -26.926794) (xy 18.303494 -28.6004)
				(xy 11.706606 -28.6004) (xy 10.5537 -27.447494) (xy 10.5537 -22.545294) (xy 8.9662 -20.957794) (xy 8.9662 -12.011406)
				(xy 10.2743 -10.703306) (xy 10.2743 -4.658106) (xy 12.5984 -2.334006) (xy 12.5984 -0.929894) (xy 12.431522 -0.763016)
				(arc
					(start 10.113772 -0.763016)
					(mid 10.023303 -0.781069)
					(end 9.94664 -0.832358)
				)
				(arc
					(start 9.532366 -1.246632)
					(mid 9.481154 -1.323326)
					(end 9.463024 -1.413764)
				)
				(xy 9.463024 -7.590028) (xy 9.462008 -7.66064) (xy 9.462008 -7.90575)
				(arc
					(start 9.439656 -7.927848)
					(mid 6.999986 -10.052976)
					(end 4.560316 -7.927848)
				)
				(xy 4.537964 -7.90575) (xy 4.537964 -7.66064) (xy 4.536948 -7.590028)
				(arc
					(start 4.536948 -1.413764)
					(mid 4.518895 -1.323295)
					(end 4.467606 -1.246632)
				)
				(arc
					(start 4.053332 -0.832358)
					(mid 3.976638 -0.781146)
					(end 3.8862 -0.763016)
				)
				(arc
					(start 0.999998 -0.763016)
					(mid 0.832426 -0.832426)
					(end 0.763016 -0.999998)
				)
				(arc
					(start 0.763016 -31.786322)
					(mid 0.781152 -31.876738)
					(end 0.832358 -31.953454)
				)
				(arc
					(start 3.246628 -34.367724)
					(mid 3.323307 -34.419019)
					(end 3.41376 -34.437066)
				)
				(arc
					(start 45.69333 -34.437066)
					(mid 45.643492 -34.376139)
					(end 45.60316 -34.308542)
				)
				(xy 45.602906 -34.308542)
				(arc
					(start 44.6024 -32.308546)
					(mid 44.840652 -31.592774)
					(end 45.556424 -31.831026)
				)
				(arc
					(start 46.557184 -33.831276)
					(mid 46.60782 -34.148359)
					(end 46.467268 -34.437066)
				)
				(arc
					(start 47.69358 -34.437066)
					(mid 47.552979 -34.148531)
					(end 47.60341 -33.83153)
				)
				(xy 47.603156 -33.83153) (xy 48.602646 -31.83128)
				(arc
					(start 48.6029 -31.83128)
					(mid 49.31852 -31.592825)
					(end 49.556924 -32.308546)
				)
				(xy 48.557688 -34.308542)
				(arc
					(start 48.557434 -34.308542)
					(mid 48.517104 -34.37614)
					(end 48.467264 -34.437066)
				)
				(arc
					(start 53.692806 -34.437066)
					(mid 53.642948 -34.376019)
					(end 53.602636 -34.308288)
				)
				(xy 52.603146 -32.308292)
				(arc
					(start 52.6034 -32.308292)
					(mid 52.841906 -31.592774)
					(end 53.557424 -31.83128)
				)
				(xy 53.557678 -31.83128) (xy 54.557168 -33.83153)
				(arc
					(start 54.556914 -33.83153)
					(mid 54.607421 -34.148454)
					(end 54.466998 -34.437066)
				)
				(arc
					(start 57.69356 -34.437066)
					(mid 57.643722 -34.376139)
					(end 57.60339 -34.308542)
				)
				(xy 57.603136 -34.308542)
				(arc
					(start 56.60263 -32.308546)
					(mid 56.840882 -31.592774)
					(end 57.556654 -31.831026)
				)
				(arc
					(start 58.557414 -33.831276)
					(mid 58.60805 -34.148359)
					(end 58.467498 -34.437066)
				)
				(arc
					(start 61.692536 -34.437066)
					(mid 61.642678 -34.376019)
					(end 61.602366 -34.308288)
				)
				(xy 60.602876 -32.308292)
				(arc
					(start 60.60313 -32.308292)
					(mid 60.841636 -31.592774)
					(end 61.557154 -31.83128)
				)
				(xy 61.557408 -31.83128) (xy 62.556898 -33.83153)
				(arc
					(start 62.556644 -33.83153)
					(mid 62.607151 -34.148454)
					(end 62.466728 -34.437066)
				)
				(arc
					(start 63.69304 -34.437066)
					(mid 63.552439 -34.148531)
					(end 63.60287 -33.83153)
				)
				(xy 63.602616 -33.83153) (xy 64.602106 -31.83128)
				(arc
					(start 64.60236 -31.83128)
					(mid 65.31798 -31.592825)
					(end 65.556384 -32.308546)
				)
				(xy 64.557148 -34.308542)
				(arc
					(start 64.556894 -34.308542)
					(mid 64.516564 -34.37614)
					(end 64.466724 -34.437066)
				)
				(arc
					(start 67.69354 -34.437066)
					(mid 67.643702 -34.376139)
					(end 67.60337 -34.308542)
				)
				(xy 67.603116 -34.308542)
				(arc
					(start 66.60261 -32.308546)
					(mid 66.840862 -31.592774)
					(end 67.556634 -31.831026)
				)
				(arc
					(start 68.557394 -33.831276)
					(mid 68.60803 -34.148359)
					(end 68.467478 -34.437066)
				)
				(arc
					(start 71.692516 -34.437066)
					(mid 71.642658 -34.376019)
					(end 71.602346 -34.308288)
				)
				(xy 70.602856 -32.308292)
				(arc
					(start 70.60311 -32.308292)
					(mid 70.841616 -31.592774)
					(end 71.557134 -31.83128)
				)
				(xy 71.557388 -31.83128) (xy 72.556878 -33.83153)
				(arc
					(start 72.556624 -33.83153)
					(mid 72.607131 -34.148454)
					(end 72.466708 -34.437066)
				)
				(arc
					(start 75.69327 -34.437066)
					(mid 75.643432 -34.376139)
					(end 75.6031 -34.308542)
				)
				(xy 75.602846 -34.308542)
				(arc
					(start 74.60234 -32.308546)
					(mid 74.840592 -31.592774)
					(end 75.556364 -31.831026)
				)
				(arc
					(start 76.557124 -33.831276)
					(mid 76.60776 -34.148359)
					(end 76.467208 -34.437066)
				)
				(arc
					(start 79.692246 -34.437066)
					(mid 79.642388 -34.376019)
					(end 79.602076 -34.308288)
				)
				(xy 78.602586 -32.308292)
				(arc
					(start 78.60284 -32.308292)
					(mid 78.841346 -31.592774)
					(end 79.556864 -31.83128)
				)
				(xy 79.557118 -31.83128) (xy 80.556608 -33.83153)
				(arc
					(start 80.556354 -33.83153)
					(mid 80.606861 -34.148454)
					(end 80.466438 -34.437066)
				)
				(arc
					(start 83.693 -34.437066)
					(mid 83.552399 -34.148531)
					(end 83.60283 -33.83153)
				)
				(xy 83.602576 -33.83153) (xy 84.602066 -31.83128)
				(arc
					(start 84.60232 -31.83128)
					(mid 85.31794 -31.592825)
					(end 85.556344 -32.308546)
				)
				(xy 84.557108 -34.308542)
				(arc
					(start 84.556854 -34.308542)
					(mid 84.516524 -34.37614)
					(end 84.466684 -34.437066)
				)
				(arc
					(start 87.6935 -34.437066)
					(mid 87.552899 -34.148531)
					(end 87.60333 -33.83153)
				)
				(xy 87.603076 -33.83153) (xy 88.602566 -31.83128)
				(arc
					(start 88.60282 -31.83128)
					(mid 89.31844 -31.592825)
					(end 89.556844 -32.308546)
				)
				(xy 88.557608 -34.308542)
				(arc
					(start 88.557354 -34.308542)
					(mid 88.517024 -34.37614)
					(end 88.467184 -34.437066)
				)
				(arc
					(start 91.692476 -34.437066)
					(mid 91.551917 -34.14836)
					(end 91.60256 -33.831276)
				)
				(arc
					(start 92.60332 -31.831026)
					(mid 93.319092 -31.592774)
					(end 93.557344 -32.308546)
				)
				(xy 93.557344 -32.3088)
				(arc
					(start 92.556584 -34.308796)
					(mid 92.516357 -34.376247)
					(end 92.466668 -34.437066)
				)
				(arc
					(start 95.69323 -34.437066)
					(mid 95.552629 -34.148531)
					(end 95.60306 -33.83153)
				)
				(xy 95.602806 -33.83153) (xy 96.602296 -31.83128)
				(arc
					(start 96.60255 -31.83128)
					(mid 97.31817 -31.592825)
					(end 97.556574 -32.308546)
				)
				(xy 96.557338 -34.308542)
				(arc
					(start 96.557084 -34.308542)
					(mid 96.516754 -34.37614)
					(end 96.466914 -34.437066)
				)
				(arc
					(start 99.692206 -34.437066)
					(mid 99.551647 -34.14836)
					(end 99.60229 -33.831276)
				)
				(arc
					(start 100.60305 -31.831026)
					(mid 101.318822 -31.592774)
					(end 101.557074 -32.308546)
				)
				(xy 101.557074 -32.3088)
				(arc
					(start 100.556314 -34.308796)
					(mid 100.516087 -34.376247)
					(end 100.466398 -34.437066)
				)
				(arc
					(start 103.69296 -34.437066)
					(mid 103.552359 -34.148531)
					(end 103.60279 -33.83153)
				)
				(xy 103.602536 -33.83153) (xy 104.602026 -31.83128)
				(arc
					(start 104.60228 -31.83128)
					(mid 105.3179 -31.592825)
					(end 105.556304 -32.308546)
				)
				(xy 104.557068 -34.308542)
				(arc
					(start 104.556814 -34.308542)
					(mid 104.516484 -34.37614)
					(end 104.466644 -34.437066)
				)
				(arc
					(start 107.69346 -34.437066)
					(mid 107.552859 -34.148531)
					(end 107.60329 -33.83153)
				)
				(xy 107.603036 -33.83153) (xy 108.602526 -31.83128)
				(arc
					(start 108.60278 -31.83128)
					(mid 109.3184 -31.592825)
					(end 109.556804 -32.308546)
				)
				(xy 108.557568 -34.308542)
				(arc
					(start 108.557314 -34.308542)
					(mid 108.516984 -34.37614)
					(end 108.467144 -34.437066)
				)
				(arc
					(start 111.692436 -34.437066)
					(mid 111.551877 -34.14836)
					(end 111.60252 -33.831276)
				)
				(arc
					(start 112.60328 -31.831026)
					(mid 113.319052 -31.592774)
					(end 113.557304 -32.308546)
				)
				(xy 113.557304 -32.3088)
				(arc
					(start 112.556544 -34.308796)
					(mid 112.516317 -34.376247)
					(end 112.466628 -34.437066)
				)
				(arc
					(start 144.086072 -34.437066)
					(mid 144.176624 -34.418978)
					(end 144.253458 -34.367724)
				)
				(arc
					(start 146.667728 -31.953454)
					(mid 146.719072 -31.876657)
					(end 146.73707 -31.786068)
				)
				(arc
					(start 146.73707 -0.999998)
					(mid 146.66766 -0.832426)
					(end 146.500088 -0.763016)
				)
				(arc
					(start 143.613632 -0.763016)
					(mid 143.523216 -0.781152)
					(end 143.4465 -0.832358)
				)
				(arc
					(start 143.032734 -1.246632)
					(mid 142.981337 -1.323414)
					(end 142.963138 -1.414018)
				)
				(xy 142.963138 -7.590028) (xy 142.962122 -7.66064) (xy 142.962122 -7.90575)
				(arc
					(start 142.93977 -7.927848)
					(mid 140.5001 -10.052976)
					(end 138.06043 -7.927848)
				)
				(xy 138.038078 -7.90575) (xy 138.038078 -7.66064) (xy 138.037062 -7.590028)
				(arc
					(start 138.037062 -1.413764)
					(mid 138.018926 -1.323348)
					(end 137.96772 -1.246632)
				)
				(arc
					(start 137.553446 -0.832358)
					(mid 137.476767 -0.781063)
					(end 137.386314 -0.763016)
				)
				(xy 133.399784 -0.763016) (xy 133.355588 -0.762) (xy 133.084316 -0.762)
				(arc
					(start 132.997194 -0.674624)
					(mid 132.719143 -0.481053)
					(end 132.525262 -0.2032)
				)
				(xy 132.437886 -0.115824) (xy 132.437886 0.155702) (xy 132.43687 0.199644) (xy 132.43687 10.73277)
				(xy 108.713016 10.73277) (xy 108.713016 6.729984) (xy 108.712 6.685788) (xy 108.712 6.414262)
				(arc
					(start 108.624624 6.326886)
					(mid 108.431012 6.049074)
					(end 108.1532 5.855462)
				)
				(xy 108.065824 5.768086) (xy 107.794298 5.768086) (xy 107.750102 5.76707) (xy 99.199954 5.76707)
				(xy 99.155758 5.768086) (xy 98.884232 5.768086)
				(arc
					(start 98.796856 5.855462)
					(mid 98.519044 6.049074)
					(end 98.325432 6.326886)
				)
				(xy 98.238056 6.414262) (xy 98.238056 6.685788) (xy 98.23704 6.729984) (xy 98.23704 10.73277) (xy 44.343066 10.73277)
				(xy 44.343066 9.329928) (xy 44.34205 9.266682) (xy 44.34205 9.014206)
				(arc
					(start 44.312586 8.984742)
					(mid 42.380132 7.366908)
					(end 40.447468 8.984742)
				)
				(xy 40.418004 9.014206) (xy 40.418004 9.266682) (xy 40.416988 9.329928) (xy 40.416988 10.73277)
			)
		)
		(polygon
			(pts
				(arc
					(start 126.511558 -34.426906)
					(mid 127.072644 -33.865439)
					(end 126.511304 -33.304226)
				)
				(arc
					(start 125.639576 -33.304226)
					(mid 125.078236 -33.865566)
					(end 125.639576 -34.426906)
				)
			)
		)
		(polygon
			(pts
				(arc
					(start 116.675408 -33.986978)
					(mid 117.222778 -33.412176)
					(end 116.647976 -32.864806)
				)
				(xy 116.647976 -32.862266) (xy 115.784884 -32.883348) (xy 115.78463 -32.883602)
				(arc
					(start 115.78463 -32.885888)
					(mid 115.23726 -33.46069)
					(end 115.812062 -34.00806)
				)
				(xy 115.812062 -34.0106) (xy 116.675408 -33.989518)
			)
		)
		(polygon
			(pts
				(arc
					(start 106.557064 -27.33167)
					(mid 105.841546 -27.093164)
					(end 105.60304 -27.808682)
				)
				(xy 105.602786 -27.808682)
				(arc
					(start 106.602276 -29.808678)
					(mid 107.317946 -30.047616)
					(end 107.556554 -29.33192)
				)
				(xy 107.556808 -29.33192) (xy 106.557318 -27.33167)
			)
		)
		(polygon
			(pts
				(arc
					(start 98.557334 -27.33167)
					(mid 97.841816 -27.093164)
					(end 97.60331 -27.808682)
				)
				(xy 97.603056 -27.808682)
				(arc
					(start 98.602546 -29.808678)
					(mid 99.318216 -30.047616)
					(end 99.556824 -29.33192)
				)
				(xy 99.557078 -29.33192) (xy 98.557588 -27.33167)
			)
		)
		(polygon
			(pts
				(arc
					(start 94.556834 -27.33167)
					(mid 93.841316 -27.093164)
					(end 93.60281 -27.808682)
				)
				(xy 93.602556 -27.808682)
				(arc
					(start 94.602046 -29.808678)
					(mid 95.317716 -30.047616)
					(end 95.556324 -29.33192)
				)
				(xy 95.556578 -29.33192) (xy 94.557088 -27.33167)
			)
		)
		(polygon
			(pts
				(arc
					(start 86.557104 -27.33167)
					(mid 85.841586 -27.093164)
					(end 85.60308 -27.808682)
				)
				(xy 85.602826 -27.808682)
				(arc
					(start 86.602316 -29.808678)
					(mid 87.317986 -30.047616)
					(end 87.556594 -29.33192)
				)
				(xy 87.556848 -29.33192) (xy 86.557358 -27.33167)
			)
		)
		(polygon
			(pts
				(arc
					(start 46.557184 -27.33167)
					(mid 45.841666 -27.093164)
					(end 45.60316 -27.808682)
				)
				(xy 45.602906 -27.808682)
				(arc
					(start 46.602396 -29.808678)
					(mid 47.318066 -30.047616)
					(end 47.556674 -29.33192)
				)
				(xy 47.556928 -29.33192) (xy 46.557438 -27.33167)
			)
		)
		(polygon
			(pts
				(arc
					(start 74.556874 -27.808936)
					(mid 74.31852 -27.093113)
					(end 73.60285 -27.33167)
				)
				(xy 73.602596 -27.33167) (xy 72.603106 -29.33192)
				(arc
					(start 72.60336 -29.33192)
					(mid 72.841866 -30.047438)
					(end 73.557384 -29.808932)
				)
				(xy 73.557638 -29.808932)
			)
		)
		(polygon
			(pts
				(arc
					(start 70.556374 -27.808936)
					(mid 70.31802 -27.093113)
					(end 69.60235 -27.33167)
				)
				(xy 69.602096 -27.33167) (xy 68.602606 -29.33192)
				(arc
					(start 68.60286 -29.33192)
					(mid 68.841366 -30.047438)
					(end 69.556884 -29.808932)
				)
				(xy 69.557138 -29.808932)
			)
		)
		(polygon
			(pts
				(arc
					(start 60.556394 -27.808936)
					(mid 60.31804 -27.093113)
					(end 59.60237 -27.33167)
				)
				(xy 59.602116 -27.33167) (xy 58.602626 -29.33192)
				(arc
					(start 58.60288 -29.33192)
					(mid 58.841386 -30.047438)
					(end 59.556904 -29.808932)
				)
				(xy 59.557158 -29.808932)
			)
		)
		(polygon
			(pts
				(arc
					(start 52.556664 -27.808936)
					(mid 52.31831 -27.093113)
					(end 51.60264 -27.33167)
				)
				(xy 51.602386 -27.33167) (xy 50.602896 -29.33192)
				(arc
					(start 50.60315 -29.33192)
					(mid 50.841656 -30.047438)
					(end 51.557174 -29.808932)
				)
				(xy 51.557428 -29.808932)
			)
		)
		(polygon
			(pts
				(arc
					(start 110.556294 -27.331416)
					(mid 109.840522 -27.093164)
					(end 109.60227 -27.808936)
				)
				(xy 110.602776 -29.808932)
				(arc
					(start 110.60303 -29.808932)
					(mid 111.31865 -30.047387)
					(end 111.557054 -29.331666)
				)
			)
		)
		(polygon
			(pts
				(arc
					(start 102.556564 -27.331416)
					(mid 101.840792 -27.093164)
					(end 101.60254 -27.808936)
				)
				(xy 102.603046 -29.808932)
				(arc
					(start 102.6033 -29.808932)
					(mid 103.31892 -30.047387)
					(end 103.557324 -29.331666)
				)
			)
		)
		(polygon
			(pts
				(arc
					(start 90.556334 -27.331416)
					(mid 89.840562 -27.093164)
					(end 89.60231 -27.808936)
				)
				(xy 90.602816 -29.808932)
				(arc
					(start 90.60307 -29.808932)
					(mid 91.31869 -30.047387)
					(end 91.557094 -29.331666)
				)
			)
		)
		(polygon
			(pts
				(arc
					(start 82.556604 -27.331416)
					(mid 81.840832 -27.093164)
					(end 81.60258 -27.808936)
				)
				(xy 82.603086 -29.808932)
				(arc
					(start 82.60334 -29.808932)
					(mid 83.31896 -30.047387)
					(end 83.557364 -29.331666)
				)
			)
		)
		(polygon
			(pts
				(arc
					(start 78.557374 -27.808936)
					(mid 78.319122 -27.093164)
					(end 77.60335 -27.331416)
				)
				(arc
					(start 76.60259 -29.331666)
					(mid 76.840842 -30.047438)
					(end 77.556614 -29.809186)
				)
				(xy 78.557374 -27.80919)
			)
		)
		(polygon
			(pts
				(arc
					(start 66.557144 -27.808936)
					(mid 66.318892 -27.093164)
					(end 65.60312 -27.331416)
				)
				(arc
					(start 64.60236 -29.331666)
					(mid 64.840612 -30.047438)
					(end 65.556384 -29.809186)
				)
				(xy 66.557144 -27.80919)
			)
		)
		(polygon
			(pts
				(arc
					(start 56.557164 -27.808936)
					(mid 56.318912 -27.093164)
					(end 55.60314 -27.331416)
				)
				(arc
					(start 54.60238 -29.331666)
					(mid 54.840632 -30.047438)
					(end 55.556404 -29.809186)
				)
				(xy 56.557164 -27.80919)
			)
		)
		(polygon
			(pts
				(arc
					(start 79.556864 -11.51128)
					(mid 78.841346 -11.272774)
					(end 78.60284 -11.988292)
				)
				(xy 78.602586 -11.988292)
				(arc
					(start 79.602076 -13.988288)
					(mid 80.317746 -14.227226)
					(end 80.556354 -13.51153)
				)
				(xy 80.556608 -13.51153) (xy 79.557118 -11.51128)
			)
		)
		(polygon
			(pts
				(arc
					(start 71.557134 -11.51128)
					(mid 70.841616 -11.272774)
					(end 70.60311 -11.988292)
				)
				(xy 70.602856 -11.988292)
				(arc
					(start 71.602346 -13.988288)
					(mid 72.318016 -14.227226)
					(end 72.556624 -13.51153)
				)
				(xy 72.556878 -13.51153) (xy 71.557388 -11.51128)
			)
		)
		(polygon
			(pts
				(arc
					(start 61.557154 -11.51128)
					(mid 60.841636 -11.272774)
					(end 60.60313 -11.988292)
				)
				(xy 60.602876 -11.988292)
				(arc
					(start 61.602366 -13.988288)
					(mid 62.318036 -14.227226)
					(end 62.556644 -13.51153)
				)
				(xy 62.556898 -13.51153) (xy 61.557408 -11.51128)
			)
		)
		(polygon
			(pts
				(arc
					(start 53.557424 -11.51128)
					(mid 52.841906 -11.272774)
					(end 52.6034 -11.988292)
				)
				(xy 52.603146 -11.988292)
				(arc
					(start 53.602636 -13.988288)
					(mid 54.318306 -14.227226)
					(end 54.556914 -13.51153)
				)
				(xy 54.557168 -13.51153) (xy 53.557678 -11.51128)
			)
		)
		(polygon
			(pts
				(arc
					(start 109.556804 -11.988546)
					(mid 109.31845 -11.272723)
					(end 108.60278 -11.51128)
				)
				(xy 108.602526 -11.51128) (xy 107.603036 -13.51153)
				(arc
					(start 107.60329 -13.51153)
					(mid 107.841796 -14.227048)
					(end 108.557314 -13.988542)
				)
				(xy 108.557568 -13.988542)
			)
		)
		(polygon
			(pts
				(arc
					(start 105.556304 -11.988546)
					(mid 105.31795 -11.272723)
					(end 104.60228 -11.51128)
				)
				(xy 104.602026 -11.51128) (xy 103.602536 -13.51153)
				(arc
					(start 103.60279 -13.51153)
					(mid 103.841296 -14.227048)
					(end 104.556814 -13.988542)
				)
				(xy 104.557068 -13.988542)
			)
		)
		(polygon
			(pts
				(arc
					(start 97.556574 -11.988546)
					(mid 97.31822 -11.272723)
					(end 96.60255 -11.51128)
				)
				(xy 96.602296 -11.51128) (xy 95.602806 -13.51153)
				(arc
					(start 95.60306 -13.51153)
					(mid 95.841566 -14.227048)
					(end 96.557084 -13.988542)
				)
				(xy 96.557338 -13.988542)
			)
		)
		(polygon
			(pts
				(arc
					(start 89.556844 -11.988546)
					(mid 89.31849 -11.272723)
					(end 88.60282 -11.51128)
				)
				(xy 88.602566 -11.51128) (xy 87.603076 -13.51153)
				(arc
					(start 87.60333 -13.51153)
					(mid 87.841836 -14.227048)
					(end 88.557354 -13.988542)
				)
				(xy 88.557608 -13.988542)
			)
		)
		(polygon
			(pts
				(arc
					(start 85.556344 -11.988546)
					(mid 85.31799 -11.272723)
					(end 84.60232 -11.51128)
				)
				(xy 84.602066 -11.51128) (xy 83.602576 -13.51153)
				(arc
					(start 83.60283 -13.51153)
					(mid 83.841336 -14.227048)
					(end 84.556854 -13.988542)
				)
				(xy 84.557108 -13.988542)
			)
		)
		(polygon
			(pts
				(arc
					(start 65.556384 -11.988546)
					(mid 65.31803 -11.272723)
					(end 64.60236 -11.51128)
				)
				(xy 64.602106 -11.51128) (xy 63.602616 -13.51153)
				(arc
					(start 63.60287 -13.51153)
					(mid 63.841376 -14.227048)
					(end 64.556894 -13.988542)
				)
				(xy 64.557148 -13.988542)
			)
		)
		(polygon
			(pts
				(arc
					(start 49.556924 -11.988546)
					(mid 49.31857 -11.272723)
					(end 48.6029 -11.51128)
				)
				(xy 48.602646 -11.51128) (xy 47.603156 -13.51153)
				(arc
					(start 47.60341 -13.51153)
					(mid 47.841916 -14.227048)
					(end 48.557434 -13.988542)
				)
				(xy 48.557688 -13.988542)
			)
		)
		(polygon
			(pts
				(arc
					(start 113.557304 -11.988546)
					(mid 113.319052 -11.272774)
					(end 112.60328 -11.511026)
				)
				(arc
					(start 111.60252 -13.511276)
					(mid 111.840772 -14.227048)
					(end 112.556544 -13.988796)
				)
				(xy 113.557304 -11.9888)
			)
		)
		(polygon
			(pts
				(arc
					(start 101.557074 -11.988546)
					(mid 101.318822 -11.272774)
					(end 100.60305 -11.511026)
				)
				(arc
					(start 99.60229 -13.511276)
					(mid 99.840542 -14.227048)
					(end 100.556314 -13.988796)
				)
				(xy 101.557074 -11.9888)
			)
		)
		(polygon
			(pts
				(arc
					(start 93.557344 -11.988546)
					(mid 93.319092 -11.272774)
					(end 92.60332 -11.511026)
				)
				(arc
					(start 91.60256 -13.511276)
					(mid 91.840812 -14.227048)
					(end 92.556584 -13.988796)
				)
				(xy 93.557344 -11.9888)
			)
		)
		(polygon
			(pts
				(arc
					(start 75.556364 -11.511026)
					(mid 74.840592 -11.272774)
					(end 74.60234 -11.988546)
				)
				(xy 75.602846 -13.988542)
				(arc
					(start 75.6031 -13.988542)
					(mid 76.31872 -14.226997)
					(end 76.557124 -13.511276)
				)
			)
		)
		(polygon
			(pts
				(arc
					(start 67.556634 -11.511026)
					(mid 66.840862 -11.272774)
					(end 66.60261 -11.988546)
				)
				(xy 67.603116 -13.988542)
				(arc
					(start 67.60337 -13.988542)
					(mid 68.31899 -14.226997)
					(end 68.557394 -13.511276)
				)
			)
		)
		(polygon
			(pts
				(arc
					(start 57.556654 -11.511026)
					(mid 56.840882 -11.272774)
					(end 56.60263 -11.988546)
				)
				(xy 57.603136 -13.988542)
				(arc
					(start 57.60339 -13.988542)
					(mid 58.31901 -14.226997)
					(end 58.557414 -13.511276)
				)
			)
		)
		(polygon
			(pts
				(arc
					(start 45.556424 -11.511026)
					(mid 44.840652 -11.272774)
					(end 44.6024 -11.988546)
				)
				(xy 45.602906 -13.988542)
				(arc
					(start 45.60316 -13.988542)
					(mid 46.31878 -14.226997)
					(end 46.557184 -13.511276)
				)
			)
		)
		(polygon
			(pts
				(arc
					(start 106.557064 -7.01167)
					(mid 105.841546 -6.773164)
					(end 105.60304 -7.488682)
				)
				(xy 105.602786 -7.488682)
				(arc
					(start 106.602276 -9.488678)
					(mid 107.317946 -9.727616)
					(end 107.556554 -9.01192)
				)
				(xy 107.556808 -9.01192) (xy 106.557318 -7.01167)
			)
		)
		(polygon
			(pts
				(arc
					(start 98.557334 -7.01167)
					(mid 97.841816 -6.773164)
					(end 97.60331 -7.488682)
				)
				(xy 97.603056 -7.488682)
				(arc
					(start 98.602546 -9.488678)
					(mid 99.318216 -9.727616)
					(end 99.556824 -9.01192)
				)
				(xy 99.557078 -9.01192) (xy 98.557588 -7.01167)
			)
		)
		(polygon
			(pts
				(arc
					(start 94.556834 -7.01167)
					(mid 93.841316 -6.773164)
					(end 93.60281 -7.488682)
				)
				(xy 93.602556 -7.488682)
				(arc
					(start 94.602046 -9.488678)
					(mid 95.317716 -9.727616)
					(end 95.556324 -9.01192)
				)
				(xy 95.556578 -9.01192) (xy 94.557088 -7.01167)
			)
		)
		(polygon
			(pts
				(arc
					(start 86.557104 -7.01167)
					(mid 85.841586 -6.773164)
					(end 85.60308 -7.488682)
				)
				(xy 85.602826 -7.488682)
				(arc
					(start 86.602316 -9.488678)
					(mid 87.317986 -9.727616)
					(end 87.556594 -9.01192)
				)
				(xy 87.556848 -9.01192) (xy 86.557358 -7.01167)
			)
		)
		(polygon
			(pts
				(arc
					(start 46.557184 -7.01167)
					(mid 45.841666 -6.773164)
					(end 45.60316 -7.488682)
				)
				(xy 45.602906 -7.488682)
				(arc
					(start 46.602396 -9.488678)
					(mid 47.318066 -9.727616)
					(end 47.556674 -9.01192)
				)
				(xy 47.556928 -9.01192) (xy 46.557438 -7.01167)
			)
		)
		(polygon
			(pts
				(arc
					(start 74.556874 -7.488936)
					(mid 74.31852 -6.773113)
					(end 73.60285 -7.01167)
				)
				(xy 73.602596 -7.01167) (xy 72.603106 -9.01192)
				(arc
					(start 72.60336 -9.01192)
					(mid 72.841866 -9.727438)
					(end 73.557384 -9.488932)
				)
				(xy 73.557638 -9.488932)
			)
		)
		(polygon
			(pts
				(arc
					(start 70.556374 -7.488936)
					(mid 70.31802 -6.773113)
					(end 69.60235 -7.01167)
				)
				(xy 69.602096 -7.01167) (xy 68.602606 -9.01192)
				(arc
					(start 68.60286 -9.01192)
					(mid 68.841366 -9.727438)
					(end 69.556884 -9.488932)
				)
				(xy 69.557138 -9.488932)
			)
		)
		(polygon
			(pts
				(arc
					(start 60.556394 -7.488936)
					(mid 60.31804 -6.773113)
					(end 59.60237 -7.01167)
				)
				(xy 59.602116 -7.01167) (xy 58.602626 -9.01192)
				(arc
					(start 58.60288 -9.01192)
					(mid 58.841386 -9.727438)
					(end 59.556904 -9.488932)
				)
				(xy 59.557158 -9.488932)
			)
		)
		(polygon
			(pts
				(arc
					(start 52.556664 -7.488936)
					(mid 52.31831 -6.773113)
					(end 51.60264 -7.01167)
				)
				(xy 51.602386 -7.01167) (xy 50.602896 -9.01192)
				(arc
					(start 50.60315 -9.01192)
					(mid 50.841656 -9.727438)
					(end 51.557174 -9.488932)
				)
				(xy 51.557428 -9.488932)
			)
		)
		(polygon
			(pts
				(arc
					(start 110.556294 -7.011416)
					(mid 109.840522 -6.773164)
					(end 109.60227 -7.488936)
				)
				(xy 110.602776 -9.488932)
				(arc
					(start 110.60303 -9.488932)
					(mid 111.31865 -9.727387)
					(end 111.557054 -9.011666)
				)
			)
		)
		(polygon
			(pts
				(arc
					(start 102.556564 -7.011416)
					(mid 101.840792 -6.773164)
					(end 101.60254 -7.488936)
				)
				(xy 102.603046 -9.488932)
				(arc
					(start 102.6033 -9.488932)
					(mid 103.31892 -9.727387)
					(end 103.557324 -9.011666)
				)
			)
		)
		(polygon
			(pts
				(arc
					(start 90.556334 -7.011416)
					(mid 89.840562 -6.773164)
					(end 89.60231 -7.488936)
				)
				(xy 90.602816 -9.488932)
				(arc
					(start 90.60307 -9.488932)
					(mid 91.31869 -9.727387)
					(end 91.557094 -9.011666)
				)
			)
		)
		(polygon
			(pts
				(arc
					(start 82.556604 -7.011416)
					(mid 81.840832 -6.773164)
					(end 81.60258 -7.488936)
				)
				(xy 82.603086 -9.488932)
				(arc
					(start 82.60334 -9.488932)
					(mid 83.31896 -9.727387)
					(end 83.557364 -9.011666)
				)
			)
		)
		(polygon
			(pts
				(arc
					(start 78.557374 -7.488936)
					(mid 78.319122 -6.773164)
					(end 77.60335 -7.011416)
				)
				(arc
					(start 76.60259 -9.011666)
					(mid 76.840842 -9.727438)
					(end 77.556614 -9.489186)
				)
				(xy 78.557374 -7.48919)
			)
		)
		(polygon
			(pts
				(arc
					(start 66.557144 -7.488936)
					(mid 66.318892 -6.773164)
					(end 65.60312 -7.011416)
				)
				(arc
					(start 64.60236 -9.011666)
					(mid 64.840612 -9.727438)
					(end 65.556384 -9.489186)
				)
				(xy 66.557144 -7.48919)
			)
		)
		(polygon
			(pts
				(arc
					(start 56.557164 -7.488936)
					(mid 56.318912 -6.773164)
					(end 55.60314 -7.011416)
				)
				(arc
					(start 54.60238 -9.011666)
					(mid 54.840632 -9.727438)
					(end 55.556404 -9.489186)
				)
				(xy 56.557164 -7.48919)
			)
		)
		(polygon
			(pts
				(arc
					(start 97.783142 4.807712)
					(mid 98.141028 5.165979)
					(end 97.782888 5.523992)
				)
				(arc
					(start 96.766888 5.523992)
					(mid 96.408748 5.165852)
					(end 96.766888 4.807712)
				)
			)
		)
		(polygon
			(pts
				(arc
					(start 95.192342 4.807712)
					(mid 95.550228 5.165979)
					(end 95.192088 5.523992)
				)
				(arc
					(start 94.176088 5.523992)
					(mid 93.817948 5.165852)
					(end 94.176088 4.807712)
				)
			)
		)
		(polygon
			(pts
				(arc
					(start 92.601542 4.807712)
					(mid 92.959428 5.165979)
					(end 92.601288 5.523992)
				)
				(arc
					(start 91.585288 5.523992)
					(mid 91.227148 5.165852)
					(end 91.585288 4.807712)
				)
			)
		)
		(polygon
			(pts
				(arc
					(start 90.010742 4.807712)
					(mid 90.368628 5.165979)
					(end 90.010488 5.523992)
				)
				(arc
					(start 88.994488 5.523992)
					(mid 88.636348 5.165852)
					(end 88.994488 4.807712)
				)
			)
		)
		(polygon
			(pts
				(arc
					(start 87.419942 4.807712)
					(mid 87.777828 5.165979)
					(end 87.419688 5.523992)
				)
				(arc
					(start 86.403688 5.523992)
					(mid 86.045548 5.165852)
					(end 86.403688 4.807712)
				)
			)
		)
		(polygon
			(pts
				(arc
					(start 84.829142 4.807712)
					(mid 85.187028 5.165979)
					(end 84.828888 5.523992)
				)
				(arc
					(start 83.812888 5.523992)
					(mid 83.454748 5.165852)
					(end 83.812888 4.807712)
				)
			)
		)
		(polygon
			(pts
				(arc
					(start 82.238342 4.807712)
					(mid 82.596228 5.165979)
					(end 82.238088 5.523992)
				)
				(arc
					(start 81.222088 5.523992)
					(mid 80.863948 5.165852)
					(end 81.222088 4.807712)
				)
			)
		)
		(polygon
			(pts
				(arc
					(start 79.647542 4.807712)
					(mid 80.005428 5.165979)
					(end 79.647288 5.523992)
				)
				(arc
					(start 78.631288 5.523992)
					(mid 78.273148 5.165852)
					(end 78.631288 4.807712)
				)
			)
		)
		(polygon
			(pts
				(arc
					(start 129.720594 4.848352)
					(mid 130.07848 5.206619)
					(end 129.72034 5.564632)
				)
				(arc
					(start 128.70434 5.564632)
					(mid 128.3462 5.206492)
					(end 128.70434 4.848352)
				)
			)
		)
		(polygon
			(pts
				(arc
					(start 127.129794 4.848352)
					(mid 127.48768 5.206619)
					(end 127.12954 5.564632)
				)
				(arc
					(start 126.11354 5.564632)
					(mid 125.7554 5.206492)
					(end 126.11354 4.848352)
				)
			)
		)
		(polygon
			(pts
				(arc
					(start 124.538994 4.848352)
					(mid 124.89688 5.206619)
					(end 124.53874 5.564632)
				)
				(arc
					(start 123.52274 5.564632)
					(mid 123.1646 5.206492)
					(end 123.52274 4.848352)
				)
			)
		)
		(polygon
			(pts
				(arc
					(start 121.948194 4.848352)
					(mid 122.30608 5.206619)
					(end 121.94794 5.564632)
				)
				(arc
					(start 120.93194 5.564632)
					(mid 120.5738 5.206492)
					(end 120.93194 4.848352)
				)
			)
		)
		(polygon
			(pts
				(arc
					(start 119.357394 4.848352)
					(mid 119.71528 5.206619)
					(end 119.35714 5.564632)
				)
				(arc
					(start 118.34114 5.564632)
					(mid 117.983 5.206492)
					(end 118.34114 4.848352)
				)
			)
		)
		(polygon
			(pts
				(arc
					(start 116.766594 4.848352)
					(mid 117.12448 5.206619)
					(end 116.76634 5.564632)
				)
				(arc
					(start 115.75034 5.564632)
					(mid 115.3922 5.206492)
					(end 115.75034 4.848352)
				)
			)
		)
		(polygon
			(pts
				(arc
					(start 114.175794 4.848352)
					(mid 114.53368 5.206619)
					(end 114.17554 5.564632)
				)
				(arc
					(start 113.15954 5.564632)
					(mid 112.8014 5.206492)
					(end 113.15954 4.848352)
				)
			)
		)
		(polygon
			(pts
				(arc
					(start 111.584994 4.848352)
					(mid 111.94288 5.206619)
					(end 111.58474 5.564632)
				)
				(arc
					(start 110.56874 5.564632)
					(mid 110.2106 5.206492)
					(end 110.56874 4.848352)
				)
			)
		)
		(polygon
			(pts
				(arc
					(start 96.457008 7.343902)
					(mid 96.814894 7.702169)
					(end 96.456754 8.060182)
				)
				(arc
					(start 95.440754 8.060182)
					(mid 95.082614 7.702042)
					(end 95.440754 7.343902)
				)
			)
		)
		(polygon
			(pts
				(arc
					(start 93.866208 7.343902)
					(mid 94.224094 7.702169)
					(end 93.865954 8.060182)
				)
				(arc
					(start 92.849954 8.060182)
					(mid 92.491814 7.702042)
					(end 92.849954 7.343902)
				)
			)
		)
		(polygon
			(pts
				(arc
					(start 91.275408 7.343902)
					(mid 91.633294 7.702169)
					(end 91.275154 8.060182)
				)
				(arc
					(start 90.259154 8.060182)
					(mid 89.901014 7.702042)
					(end 90.259154 7.343902)
				)
			)
		)
		(polygon
			(pts
				(arc
					(start 88.684608 7.343902)
					(mid 89.042494 7.702169)
					(end 88.684354 8.060182)
				)
				(arc
					(start 87.668354 8.060182)
					(mid 87.310214 7.702042)
					(end 87.668354 7.343902)
				)
			)
		)
		(polygon
			(pts
				(arc
					(start 86.093808 7.343902)
					(mid 86.451694 7.702169)
					(end 86.093554 8.060182)
				)
				(arc
					(start 85.077554 8.060182)
					(mid 84.719414 7.702042)
					(end 85.077554 7.343902)
				)
			)
		)
		(polygon
			(pts
				(arc
					(start 83.503008 7.343902)
					(mid 83.860894 7.702169)
					(end 83.502754 8.060182)
				)
				(arc
					(start 82.486754 8.060182)
					(mid 82.128614 7.702042)
					(end 82.486754 7.343902)
				)
			)
		)
		(polygon
			(pts
				(arc
					(start 80.912208 7.343902)
					(mid 81.270094 7.702169)
					(end 80.911954 8.060182)
				)
				(arc
					(start 79.895954 8.060182)
					(mid 79.537814 7.702042)
					(end 79.895954 7.343902)
				)
			)
		)
		(polygon
			(pts
				(arc
					(start 78.321408 7.343902)
					(mid 78.679294 7.702169)
					(end 78.321154 8.060182)
				)
				(arc
					(start 77.305154 8.060182)
					(mid 76.947014 7.702042)
					(end 77.305154 7.343902)
				)
			)
		)
		(polygon
			(pts
				(arc
					(start 128.39446 7.384542)
					(mid 128.752346 7.742809)
					(end 128.394206 8.100822)
				)
				(arc
					(start 127.378206 8.100822)
					(mid 127.020066 7.742682)
					(end 127.378206 7.384542)
				)
			)
		)
		(polygon
			(pts
				(arc
					(start 125.803406 7.384542)
					(mid 126.161546 7.742682)
					(end 125.803406 8.100822)
				)
				(arc
					(start 124.787152 8.100822)
					(mid 124.429266 7.742555)
					(end 124.787406 7.384542)
				)
			)
		)
		(polygon
			(pts
				(arc
					(start 123.21286 7.384542)
					(mid 123.570746 7.742809)
					(end 123.212606 8.100822)
				)
				(arc
					(start 122.196606 8.100822)
					(mid 121.838466 7.742682)
					(end 122.196606 7.384542)
				)
			)
		)
		(polygon
			(pts
				(arc
					(start 120.62206 7.384542)
					(mid 120.979946 7.742809)
					(end 120.621806 8.100822)
				)
				(arc
					(start 119.605806 8.100822)
					(mid 119.247666 7.742682)
					(end 119.605806 7.384542)
				)
			)
		)
		(polygon
			(pts
				(arc
					(start 118.03126 7.384542)
					(mid 118.389146 7.742809)
					(end 118.031006 8.100822)
				)
				(arc
					(start 117.015006 8.100822)
					(mid 116.656866 7.742682)
					(end 117.015006 7.384542)
				)
			)
		)
		(polygon
			(pts
				(arc
					(start 115.44046 7.384542)
					(mid 115.798346 7.742809)
					(end 115.440206 8.100822)
				)
				(arc
					(start 114.424206 8.100822)
					(mid 114.066066 7.742682)
					(end 114.424206 7.384542)
				)
			)
		)
		(polygon
			(pts
				(arc
					(start 112.84966 7.384542)
					(mid 113.207546 7.742809)
					(end 112.849406 8.100822)
				)
				(arc
					(start 111.833406 8.100822)
					(mid 111.475266 7.742682)
					(end 111.833406 7.384542)
				)
			)
		)
		(polygon
			(pts
				(arc
					(start 110.25886 7.384542)
					(mid 110.616746 7.742809)
					(end 110.258606 8.100822)
				)
				(arc
					(start 109.242606 8.100822)
					(mid 108.884466 7.742682)
					(end 109.242606 7.384542)
				)
			)
		)
	)
	(zone
		(layers "In1.Cu" "In4.Cu")
		(hatch none 0.5)
		(connect_pads
			(clearance 0)
		)
		(min_thickness 0.25)
		(keepout
			(tracks not_allowed)
			(vias allowed)
			(pads allowed)
			(copperpour not_allowed)
			(footprints allowed)
		)
		(placement
			(enabled no)
			(sheetname "")
		)
		(fill yes
			(thermal_gap 0.5)
			(thermal_bridge_width 0.5)
			(island_removal_mode 0)
		)
		(polygon
			(pts
				(arc
					(start 61.557154 -31.83128)
					(mid 60.841636 -31.592774)
					(end 60.60313 -32.308292)
				)
				(xy 60.602876 -32.308292)
				(arc
					(start 61.602366 -34.308288)
					(mid 62.318036 -34.547226)
					(end 62.556644 -33.83153)
				)
				(xy 62.556898 -33.83153) (xy 61.557408 -31.83128)
			)
		)
	)
	(zone
		(layers "In1.Cu" "In4.Cu")
		(hatch none 0.5)
		(connect_pads
			(clearance 0)
		)
		(min_thickness 0.25)
		(keepout
			(tracks not_allowed)
			(vias allowed)
			(pads allowed)
			(copperpour not_allowed)
			(footprints allowed)
		)
		(placement
			(enabled no)
			(sheetname "")
		)
		(fill yes
			(thermal_gap 0.5)
			(thermal_bridge_width 0.5)
			(island_removal_mode 0)
		)
		(polygon
			(pts
				(arc
					(start 90.556334 -27.331416)
					(mid 89.840562 -27.093164)
					(end 89.60231 -27.808936)
				)
				(xy 90.602816 -29.808932)
				(arc
					(start 90.60307 -29.808932)
					(mid 91.31869 -30.047387)
					(end 91.557094 -29.331666)
				)
			)
		)
	)
	(zone
		(layers "In1.Cu" "In4.Cu")
		(hatch none 0.5)
		(connect_pads
			(clearance 0)
		)
		(min_thickness 0.25)
		(keepout
			(tracks not_allowed)
			(vias allowed)
			(pads allowed)
			(copperpour not_allowed)
			(footprints allowed)
		)
		(placement
			(enabled no)
			(sheetname "")
		)
		(fill yes
			(thermal_gap 0.5)
			(thermal_bridge_width 0.5)
			(island_removal_mode 0)
		)
		(polygon
			(pts
				(arc
					(start 97.782634 4.807712)
					(mid 98.141028 5.165725)
					(end 97.782888 5.523992)
				)
				(arc
					(start 96.766888 5.523992)
					(mid 96.408748 5.165852)
					(end 96.766888 4.807712)
				)
			)
		)
	)
	(zone
		(layers "In1.Cu" "In4.Cu")
		(hatch none 0.5)
		(connect_pads
			(clearance 0)
		)
		(min_thickness 0.25)
		(keepout
			(tracks not_allowed)
			(vias allowed)
			(pads allowed)
			(copperpour not_allowed)
			(footprints allowed)
		)
		(placement
			(enabled no)
			(sheetname "")
		)
		(fill yes
			(thermal_gap 0.5)
			(thermal_bridge_width 0.5)
			(island_removal_mode 0)
		)
		(polygon
			(pts
				(arc
					(start 94.176088 5.523992)
					(mid 93.817948 5.165852)
					(end 94.176088 4.807712)
				)
				(arc
					(start 95.191834 4.807712)
					(mid 95.550228 5.165725)
					(end 95.192088 5.523992)
				)
			)
		)
	)
	(zone
		(layers "In1.Cu" "In4.Cu")
		(hatch none 0.5)
		(connect_pads
			(clearance 0)
		)
		(min_thickness 0.25)
		(keepout
			(tracks not_allowed)
			(vias allowed)
			(pads allowed)
			(copperpour not_allowed)
			(footprints allowed)
		)
		(placement
			(enabled no)
			(sheetname "")
		)
		(fill yes
			(thermal_gap 0.5)
			(thermal_bridge_width 0.5)
			(island_removal_mode 0)
		)
		(polygon
			(pts
				(arc
					(start 96.4565 7.343902)
					(mid 96.814894 7.701915)
					(end 96.456754 8.060182)
				)
				(arc
					(start 95.440754 8.060182)
					(mid 95.082614 7.702042)
					(end 95.440754 7.343902)
				)
			)
		)
	)
	(zone
		(layers "In1.Cu" "In4.Cu")
		(hatch none 0.5)
		(connect_pads
			(clearance 0)
		)
		(min_thickness 0.25)
		(keepout
			(tracks not_allowed)
			(vias allowed)
			(pads allowed)
			(copperpour not_allowed)
			(footprints allowed)
		)
		(placement
			(enabled no)
			(sheetname "")
		)
		(fill yes
			(thermal_gap 0.5)
			(thermal_bridge_width 0.5)
			(island_removal_mode 0)
		)
		(polygon
			(pts
				(arc
					(start 52.556664 -7.488936)
					(mid 52.31831 -6.773113)
					(end 51.60264 -7.01167)
				)
				(xy 51.602386 -7.01167) (xy 50.602896 -9.01192)
				(arc
					(start 50.60315 -9.01192)
					(mid 50.841656 -9.727438)
					(end 51.557174 -9.488932)
				)
				(xy 51.557428 -9.488932)
			)
		)
	)
	(zone
		(layers "In1.Cu" "In4.Cu")
		(hatch none 0.5)
		(connect_pads
			(clearance 0)
		)
		(min_thickness 0.25)
		(keepout
			(tracks not_allowed)
			(vias allowed)
			(pads allowed)
			(copperpour not_allowed)
			(footprints allowed)
		)
		(placement
			(enabled no)
			(sheetname "")
		)
		(fill yes
			(thermal_gap 0.5)
			(thermal_bridge_width 0.5)
			(island_removal_mode 0)
		)
		(polygon
			(pts
				(arc
					(start 90.556334 -7.011416)
					(mid 89.840562 -6.773164)
					(end 89.60231 -7.488936)
				)
				(xy 90.602816 -9.488932)
				(arc
					(start 90.60307 -9.488932)
					(mid 91.31869 -9.727387)
					(end 91.557094 -9.011666)
				)
			)
		)
	)
	(zone
		(layers "In1.Cu" "In4.Cu")
		(hatch none 0.5)
		(connect_pads
			(clearance 0)
		)
		(min_thickness 0.25)
		(keepout
			(tracks not_allowed)
			(vias allowed)
			(pads allowed)
			(copperpour not_allowed)
			(footprints allowed)
		)
		(placement
			(enabled no)
			(sheetname "")
		)
		(fill yes
			(thermal_gap 0.5)
			(thermal_bridge_width 0.5)
			(island_removal_mode 0)
		)
		(polygon
			(pts
				(arc
					(start 113.557304 -32.308546)
					(mid 113.319052 -31.592774)
					(end 112.60328 -31.831026)
				)
				(arc
					(start 111.60252 -33.831276)
					(mid 111.840772 -34.547048)
					(end 112.556544 -34.308796)
				)
				(xy 113.557304 -32.3088)
			)
		)
	)
	(zone
		(layers "In1.Cu" "In4.Cu")
		(hatch none 0.5)
		(connect_pads
			(clearance 0)
		)
		(min_thickness 0.25)
		(keepout
			(tracks not_allowed)
			(vias allowed)
			(pads allowed)
			(copperpour not_allowed)
			(footprints allowed)
		)
		(placement
			(enabled no)
			(sheetname "")
		)
		(fill yes
			(thermal_gap 0.5)
			(thermal_bridge_width 0.5)
			(island_removal_mode 0)
		)
		(polygon
			(pts
				(arc
					(start 92.849954 8.060182)
					(mid 92.491814 7.702042)
					(end 92.849954 7.343902)
				)
				(arc
					(start 93.8657 7.343902)
					(mid 94.224094 7.701915)
					(end 93.865954 8.060182)
				)
			)
		)
	)
	(zone
		(layers "In1.Cu" "In4.Cu")
		(hatch none 0.5)
		(connect_pads
			(clearance 0)
		)
		(min_thickness 0.25)
		(keepout
			(tracks not_allowed)
			(vias allowed)
			(pads allowed)
			(copperpour not_allowed)
			(footprints allowed)
		)
		(placement
			(enabled no)
			(sheetname "")
		)
		(fill yes
			(thermal_gap 0.5)
			(thermal_bridge_width 0.5)
			(island_removal_mode 0)
		)
		(polygon
			(pts
				(arc
					(start 93.557344 -11.988546)
					(mid 93.319092 -11.272774)
					(end 92.60332 -11.511026)
				)
				(arc
					(start 91.60256 -13.511276)
					(mid 91.840812 -14.227048)
					(end 92.556584 -13.988796)
				)
				(xy 93.557344 -11.9888)
			)
		)
	)
	(zone
		(layers "In1.Cu" "In4.Cu")
		(hatch none 0.5)
		(connect_pads
			(clearance 0)
		)
		(min_thickness 0.25)
		(keepout
			(tracks not_allowed)
			(vias allowed)
			(pads allowed)
			(copperpour not_allowed)
			(footprints allowed)
		)
		(placement
			(enabled no)
			(sheetname "")
		)
		(fill yes
			(thermal_gap 0.5)
			(thermal_bridge_width 0.5)
			(island_removal_mode 0)
		)
		(polygon
			(pts
				(arc
					(start 116.675408 -33.986978)
					(mid 117.222778 -33.412176)
					(end 116.647976 -32.864806)
				)
				(xy 116.647976 -32.862266) (xy 115.784884 -32.883348) (xy 115.78463 -32.883602)
				(arc
					(start 115.78463 -32.885888)
					(mid 115.23726 -33.46069)
					(end 115.812062 -34.00806)
				)
				(xy 115.812062 -34.0106) (xy 116.675408 -33.989518) (xy 116.675408 -33.987232)
			)
		)
	)
	(zone
		(layers "In1.Cu" "In4.Cu")
		(hatch none 0.5)
		(connect_pads
			(clearance 0)
		)
		(min_thickness 0.25)
		(keepout
			(tracks not_allowed)
			(vias allowed)
			(pads allowed)
			(copperpour not_allowed)
			(footprints allowed)
		)
		(placement
			(enabled no)
			(sheetname "")
		)
		(fill yes
			(thermal_gap 0.5)
			(thermal_bridge_width 0.5)
			(island_removal_mode 0)
		)
		(polygon
			(pts
				(arc
					(start 101.557074 -11.988546)
					(mid 101.318822 -11.272774)
					(end 100.60305 -11.511026)
				)
				(arc
					(start 99.60229 -13.511276)
					(mid 99.840542 -14.227048)
					(end 100.556314 -13.988796)
				)
				(xy 101.557074 -11.9888)
			)
		)
	)
	(zone
		(layers "In1.Cu" "In4.Cu")
		(hatch none 0.5)
		(connect_pads
			(clearance 0)
		)
		(min_thickness 0.25)
		(keepout
			(tracks not_allowed)
			(vias allowed)
			(pads allowed)
			(copperpour not_allowed)
			(footprints allowed)
		)
		(placement
			(enabled no)
			(sheetname "")
		)
		(fill yes
			(thermal_gap 0.5)
			(thermal_bridge_width 0.5)
			(island_removal_mode 0)
		)
		(polygon
			(pts
				(arc
					(start 106.557064 -27.33167)
					(mid 105.841546 -27.093164)
					(end 105.60304 -27.808682)
				)
				(xy 105.602786 -27.808682)
				(arc
					(start 106.602276 -29.808678)
					(mid 107.317946 -30.047616)
					(end 107.556554 -29.33192)
				)
				(xy 107.556808 -29.33192) (xy 106.557318 -27.33167)
			)
		)
	)
	(zone
		(layers "In1.Cu" "In4.Cu")
		(hatch none 0.5)
		(connect_pads
			(clearance 0)
		)
		(min_thickness 0.25)
		(keepout
			(tracks not_allowed)
			(vias allowed)
			(pads allowed)
			(copperpour not_allowed)
			(footprints allowed)
		)
		(placement
			(enabled no)
			(sheetname "")
		)
		(fill yes
			(thermal_gap 0.5)
			(thermal_bridge_width 0.5)
			(island_removal_mode 0)
		)
		(polygon
			(pts
				(arc
					(start 116.766086 4.848352)
					(mid 117.12448 5.206365)
					(end 116.76634 5.564632)
				)
				(arc
					(start 115.75034 5.564632)
					(mid 115.3922 5.206492)
					(end 115.75034 4.848352)
				)
			)
		)
	)
	(zone
		(layers "In1.Cu" "In4.Cu")
		(hatch none 0.5)
		(connect_pads
			(clearance 0)
		)
		(min_thickness 0.25)
		(keepout
			(tracks not_allowed)
			(vias allowed)
			(pads allowed)
			(copperpour not_allowed)
			(footprints allowed)
		)
		(placement
			(enabled no)
			(sheetname "")
		)
		(fill yes
			(thermal_gap 0.5)
			(thermal_bridge_width 0.5)
			(island_removal_mode 0)
		)
		(polygon
			(pts
				(arc
					(start 82.556604 -27.331416)
					(mid 81.840832 -27.093164)
					(end 81.60258 -27.808936)
				)
				(xy 82.603086 -29.808932)
				(arc
					(start 82.60334 -29.808932)
					(mid 83.31896 -30.047387)
					(end 83.557364 -29.331666)
				)
			)
		)
	)
	(zone
		(layers "In1.Cu" "In4.Cu")
		(hatch none 0.5)
		(connect_pads
			(clearance 0)
		)
		(min_thickness 0.25)
		(keepout
			(tracks not_allowed)
			(vias allowed)
			(pads allowed)
			(copperpour not_allowed)
			(footprints allowed)
		)
		(placement
			(enabled no)
			(sheetname "")
		)
		(fill yes
			(thermal_gap 0.5)
			(thermal_bridge_width 0.5)
			(island_removal_mode 0)
		)
		(polygon
			(pts
				(arc
					(start 110.258352 7.384542)
					(mid 110.616746 7.742555)
					(end 110.258606 8.100822)
				)
				(arc
					(start 109.242606 8.100822)
					(mid 108.884466 7.742682)
					(end 109.242606 7.384542)
				)
			)
		)
	)
	(zone
		(layers "In1.Cu" "In4.Cu")
		(hatch none 0.5)
		(connect_pads
			(clearance 0)
		)
		(min_thickness 0.25)
		(keepout
			(tracks not_allowed)
			(vias allowed)
			(pads allowed)
			(copperpour not_allowed)
			(footprints allowed)
		)
		(placement
			(enabled no)
			(sheetname "")
		)
		(fill yes
			(thermal_gap 0.5)
			(thermal_bridge_width 0.5)
			(island_removal_mode 0)
		)
		(polygon
			(pts
				(arc
					(start 89.556844 -11.988546)
					(mid 89.31849 -11.272723)
					(end 88.60282 -11.51128)
				)
				(xy 88.602566 -11.51128) (xy 87.603076 -13.51153)
				(arc
					(start 87.60333 -13.51153)
					(mid 87.841836 -14.227048)
					(end 88.557354 -13.988542)
				)
				(xy 88.557608 -13.988542)
			)
		)
	)
	(zone
		(layers "In1.Cu" "In4.Cu")
		(hatch none 0.5)
		(connect_pads
			(clearance 0)
		)
		(min_thickness 0.25)
		(keepout
			(tracks not_allowed)
			(vias allowed)
			(pads allowed)
			(copperpour not_allowed)
			(footprints allowed)
		)
		(placement
			(enabled no)
			(sheetname "")
		)
		(fill yes
			(thermal_gap 0.5)
			(thermal_bridge_width 0.5)
			(island_removal_mode 0)
		)
		(polygon
			(pts
				(arc
					(start 105.556304 -11.988546)
					(mid 105.31795 -11.272723)
					(end 104.60228 -11.51128)
				)
				(xy 104.602026 -11.51128) (xy 103.602536 -13.51153)
				(arc
					(start 103.60279 -13.51153)
					(mid 103.841296 -14.227048)
					(end 104.556814 -13.988542)
				)
				(xy 104.557068 -13.988542)
			)
		)
	)
	(zone
		(layers "In1.Cu" "In4.Cu")
		(hatch none 0.5)
		(connect_pads
			(clearance 0)
		)
		(min_thickness 0.25)
		(keepout
			(tracks not_allowed)
			(vias allowed)
			(pads allowed)
			(copperpour not_allowed)
			(footprints allowed)
		)
		(placement
			(enabled no)
			(sheetname "")
		)
		(fill yes
			(thermal_gap 0.5)
			(thermal_bridge_width 0.5)
			(island_removal_mode 0)
		)
		(polygon
			(pts
				(arc
					(start 70.556374 -7.488936)
					(mid 70.31802 -6.773113)
					(end 69.60235 -7.01167)
				)
				(xy 69.602096 -7.01167) (xy 68.602606 -9.01192)
				(arc
					(start 68.60286 -9.01192)
					(mid 68.841366 -9.727438)
					(end 69.556884 -9.488932)
				)
				(xy 69.557138 -9.488932)
			)
		)
	)
	(zone
		(layers "In1.Cu" "In4.Cu")
		(hatch none 0.5)
		(connect_pads
			(clearance 0)
		)
		(min_thickness 0.25)
		(keepout
			(tracks not_allowed)
			(vias allowed)
			(pads allowed)
			(copperpour not_allowed)
			(footprints allowed)
		)
		(placement
			(enabled no)
			(sheetname "")
		)
		(fill yes
			(thermal_gap 0.5)
			(thermal_bridge_width 0.5)
			(island_removal_mode 0)
		)
		(polygon
			(pts
				(arc
					(start 106.557064 -7.01167)
					(mid 105.841546 -6.773164)
					(end 105.60304 -7.488682)
				)
				(xy 105.602786 -7.488682)
				(arc
					(start 106.602276 -9.488678)
					(mid 107.317946 -9.727616)
					(end 107.556554 -9.01192)
				)
				(xy 107.556808 -9.01192) (xy 106.557318 -7.01167)
			)
		)
	)
	(zone
		(layers "In1.Cu" "In4.Cu")
		(hatch none 0.5)
		(connect_pads
			(clearance 0)
		)
		(min_thickness 0.25)
		(keepout
			(tracks not_allowed)
			(vias allowed)
			(pads allowed)
			(copperpour not_allowed)
			(footprints allowed)
		)
		(placement
			(enabled no)
			(sheetname "")
		)
		(fill yes
			(thermal_gap 0.5)
			(thermal_bridge_width 0.5)
			(island_removal_mode 0)
		)
		(polygon
			(pts
				(arc
					(start 123.212352 7.384542)
					(mid 123.570746 7.742555)
					(end 123.212606 8.100822)
				)
				(arc
					(start 122.196606 8.100822)
					(mid 121.838466 7.742682)
					(end 122.196606 7.384542)
				)
			)
		)
	)
	(zone
		(layers "In1.Cu" "In4.Cu")
		(hatch none 0.5)
		(connect_pads
			(clearance 0)
		)
		(min_thickness 0.25)
		(keepout
			(tracks not_allowed)
			(vias allowed)
			(pads allowed)
			(copperpour not_allowed)
			(footprints allowed)
		)
		(placement
			(enabled no)
			(sheetname "")
		)
		(fill yes
			(thermal_gap 0.5)
			(thermal_bridge_width 0.5)
			(island_removal_mode 0)
		)
		(polygon
			(pts
				(arc
					(start 75.556364 -31.831026)
					(mid 74.840592 -31.592774)
					(end 74.60234 -32.308546)
				)
				(xy 75.602846 -34.308542)
				(arc
					(start 75.6031 -34.308542)
					(mid 76.31872 -34.546997)
					(end 76.557124 -33.831276)
				)
			)
		)
	)
	(zone
		(layers "In1.Cu" "In4.Cu")
		(hatch none 0.5)
		(connect_pads
			(clearance 0)
		)
		(min_thickness 0.25)
		(keepout
			(tracks not_allowed)
			(vias allowed)
			(pads allowed)
			(copperpour not_allowed)
			(footprints allowed)
		)
		(placement
			(enabled no)
			(sheetname "")
		)
		(fill yes
			(thermal_gap 0.5)
			(thermal_bridge_width 0.5)
			(island_removal_mode 0)
		)
		(polygon
			(pts
				(arc
					(start 46.557184 -27.33167)
					(mid 45.841666 -27.093164)
					(end 45.60316 -27.808682)
				)
				(xy 45.602906 -27.808682)
				(arc
					(start 46.602396 -29.808678)
					(mid 47.318066 -30.047616)
					(end 47.556674 -29.33192)
				)
				(xy 47.556928 -29.33192) (xy 46.557438 -27.33167)
			)
		)
	)
	(zone
		(layers "In1.Cu" "In4.Cu")
		(hatch none 0.5)
		(connect_pads
			(clearance 0)
		)
		(min_thickness 0.25)
		(keepout
			(tracks not_allowed)
			(vias allowed)
			(pads allowed)
			(copperpour not_allowed)
			(footprints allowed)
		)
		(placement
			(enabled no)
			(sheetname "")
		)
		(fill yes
			(thermal_gap 0.5)
			(thermal_bridge_width 0.5)
			(island_removal_mode 0)
		)
		(polygon
			(pts
				(arc
					(start 91.585288 5.523992)
					(mid 91.227148 5.165852)
					(end 91.585288 4.807712)
				)
				(arc
					(start 92.601034 4.807712)
					(mid 92.959428 5.165725)
					(end 92.601288 5.523992)
				)
			)
		)
	)
	(zone
		(layers "In1.Cu" "In4.Cu")
		(hatch none 0.5)
		(connect_pads
			(clearance 0)
		)
		(min_thickness 0.25)
		(keepout
			(tracks not_allowed)
			(vias allowed)
			(pads allowed)
			(copperpour not_allowed)
			(footprints allowed)
		)
		(placement
			(enabled no)
			(sheetname "")
		)
		(fill yes
			(thermal_gap 0.5)
			(thermal_bridge_width 0.5)
			(island_removal_mode 0)
		)
		(polygon
			(pts
				(arc
					(start 56.557164 -7.488936)
					(mid 56.318912 -6.773164)
					(end 55.60314 -7.011416)
				)
				(arc
					(start 54.60238 -9.011666)
					(mid 54.840632 -9.727438)
					(end 55.556404 -9.489186)
				)
				(xy 56.557164 -7.48919)
			)
		)
	)
	(zone
		(layers "In1.Cu" "In4.Cu")
		(hatch none 0.5)
		(connect_pads
			(clearance 0)
		)
		(min_thickness 0.25)
		(keepout
			(tracks not_allowed)
			(vias allowed)
			(pads allowed)
			(copperpour not_allowed)
			(footprints allowed)
		)
		(placement
			(enabled no)
			(sheetname "")
		)
		(fill yes
			(thermal_gap 0.5)
			(thermal_bridge_width 0.5)
			(island_removal_mode 0)
		)
		(polygon
			(pts
				(arc
					(start 118.030752 7.384542)
					(mid 118.389146 7.742555)
					(end 118.031006 8.100822)
				)
				(arc
					(start 117.015006 8.100822)
					(mid 116.656866 7.742682)
					(end 117.015006 7.384542)
				)
			)
		)
	)
	(zone
		(layers "In1.Cu" "In4.Cu")
		(hatch none 0.5)
		(connect_pads
			(clearance 0)
		)
		(min_thickness 0.25)
		(keepout
			(tracks not_allowed)
			(vias allowed)
			(pads allowed)
			(copperpour not_allowed)
			(footprints allowed)
		)
		(placement
			(enabled no)
			(sheetname "")
		)
		(fill yes
			(thermal_gap 0.5)
			(thermal_bridge_width 0.5)
			(island_removal_mode 0)
		)
		(polygon
			(pts
				(arc
					(start 67.556634 -31.831026)
					(mid 66.840862 -31.592774)
					(end 66.60261 -32.308546)
				)
				(xy 67.603116 -34.308542)
				(arc
					(start 67.60337 -34.308542)
					(mid 68.31899 -34.546997)
					(end 68.557394 -33.831276)
				)
			)
		)
	)
	(zone
		(layers "In1.Cu" "In4.Cu")
		(hatch none 0.5)
		(connect_pads
			(clearance 0)
		)
		(min_thickness 0.25)
		(keepout
			(tracks not_allowed)
			(vias allowed)
			(pads allowed)
			(copperpour not_allowed)
			(footprints allowed)
		)
		(placement
			(enabled no)
			(sheetname "")
		)
		(fill yes
			(thermal_gap 0.5)
			(thermal_bridge_width 0.5)
			(island_removal_mode 0)
		)
		(polygon
			(pts
				(arc
					(start 85.077554 8.060182)
					(mid 84.719414 7.702042)
					(end 85.077554 7.343902)
				)
				(arc
					(start 86.0933 7.343902)
					(mid 86.451694 7.701915)
					(end 86.093554 8.060182)
				)
			)
		)
	)
	(zone
		(layers "In1.Cu" "In4.Cu")
		(hatch none 0.5)
		(connect_pads
			(clearance 0)
		)
		(min_thickness 0.25)
		(keepout
			(tracks not_allowed)
			(vias allowed)
			(pads allowed)
			(copperpour not_allowed)
			(footprints allowed)
		)
		(placement
			(enabled no)
			(sheetname "")
		)
		(fill yes
			(thermal_gap 0.5)
			(thermal_bridge_width 0.5)
			(island_removal_mode 0)
		)
		(polygon
			(pts
				(arc
					(start 78.557374 -7.488936)
					(mid 78.319122 -6.773164)
					(end 77.60335 -7.011416)
				)
				(arc
					(start 76.60259 -9.011666)
					(mid 76.840842 -9.727438)
					(end 77.556614 -9.489186)
				)
				(xy 78.557374 -7.48919)
			)
		)
	)
	(zone
		(layers "In1.Cu" "In4.Cu")
		(hatch none 0.5)
		(connect_pads
			(clearance 0)
		)
		(min_thickness 0.25)
		(keepout
			(tracks not_allowed)
			(vias allowed)
			(pads allowed)
			(copperpour not_allowed)
			(footprints allowed)
		)
		(placement
			(enabled no)
			(sheetname "")
		)
		(fill yes
			(thermal_gap 0.5)
			(thermal_bridge_width 0.5)
			(island_removal_mode 0)
		)
		(polygon
			(pts
				(arc
					(start 109.556804 -11.988546)
					(mid 109.31845 -11.272723)
					(end 108.60278 -11.51128)
				)
				(xy 108.602526 -11.51128) (xy 107.603036 -13.51153)
				(arc
					(start 107.60329 -13.51153)
					(mid 107.841796 -14.227048)
					(end 108.557314 -13.988542)
				)
				(xy 108.557568 -13.988542)
			)
		)
	)
	(zone
		(layers "In1.Cu" "In4.Cu")
		(hatch none 0.5)
		(connect_pads
			(clearance 0)
		)
		(min_thickness 0.25)
		(keepout
			(tracks not_allowed)
			(vias allowed)
			(pads allowed)
			(copperpour not_allowed)
			(footprints allowed)
		)
		(placement
			(enabled no)
			(sheetname "")
		)
		(fill yes
			(thermal_gap 0.5)
			(thermal_bridge_width 0.5)
			(island_removal_mode 0)
		)
		(polygon
			(pts
				(arc
					(start 98.557334 -27.33167)
					(mid 97.841816 -27.093164)
					(end 97.60331 -27.808682)
				)
				(xy 97.603056 -27.808682)
				(arc
					(start 98.602546 -29.808678)
					(mid 99.318216 -30.047616)
					(end 99.556824 -29.33192)
				)
				(xy 99.557078 -29.33192) (xy 98.557588 -27.33167)
			)
		)
	)
	(zone
		(layers "In1.Cu" "In4.Cu")
		(hatch none 0.5)
		(connect_pads
			(clearance 0)
		)
		(min_thickness 0.25)
		(keepout
			(tracks not_allowed)
			(vias allowed)
			(pads allowed)
			(copperpour not_allowed)
			(footprints allowed)
		)
		(placement
			(enabled no)
			(sheetname "")
		)
		(fill yes
			(thermal_gap 0.5)
			(thermal_bridge_width 0.5)
			(island_removal_mode 0)
		)
		(polygon
			(pts
				(arc
					(start 74.556874 -27.808936)
					(mid 74.31852 -27.093113)
					(end 73.60285 -27.33167)
				)
				(xy 73.602596 -27.33167) (xy 72.603106 -29.33192)
				(arc
					(start 72.60336 -29.33192)
					(mid 72.841866 -30.047438)
					(end 73.557384 -29.808932)
				)
				(xy 73.557638 -29.808932)
			)
		)
	)
	(zone
		(layers "In1.Cu" "In4.Cu")
		(hatch none 0.5)
		(connect_pads
			(clearance 0)
		)
		(min_thickness 0.25)
		(keepout
			(tracks not_allowed)
			(vias allowed)
			(pads allowed)
			(copperpour not_allowed)
			(footprints allowed)
		)
		(placement
			(enabled no)
			(sheetname "")
		)
		(fill yes
			(thermal_gap 0.5)
			(thermal_bridge_width 0.5)
			(island_removal_mode 0)
		)
		(polygon
			(pts
				(arc
					(start 57.556654 -11.511026)
					(mid 56.840882 -11.272774)
					(end 56.60263 -11.988546)
				)
				(xy 57.603136 -13.988542)
				(arc
					(start 57.60339 -13.988542)
					(mid 58.31901 -14.226997)
					(end 58.557414 -13.511276)
				)
			)
		)
	)
	(zone
		(layers "In1.Cu" "In4.Cu")
		(hatch none 0.5)
		(connect_pads
			(clearance 0)
		)
		(min_thickness 0.25)
		(keepout
			(tracks not_allowed)
			(vias allowed)
			(pads allowed)
			(copperpour not_allowed)
			(footprints allowed)
		)
		(placement
			(enabled no)
			(sheetname "")
		)
		(fill yes
			(thermal_gap 0.5)
			(thermal_bridge_width 0.5)
			(island_removal_mode 0)
		)
		(polygon
			(pts
				(arc
					(start 53.557424 -31.83128)
					(mid 52.841906 -31.592774)
					(end 52.6034 -32.308292)
				)
				(xy 52.603146 -32.308292)
				(arc
					(start 53.602636 -34.308288)
					(mid 54.318306 -34.547226)
					(end 54.556914 -33.83153)
				)
				(xy 54.557168 -33.83153) (xy 53.557678 -31.83128)
			)
		)
	)
	(zone
		(layers "In1.Cu" "In4.Cu")
		(hatch none 0.5)
		(connect_pads
			(clearance 0)
		)
		(min_thickness 0.25)
		(keepout
			(tracks not_allowed)
			(vias allowed)
			(pads allowed)
			(copperpour not_allowed)
			(footprints allowed)
		)
		(placement
			(enabled no)
			(sheetname "")
		)
		(fill yes
			(thermal_gap 0.5)
			(thermal_bridge_width 0.5)
			(island_removal_mode 0)
		)
		(polygon
			(pts
				(arc
					(start 81.222088 5.523992)
					(mid 80.863948 5.165852)
					(end 81.222088 4.807712)
				)
				(arc
					(start 82.237834 4.807712)
					(mid 82.596228 5.165725)
					(end 82.238088 5.523992)
				)
			)
		)
	)
	(zone
		(layers "In1.Cu" "In4.Cu")
		(hatch none 0.5)
		(connect_pads
			(clearance 0)
		)
		(min_thickness 0.25)
		(keepout
			(tracks not_allowed)
			(vias allowed)
			(pads allowed)
			(copperpour not_allowed)
			(footprints allowed)
		)
		(placement
			(enabled no)
			(sheetname "")
		)
		(fill yes
			(thermal_gap 0.5)
			(thermal_bridge_width 0.5)
			(island_removal_mode 0)
		)
		(polygon
			(pts
				(arc
					(start 97.556574 -11.988546)
					(mid 97.31822 -11.272723)
					(end 96.60255 -11.51128)
				)
				(xy 96.602296 -11.51128) (xy 95.602806 -13.51153)
				(arc
					(start 95.60306 -13.51153)
					(mid 95.841566 -14.227048)
					(end 96.557084 -13.988542)
				)
				(xy 96.557338 -13.988542)
			)
		)
	)
	(zone
		(layers "In1.Cu" "In4.Cu")
		(hatch none 0.5)
		(connect_pads
			(clearance 0)
		)
		(min_thickness 0.25)
		(keepout
			(tracks not_allowed)
			(vias allowed)
			(pads allowed)
			(copperpour not_allowed)
			(footprints allowed)
		)
		(placement
			(enabled no)
			(sheetname "")
		)
		(fill yes
			(thermal_gap 0.5)
			(thermal_bridge_width 0.5)
			(island_removal_mode 0)
		)
		(polygon
			(pts
				(arc
					(start 83.812888 5.523992)
					(mid 83.454748 5.165852)
					(end 83.812888 4.807712)
				)
				(arc
					(start 84.828634 4.807712)
					(mid 85.187028 5.165725)
					(end 84.828888 5.523992)
				)
			)
		)
	)
	(zone
		(layers "In1.Cu" "In4.Cu")
		(hatch none 0.5)
		(connect_pads
			(clearance 0)
		)
		(min_thickness 0.25)
		(keepout
			(tracks not_allowed)
			(vias allowed)
			(pads allowed)
			(copperpour not_allowed)
			(footprints allowed)
		)
		(placement
			(enabled no)
			(sheetname "")
		)
		(fill yes
			(thermal_gap 0.5)
			(thermal_bridge_width 0.5)
			(island_removal_mode 0)
		)
		(polygon
			(pts
				(arc
					(start 127.129286 4.848352)
					(mid 127.48768 5.206365)
					(end 127.12954 5.564632)
				)
				(arc
					(start 126.11354 5.564632)
					(mid 125.7554 5.206492)
					(end 126.11354 4.848352)
				)
			)
		)
	)
	(zone
		(layers "In1.Cu" "In4.Cu")
		(hatch none 0.5)
		(connect_pads
			(clearance 0)
		)
		(min_thickness 0.25)
		(keepout
			(tracks not_allowed)
			(vias allowed)
			(pads allowed)
			(copperpour not_allowed)
			(footprints allowed)
		)
		(placement
			(enabled no)
			(sheetname "")
		)
		(fill yes
			(thermal_gap 0.5)
			(thermal_bridge_width 0.5)
			(island_removal_mode 0)
		)
		(polygon
			(pts
				(arc
					(start 56.557164 -27.808936)
					(mid 56.318912 -27.093164)
					(end 55.60314 -27.331416)
				)
				(arc
					(start 54.60238 -29.331666)
					(mid 54.840632 -30.047438)
					(end 55.556404 -29.809186)
				)
				(xy 56.557164 -27.80919)
			)
		)
	)
	(zone
		(layers "In1.Cu" "In4.Cu")
		(hatch none 0.5)
		(connect_pads
			(clearance 0)
		)
		(min_thickness 0.25)
		(keepout
			(tracks not_allowed)
			(vias allowed)
			(pads allowed)
			(copperpour not_allowed)
			(footprints allowed)
		)
		(placement
			(enabled no)
			(sheetname "")
		)
		(fill yes
			(thermal_gap 0.5)
			(thermal_bridge_width 0.5)
			(island_removal_mode 0)
		)
		(polygon
			(pts
				(arc
					(start 86.403688 5.523992)
					(mid 86.045548 5.165852)
					(end 86.403688 4.807712)
				)
				(arc
					(start 87.419434 4.807712)
					(mid 87.777828 5.165725)
					(end 87.419688 5.523992)
				)
			)
		)
	)
	(zone
		(layers "In1.Cu" "In4.Cu")
		(hatch none 0.5)
		(connect_pads
			(clearance 0)
		)
		(min_thickness 0.25)
		(keepout
			(tracks not_allowed)
			(vias allowed)
			(pads allowed)
			(copperpour not_allowed)
			(footprints allowed)
		)
		(placement
			(enabled no)
			(sheetname "")
		)
		(fill yes
			(thermal_gap 0.5)
			(thermal_bridge_width 0.5)
			(island_removal_mode 0)
		)
		(polygon
			(pts
				(arc
					(start 87.668354 8.060182)
					(mid 87.310214 7.702042)
					(end 87.668354 7.343902)
				)
				(arc
					(start 88.6841 7.343902)
					(mid 89.042494 7.701915)
					(end 88.684354 8.060182)
				)
			)
		)
	)
	(zone
		(layers "In1.Cu" "In4.Cu")
		(hatch none 0.5)
		(connect_pads
			(clearance 0)
		)
		(min_thickness 0.25)
		(keepout
			(tracks not_allowed)
			(vias allowed)
			(pads allowed)
			(copperpour not_allowed)
			(footprints allowed)
		)
		(placement
			(enabled no)
			(sheetname "")
		)
		(fill yes
			(thermal_gap 0.5)
			(thermal_bridge_width 0.5)
			(island_removal_mode 0)
		)
		(polygon
			(pts
				(arc
					(start 115.439952 7.384542)
					(mid 115.798346 7.742555)
					(end 115.440206 8.100822)
				)
				(arc
					(start 114.424206 8.100822)
					(mid 114.066066 7.742682)
					(end 114.424206 7.384542)
				)
			)
		)
	)
	(zone
		(layers "In1.Cu" "In4.Cu")
		(hatch none 0.5)
		(connect_pads
			(clearance 0)
		)
		(min_thickness 0.25)
		(keepout
			(tracks not_allowed)
			(vias allowed)
			(pads allowed)
			(copperpour not_allowed)
			(footprints allowed)
		)
		(placement
			(enabled no)
			(sheetname "")
		)
		(fill yes
			(thermal_gap 0.5)
			(thermal_bridge_width 0.5)
			(island_removal_mode 0)
		)
		(polygon
			(pts
				(arc
					(start 101.557074 -32.308546)
					(mid 101.318822 -31.592774)
					(end 100.60305 -31.831026)
				)
				(arc
					(start 99.60229 -33.831276)
					(mid 99.840542 -34.547048)
					(end 100.556314 -34.308796)
				)
				(xy 101.557074 -32.3088)
			)
		)
	)
	(zone
		(layers "In1.Cu" "In4.Cu")
		(hatch none 0.5)
		(connect_pads
			(clearance 0)
		)
		(min_thickness 0.25)
		(keepout
			(tracks not_allowed)
			(vias allowed)
			(pads allowed)
			(copperpour not_allowed)
			(footprints allowed)
		)
		(placement
			(enabled no)
			(sheetname "")
		)
		(fill yes
			(thermal_gap 0.5)
			(thermal_bridge_width 0.5)
			(island_removal_mode 0)
		)
		(polygon
			(pts
				(arc
					(start 86.557104 -27.33167)
					(mid 85.841586 -27.093164)
					(end 85.60308 -27.808682)
				)
				(xy 85.602826 -27.808682)
				(arc
					(start 86.602316 -29.808678)
					(mid 87.317986 -30.047616)
					(end 87.556594 -29.33192)
				)
				(xy 87.556848 -29.33192) (xy 86.557358 -27.33167)
			)
		)
	)
	(zone
		(layers "In1.Cu" "In4.Cu")
		(hatch none 0.5)
		(connect_pads
			(clearance 0)
		)
		(min_thickness 0.25)
		(keepout
			(tracks not_allowed)
			(vias allowed)
			(pads allowed)
			(copperpour not_allowed)
			(footprints allowed)
		)
		(placement
			(enabled no)
			(sheetname "")
		)
		(fill yes
			(thermal_gap 0.5)
			(thermal_bridge_width 0.5)
			(island_removal_mode 0)
		)
		(polygon
			(pts
				(arc
					(start 52.556664 -27.808936)
					(mid 52.31831 -27.093113)
					(end 51.60264 -27.33167)
				)
				(xy 51.602386 -27.33167) (xy 50.602896 -29.33192)
				(arc
					(start 50.60315 -29.33192)
					(mid 50.841656 -30.047438)
					(end 51.557174 -29.808932)
				)
				(xy 51.557428 -29.808932)
			)
		)
	)
	(zone
		(layers "In1.Cu" "In4.Cu")
		(hatch none 0.5)
		(connect_pads
			(clearance 0)
		)
		(min_thickness 0.25)
		(keepout
			(tracks not_allowed)
			(vias allowed)
			(pads allowed)
			(copperpour not_allowed)
			(footprints allowed)
		)
		(placement
			(enabled no)
			(sheetname "")
		)
		(fill yes
			(thermal_gap 0.5)
			(thermal_bridge_width 0.5)
			(island_removal_mode 0)
		)
		(polygon
			(pts
				(arc
					(start 121.947686 4.848352)
					(mid 122.30608 5.206365)
					(end 121.94794 5.564632)
				)
				(arc
					(start 120.93194 5.564632)
					(mid 120.5738 5.206492)
					(end 120.93194 4.848352)
				)
			)
		)
	)
	(zone
		(layers "In1.Cu" "In4.Cu")
		(hatch none 0.5)
		(connect_pads
			(clearance 0)
		)
		(min_thickness 0.25)
		(keepout
			(tracks not_allowed)
			(vias allowed)
			(pads allowed)
			(copperpour not_allowed)
			(footprints allowed)
		)
		(placement
			(enabled no)
			(sheetname "")
		)
		(fill yes
			(thermal_gap 0.5)
			(thermal_bridge_width 0.5)
			(island_removal_mode 0)
		)
		(polygon
			(pts
				(arc
					(start 94.556834 -7.01167)
					(mid 93.841316 -6.773164)
					(end 93.60281 -7.488682)
				)
				(xy 93.602556 -7.488682)
				(arc
					(start 94.602046 -9.488678)
					(mid 95.317716 -9.727616)
					(end 95.556324 -9.01192)
				)
				(xy 95.556578 -9.01192) (xy 94.557088 -7.01167)
			)
		)
	)
	(zone
		(layers "In1.Cu" "In4.Cu")
		(hatch none 0.5)
		(connect_pads
			(clearance 0)
		)
		(min_thickness 0.25)
		(keepout
			(tracks not_allowed)
			(vias allowed)
			(pads allowed)
			(copperpour not_allowed)
			(footprints allowed)
		)
		(placement
			(enabled no)
			(sheetname "")
		)
		(fill yes
			(thermal_gap 0.5)
			(thermal_bridge_width 0.5)
			(island_removal_mode 0)
		)
		(polygon
			(pts
				(arc
					(start 90.259154 8.060182)
					(mid 89.901014 7.702042)
					(end 90.259154 7.343902)
				)
				(arc
					(start 91.2749 7.343902)
					(mid 91.633294 7.701915)
					(end 91.275154 8.060182)
				)
			)
		)
	)
	(zone
		(layers "In1.Cu" "In4.Cu")
		(hatch none 0.5)
		(connect_pads
			(clearance 0)
		)
		(min_thickness 0.25)
		(keepout
			(tracks not_allowed)
			(vias allowed)
			(pads allowed)
			(copperpour not_allowed)
			(footprints allowed)
		)
		(placement
			(enabled no)
			(sheetname "")
		)
		(fill yes
			(thermal_gap 0.5)
			(thermal_bridge_width 0.5)
			(island_removal_mode 0)
		)
		(polygon
			(pts
				(arc
					(start 111.584486 4.848352)
					(mid 111.94288 5.206365)
					(end 111.58474 5.564632)
				)
				(arc
					(start 110.56874 5.564632)
					(mid 110.2106 5.206492)
					(end 110.56874 4.848352)
				)
			)
		)
	)
	(zone
		(layers "In1.Cu" "In4.Cu")
		(hatch none 0.5)
		(connect_pads
			(clearance 0)
		)
		(min_thickness 0.25)
		(keepout
			(tracks not_allowed)
			(vias allowed)
			(pads allowed)
			(copperpour not_allowed)
			(footprints allowed)
		)
		(placement
			(enabled no)
			(sheetname "")
		)
		(fill yes
			(thermal_gap 0.5)
			(thermal_bridge_width 0.5)
			(island_removal_mode 0)
		)
		(polygon
			(pts
				(arc
					(start 93.557344 -32.308546)
					(mid 93.319092 -31.592774)
					(end 92.60332 -31.831026)
				)
				(arc
					(start 91.60256 -33.831276)
					(mid 91.840812 -34.547048)
					(end 92.556584 -34.308796)
				)
				(xy 93.557344 -32.3088)
			)
		)
	)
	(zone
		(layers "In1.Cu" "In4.Cu")
		(hatch none 0.5)
		(connect_pads
			(clearance 0)
		)
		(min_thickness 0.25)
		(keepout
			(tracks not_allowed)
			(vias allowed)
			(pads allowed)
			(copperpour not_allowed)
			(footprints allowed)
		)
		(placement
			(enabled no)
			(sheetname "")
		)
		(fill yes
			(thermal_gap 0.5)
			(thermal_bridge_width 0.5)
			(island_removal_mode 0)
		)
		(polygon
			(pts
				(arc
					(start 105.556304 -32.308546)
					(mid 105.31795 -31.592723)
					(end 104.60228 -31.83128)
				)
				(xy 104.602026 -31.83128) (xy 103.602536 -33.83153)
				(arc
					(start 103.60279 -33.83153)
					(mid 103.841296 -34.547048)
					(end 104.556814 -34.308542)
				)
				(xy 104.557068 -34.308542)
			)
		)
	)
	(zone
		(layers "In1.Cu" "In4.Cu")
		(hatch none 0.5)
		(connect_pads
			(clearance 0)
		)
		(min_thickness 0.25)
		(keepout
			(tracks not_allowed)
			(vias allowed)
			(pads allowed)
			(copperpour not_allowed)
			(footprints allowed)
		)
		(placement
			(enabled no)
			(sheetname "")
		)
		(fill yes
			(thermal_gap 0.5)
			(thermal_bridge_width 0.5)
			(island_removal_mode 0)
		)
		(polygon
			(pts
				(arc
					(start 57.556654 -31.831026)
					(mid 56.840882 -31.592774)
					(end 56.60263 -32.308546)
				)
				(xy 57.603136 -34.308542)
				(arc
					(start 57.60339 -34.308542)
					(mid 58.31901 -34.546997)
					(end 58.557414 -33.831276)
				)
			)
		)
	)
	(zone
		(layers "In1.Cu" "In4.Cu")
		(hatch none 0.5)
		(connect_pads
			(clearance 0)
		)
		(min_thickness 0.25)
		(keepout
			(tracks not_allowed)
			(vias allowed)
			(pads allowed)
			(copperpour not_allowed)
			(footprints allowed)
		)
		(placement
			(enabled no)
			(sheetname "")
		)
		(fill yes
			(thermal_gap 0.5)
			(thermal_bridge_width 0.5)
			(island_removal_mode 0)
		)
		(polygon
			(pts
				(arc
					(start 66.557144 -7.488936)
					(mid 66.318892 -6.773164)
					(end 65.60312 -7.011416)
				)
				(arc
					(start 64.60236 -9.011666)
					(mid 64.840612 -9.727438)
					(end 65.556384 -9.489186)
				)
				(xy 66.557144 -7.48919)
			)
		)
	)
	(zone
		(layers "In1.Cu" "In4.Cu")
		(hatch none 0.5)
		(connect_pads
			(clearance 0)
		)
		(min_thickness 0.25)
		(keepout
			(tracks not_allowed)
			(vias allowed)
			(pads allowed)
			(copperpour not_allowed)
			(footprints allowed)
		)
		(placement
			(enabled no)
			(sheetname "")
		)
		(fill yes
			(thermal_gap 0.5)
			(thermal_bridge_width 0.5)
			(island_removal_mode 0)
		)
		(polygon
			(pts
				(arc
					(start 78.557374 -27.808936)
					(mid 78.319122 -27.093164)
					(end 77.60335 -27.331416)
				)
				(arc
					(start 76.60259 -29.331666)
					(mid 76.840842 -30.047438)
					(end 77.556614 -29.809186)
				)
				(xy 78.557374 -27.80919)
			)
		)
	)
	(zone
		(layers "In1.Cu" "In4.Cu")
		(hatch none 0.5)
		(connect_pads
			(clearance 0)
		)
		(min_thickness 0.25)
		(keepout
			(tracks not_allowed)
			(vias allowed)
			(pads allowed)
			(copperpour not_allowed)
			(footprints allowed)
		)
		(placement
			(enabled no)
			(sheetname "")
		)
		(fill yes
			(thermal_gap 0.5)
			(thermal_bridge_width 0.5)
			(island_removal_mode 0)
		)
		(polygon
			(pts
				(arc
					(start 65.556384 -11.988546)
					(mid 65.31803 -11.272723)
					(end 64.60236 -11.51128)
				)
				(xy 64.602106 -11.51128) (xy 63.602616 -13.51153)
				(arc
					(start 63.60287 -13.51153)
					(mid 63.841376 -14.227048)
					(end 64.556894 -13.988542)
				)
				(xy 64.557148 -13.988542)
			)
		)
	)
	(zone
		(layers "In1.Cu" "In4.Cu")
		(hatch none 0.5)
		(connect_pads
			(clearance 0)
		)
		(min_thickness 0.25)
		(keepout
			(tracks not_allowed)
			(vias allowed)
			(pads allowed)
			(copperpour not_allowed)
			(footprints allowed)
		)
		(placement
			(enabled no)
			(sheetname "")
		)
		(fill yes
			(thermal_gap 0.5)
			(thermal_bridge_width 0.5)
			(island_removal_mode 0)
		)
		(polygon
			(pts
				(arc
					(start 66.557144 -27.808936)
					(mid 66.318892 -27.093164)
					(end 65.60312 -27.331416)
				)
				(arc
					(start 64.60236 -29.331666)
					(mid 64.840612 -30.047438)
					(end 65.556384 -29.809186)
				)
				(xy 66.557144 -27.80919)
			)
		)
	)
	(zone
		(layers "In1.Cu" "In4.Cu")
		(hatch none 0.5)
		(connect_pads
			(clearance 0)
		)
		(min_thickness 0.25)
		(keepout
			(tracks not_allowed)
			(vias allowed)
			(pads allowed)
			(copperpour not_allowed)
			(footprints allowed)
		)
		(placement
			(enabled no)
			(sheetname "")
		)
		(fill yes
			(thermal_gap 0.5)
			(thermal_bridge_width 0.5)
			(island_removal_mode 0)
		)
		(polygon
			(pts
				(arc
					(start 53.557424 -11.51128)
					(mid 52.841906 -11.272774)
					(end 52.6034 -11.988292)
				)
				(xy 52.603146 -11.988292)
				(arc
					(start 53.602636 -13.988288)
					(mid 54.318306 -14.227226)
					(end 54.556914 -13.51153)
				)
				(xy 54.557168 -13.51153) (xy 53.557678 -11.51128)
			)
		)
	)
	(zone
		(layers "In1.Cu" "In4.Cu")
		(hatch none 0.5)
		(connect_pads
			(clearance 0)
		)
		(min_thickness 0.25)
		(keepout
			(tracks not_allowed)
			(vias allowed)
			(pads allowed)
			(copperpour not_allowed)
			(footprints allowed)
		)
		(placement
			(enabled no)
			(sheetname "")
		)
		(fill yes
			(thermal_gap 0.5)
			(thermal_bridge_width 0.5)
			(island_removal_mode 0)
		)
		(polygon
			(pts
				(arc
					(start 78.631288 5.523992)
					(mid 78.273148 5.165852)
					(end 78.631288 4.807712)
				)
				(arc
					(start 79.647034 4.807712)
					(mid 80.005428 5.165725)
					(end 79.647288 5.523992)
				)
			)
		)
	)
	(zone
		(layers "In1.Cu" "In4.Cu")
		(hatch none 0.5)
		(connect_pads
			(clearance 0)
		)
		(min_thickness 0.25)
		(keepout
			(tracks not_allowed)
			(vias allowed)
			(pads allowed)
			(copperpour not_allowed)
			(footprints allowed)
		)
		(placement
			(enabled no)
			(sheetname "")
		)
		(fill yes
			(thermal_gap 0.5)
			(thermal_bridge_width 0.5)
			(island_removal_mode 0)
		)
		(polygon
			(pts
				(arc
					(start 79.895954 8.060182)
					(mid 79.537814 7.702042)
					(end 79.895954 7.343902)
				)
				(arc
					(start 80.9117 7.343902)
					(mid 81.270094 7.701915)
					(end 80.911954 8.060182)
				)
			)
		)
	)
	(zone
		(layers "In1.Cu" "In4.Cu")
		(hatch none 0.5)
		(connect_pads
			(clearance 0)
		)
		(min_thickness 0.25)
		(keepout
			(tracks not_allowed)
			(vias allowed)
			(pads allowed)
			(copperpour not_allowed)
			(footprints allowed)
		)
		(placement
			(enabled no)
			(sheetname "")
		)
		(fill yes
			(thermal_gap 0.5)
			(thermal_bridge_width 0.5)
			(island_removal_mode 0)
		)
		(polygon
			(pts
				(arc
					(start 102.556564 -27.331416)
					(mid 101.840792 -27.093164)
					(end 101.60254 -27.808936)
				)
				(xy 102.603046 -29.808932)
				(arc
					(start 102.6033 -29.808932)
					(mid 103.31892 -30.047387)
					(end 103.557324 -29.331666)
				)
			)
		)
	)
	(zone
		(layers "In1.Cu" "In4.Cu")
		(hatch none 0.5)
		(connect_pads
			(clearance 0)
		)
		(min_thickness 0.25)
		(keepout
			(tracks not_allowed)
			(vias allowed)
			(pads allowed)
			(copperpour not_allowed)
			(footprints allowed)
		)
		(placement
			(enabled no)
			(sheetname "")
		)
		(fill yes
			(thermal_gap 0.5)
			(thermal_bridge_width 0.5)
			(island_removal_mode 0)
		)
		(polygon
			(pts
				(arc
					(start 46.557184 -7.01167)
					(mid 45.841666 -6.773164)
					(end 45.60316 -7.488682)
				)
				(xy 45.602906 -7.488682)
				(arc
					(start 46.602396 -9.488678)
					(mid 47.318066 -9.727616)
					(end 47.556674 -9.01192)
				)
				(xy 47.556928 -9.01192) (xy 46.557438 -7.01167)
			)
		)
	)
	(zone
		(layers "In1.Cu" "In4.Cu")
		(hatch none 0.5)
		(connect_pads
			(clearance 0)
		)
		(min_thickness 0.25)
		(keepout
			(tracks not_allowed)
			(vias allowed)
			(pads allowed)
			(copperpour not_allowed)
			(footprints allowed)
		)
		(placement
			(enabled no)
			(sheetname "")
		)
		(fill yes
			(thermal_gap 0.5)
			(thermal_bridge_width 0.5)
			(island_removal_mode 0)
		)
		(polygon
			(pts
				(arc
					(start 113.557304 -11.988546)
					(mid 113.319052 -11.272774)
					(end 112.60328 -11.511026)
				)
				(arc
					(start 111.60252 -13.511276)
					(mid 111.840772 -14.227048)
					(end 112.556544 -13.988796)
				)
				(xy 113.557304 -11.9888)
			)
		)
	)
	(zone
		(layers "In1.Cu" "In4.Cu")
		(hatch none 0.5)
		(connect_pads
			(clearance 0)
		)
		(min_thickness 0.25)
		(keepout
			(tracks not_allowed)
			(vias allowed)
			(pads allowed)
			(copperpour not_allowed)
			(footprints allowed)
		)
		(placement
			(enabled no)
			(sheetname "")
		)
		(fill yes
			(thermal_gap 0.5)
			(thermal_bridge_width 0.5)
			(island_removal_mode 0)
		)
		(polygon
			(pts
				(arc
					(start 60.556394 -7.488936)
					(mid 60.31804 -6.773113)
					(end 59.60237 -7.01167)
				)
				(xy 59.602116 -7.01167) (xy 58.602626 -9.01192)
				(arc
					(start 58.60288 -9.01192)
					(mid 58.841386 -9.727438)
					(end 59.556904 -9.488932)
				)
				(xy 59.557158 -9.488932)
			)
		)
	)
	(zone
		(layers "In1.Cu" "In4.Cu")
		(hatch none 0.5)
		(connect_pads
			(clearance 0)
		)
		(min_thickness 0.25)
		(keepout
			(tracks not_allowed)
			(vias allowed)
			(pads allowed)
			(copperpour not_allowed)
			(footprints allowed)
		)
		(placement
			(enabled no)
			(sheetname "")
		)
		(fill yes
			(thermal_gap 0.5)
			(thermal_bridge_width 0.5)
			(island_removal_mode 0)
		)
		(polygon
			(pts
				(arc
					(start 79.556864 -31.83128)
					(mid 78.841346 -31.592774)
					(end 78.60284 -32.308292)
				)
				(xy 78.602586 -32.308292)
				(arc
					(start 79.602076 -34.308288)
					(mid 80.317746 -34.547226)
					(end 80.556354 -33.83153)
				)
				(xy 80.556608 -33.83153) (xy 79.557118 -31.83128)
			)
		)
	)
	(zone
		(layers "In1.Cu" "In4.Cu")
		(hatch none 0.5)
		(connect_pads
			(clearance 0)
		)
		(min_thickness 0.25)
		(keepout
			(tracks not_allowed)
			(vias allowed)
			(pads allowed)
			(copperpour not_allowed)
			(footprints allowed)
		)
		(placement
			(enabled no)
			(sheetname "")
		)
		(fill yes
			(thermal_gap 0.5)
			(thermal_bridge_width 0.5)
			(island_removal_mode 0)
		)
		(polygon
			(pts
				(arc
					(start 45.556424 -11.511026)
					(mid 44.840652 -11.272774)
					(end 44.6024 -11.988546)
				)
				(xy 45.602906 -13.988542)
				(arc
					(start 45.60316 -13.988542)
					(mid 46.31878 -14.226997)
					(end 46.557184 -13.511276)
				)
			)
		)
	)
	(zone
		(layers "In1.Cu" "In4.Cu")
		(hatch none 0.5)
		(connect_pads
			(clearance 0)
		)
		(min_thickness 0.25)
		(keepout
			(tracks not_allowed)
			(vias allowed)
			(pads allowed)
			(copperpour not_allowed)
			(footprints allowed)
		)
		(placement
			(enabled no)
			(sheetname "")
		)
		(fill yes
			(thermal_gap 0.5)
			(thermal_bridge_width 0.5)
			(island_removal_mode 0)
		)
		(polygon
			(pts
				(arc
					(start 110.556294 -7.011416)
					(mid 109.840522 -6.773164)
					(end 109.60227 -7.488936)
				)
				(xy 110.602776 -9.488932)
				(arc
					(start 110.60303 -9.488932)
					(mid 111.31865 -9.727387)
					(end 111.557054 -9.011666)
				)
			)
		)
	)
	(zone
		(layers "In1.Cu" "In4.Cu")
		(hatch none 0.5)
		(connect_pads
			(clearance 0)
		)
		(min_thickness 0.25)
		(keepout
			(tracks not_allowed)
			(vias allowed)
			(pads allowed)
			(copperpour not_allowed)
			(footprints allowed)
		)
		(placement
			(enabled no)
			(sheetname "")
		)
		(fill yes
			(thermal_gap 0.5)
			(thermal_bridge_width 0.5)
			(island_removal_mode 0)
		)
		(polygon
			(pts
				(arc
					(start 49.556924 -11.988546)
					(mid 49.31857 -11.272723)
					(end 48.6029 -11.51128)
				)
				(xy 48.602646 -11.51128) (xy 47.603156 -13.51153)
				(arc
					(start 47.60341 -13.51153)
					(mid 47.841916 -14.227048)
					(end 48.557434 -13.988542)
				)
				(xy 48.557688 -13.988542)
			)
		)
	)
	(zone
		(layers "In1.Cu" "In4.Cu")
		(hatch none 0.5)
		(connect_pads
			(clearance 0)
		)
		(min_thickness 0.25)
		(keepout
			(tracks not_allowed)
			(vias allowed)
			(pads allowed)
			(copperpour not_allowed)
			(footprints allowed)
		)
		(placement
			(enabled no)
			(sheetname "")
		)
		(fill yes
			(thermal_gap 0.5)
			(thermal_bridge_width 0.5)
			(island_removal_mode 0)
		)
		(polygon
			(pts
				(arc
					(start 65.556384 -32.308546)
					(mid 65.31803 -31.592723)
					(end 64.60236 -31.83128)
				)
				(xy 64.602106 -31.83128) (xy 63.602616 -33.83153)
				(arc
					(start 63.60287 -33.83153)
					(mid 63.841376 -34.547048)
					(end 64.556894 -34.308542)
				)
				(xy 64.557148 -34.308542)
			)
		)
	)
	(zone
		(layers "In1.Cu" "In4.Cu")
		(hatch none 0.5)
		(connect_pads
			(clearance 0)
		)
		(min_thickness 0.25)
		(keepout
			(tracks not_allowed)
			(vias allowed)
			(pads allowed)
			(copperpour not_allowed)
			(footprints allowed)
		)
		(placement
			(enabled no)
			(sheetname "")
		)
		(fill yes
			(thermal_gap 0.5)
			(thermal_bridge_width 0.5)
			(island_removal_mode 0)
		)
		(polygon
			(pts
				(arc
					(start 67.556634 -11.511026)
					(mid 66.840862 -11.272774)
					(end 66.60261 -11.988546)
				)
				(xy 67.603116 -13.988542)
				(arc
					(start 67.60337 -13.988542)
					(mid 68.31899 -14.226997)
					(end 68.557394 -13.511276)
				)
			)
		)
	)
	(zone
		(layers "In1.Cu" "In4.Cu")
		(hatch none 0.5)
		(connect_pads
			(clearance 0)
		)
		(min_thickness 0.25)
		(keepout
			(tracks not_allowed)
			(vias allowed)
			(pads allowed)
			(copperpour not_allowed)
			(footprints allowed)
		)
		(placement
			(enabled no)
			(sheetname "")
		)
		(fill yes
			(thermal_gap 0.5)
			(thermal_bridge_width 0.5)
			(island_removal_mode 0)
		)
		(polygon
			(pts
				(arc
					(start 61.557154 -11.51128)
					(mid 60.841636 -11.272774)
					(end 60.60313 -11.988292)
				)
				(xy 60.602876 -11.988292)
				(arc
					(start 61.602366 -13.988288)
					(mid 62.318036 -14.227226)
					(end 62.556644 -13.51153)
				)
				(xy 62.556898 -13.51153) (xy 61.557408 -11.51128)
			)
		)
	)
	(zone
		(layers "In1.Cu" "In4.Cu")
		(hatch none 0.5)
		(connect_pads
			(clearance 0)
		)
		(min_thickness 0.25)
		(keepout
			(tracks not_allowed)
			(vias allowed)
			(pads allowed)
			(copperpour not_allowed)
			(footprints allowed)
		)
		(placement
			(enabled no)
			(sheetname "")
		)
		(fill yes
			(thermal_gap 0.5)
			(thermal_bridge_width 0.5)
			(island_removal_mode 0)
		)
		(polygon
			(pts
				(arc
					(start 119.356886 4.848352)
					(mid 119.71528 5.206365)
					(end 119.35714 5.564632)
				)
				(arc
					(start 118.34114 5.564632)
					(mid 117.983 5.206492)
					(end 118.34114 4.848352)
				)
			)
		)
	)
	(zone
		(layers "In1.Cu" "In4.Cu")
		(hatch none 0.5)
		(connect_pads
			(clearance 0)
		)
		(min_thickness 0.25)
		(keepout
			(tracks not_allowed)
			(vias allowed)
			(pads allowed)
			(copperpour not_allowed)
			(footprints allowed)
		)
		(placement
			(enabled no)
			(sheetname "")
		)
		(fill yes
			(thermal_gap 0.5)
			(thermal_bridge_width 0.5)
			(island_removal_mode 0)
		)
		(polygon
			(pts
				(arc
					(start 79.556864 -11.51128)
					(mid 78.841346 -11.272774)
					(end 78.60284 -11.988292)
				)
				(xy 78.602586 -11.988292)
				(arc
					(start 79.602076 -13.988288)
					(mid 80.317746 -14.227226)
					(end 80.556354 -13.51153)
				)
				(xy 80.556608 -13.51153) (xy 79.557118 -11.51128)
			)
		)
	)
	(zone
		(layers "In1.Cu" "In4.Cu")
		(hatch none 0.5)
		(connect_pads
			(clearance 0)
		)
		(min_thickness 0.25)
		(keepout
			(tracks not_allowed)
			(vias allowed)
			(pads allowed)
			(copperpour not_allowed)
			(footprints allowed)
		)
		(placement
			(enabled no)
			(sheetname "")
		)
		(fill yes
			(thermal_gap 0.5)
			(thermal_bridge_width 0.5)
			(island_removal_mode 0)
		)
		(polygon
			(pts
				(arc
					(start 120.621552 7.384542)
					(mid 120.979946 7.742555)
					(end 120.621806 8.100822)
				)
				(arc
					(start 119.605806 8.100822)
					(mid 119.247666 7.742682)
					(end 119.605806 7.384542)
				)
			)
		)
	)
	(zone
		(layers "In1.Cu" "In4.Cu")
		(hatch none 0.5)
		(connect_pads
			(clearance 0)
		)
		(min_thickness 0.25)
		(keepout
			(tracks not_allowed)
			(vias allowed)
			(pads allowed)
			(copperpour not_allowed)
			(footprints allowed)
		)
		(placement
			(enabled no)
			(sheetname "")
		)
		(fill yes
			(thermal_gap 0.5)
			(thermal_bridge_width 0.5)
			(island_removal_mode 0)
		)
		(polygon
			(pts
				(arc
					(start 45.556424 -31.831026)
					(mid 44.840652 -31.592774)
					(end 44.6024 -32.308546)
				)
				(xy 45.602906 -34.308542)
				(arc
					(start 45.60316 -34.308542)
					(mid 46.31878 -34.546997)
					(end 46.557184 -33.831276)
				)
			)
		)
	)
	(zone
		(layers "In1.Cu" "In4.Cu")
		(hatch none 0.5)
		(connect_pads
			(clearance 0)
		)
		(min_thickness 0.25)
		(keepout
			(tracks not_allowed)
			(vias allowed)
			(pads allowed)
			(copperpour not_allowed)
			(footprints allowed)
		)
		(placement
			(enabled no)
			(sheetname "")
		)
		(fill yes
			(thermal_gap 0.5)
			(thermal_bridge_width 0.5)
			(island_removal_mode 0)
		)
		(polygon
			(pts
				(arc
					(start 109.556804 -32.308546)
					(mid 109.31845 -31.592723)
					(end 108.60278 -31.83128)
				)
				(xy 108.602526 -31.83128) (xy 107.603036 -33.83153)
				(arc
					(start 107.60329 -33.83153)
					(mid 107.841796 -34.547048)
					(end 108.557314 -34.308542)
				)
				(xy 108.557568 -34.308542)
			)
		)
	)
	(zone
		(layers "In1.Cu" "In4.Cu")
		(hatch none 0.5)
		(connect_pads
			(clearance 0)
		)
		(min_thickness 0.25)
		(keepout
			(tracks not_allowed)
			(vias allowed)
			(pads allowed)
			(copperpour not_allowed)
			(footprints allowed)
		)
		(placement
			(enabled no)
			(sheetname "")
		)
		(fill yes
			(thermal_gap 0.5)
			(thermal_bridge_width 0.5)
			(island_removal_mode 0)
		)
		(polygon
			(pts
				(arc
					(start 114.175286 4.848352)
					(mid 114.53368 5.206365)
					(end 114.17554 5.564632)
				)
				(arc
					(start 113.15954 5.564632)
					(mid 112.8014 5.206492)
					(end 113.15954 4.848352)
				)
			)
		)
	)
	(zone
		(layers "In1.Cu" "In4.Cu")
		(hatch none 0.5)
		(connect_pads
			(clearance 0)
		)
		(min_thickness 0.25)
		(keepout
			(tracks not_allowed)
			(vias allowed)
			(pads allowed)
			(copperpour not_allowed)
			(footprints allowed)
		)
		(placement
			(enabled no)
			(sheetname "")
		)
		(fill yes
			(thermal_gap 0.5)
			(thermal_bridge_width 0.5)
			(island_removal_mode 0)
		)
		(polygon
			(pts
				(arc
					(start 75.556364 -11.511026)
					(mid 74.840592 -11.272774)
					(end 74.60234 -11.988546)
				)
				(xy 75.602846 -13.988542)
				(arc
					(start 75.6031 -13.988542)
					(mid 76.31872 -14.226997)
					(end 76.557124 -13.511276)
				)
			)
		)
	)
	(zone
		(layers "In1.Cu" "In4.Cu")
		(hatch none 0.5)
		(connect_pads
			(clearance 0)
		)
		(min_thickness 0.25)
		(keepout
			(tracks not_allowed)
			(vias allowed)
			(pads allowed)
			(copperpour not_allowed)
			(footprints allowed)
		)
		(placement
			(enabled no)
			(sheetname "")
		)
		(fill yes
			(thermal_gap 0.5)
			(thermal_bridge_width 0.5)
			(island_removal_mode 0)
		)
		(polygon
			(pts
				(arc
					(start 94.556834 -27.33167)
					(mid 93.841316 -27.093164)
					(end 93.60281 -27.808682)
				)
				(xy 93.602556 -27.808682)
				(arc
					(start 94.602046 -29.808678)
					(mid 95.317716 -30.047616)
					(end 95.556324 -29.33192)
				)
				(xy 95.556578 -29.33192) (xy 94.557088 -27.33167)
			)
		)
	)
	(zone
		(layers "In1.Cu" "In4.Cu")
		(hatch none 0.5)
		(connect_pads
			(clearance 0)
		)
		(min_thickness 0.25)
		(keepout
			(tracks not_allowed)
			(vias allowed)
			(pads allowed)
			(copperpour not_allowed)
			(footprints allowed)
		)
		(placement
			(enabled no)
			(sheetname "")
		)
		(fill yes
			(thermal_gap 0.5)
			(thermal_bridge_width 0.5)
			(island_removal_mode 0)
		)
		(polygon
			(pts
				(arc
					(start 74.556874 -7.488936)
					(mid 74.31852 -6.773113)
					(end 73.60285 -7.01167)
				)
				(xy 73.602596 -7.01167) (xy 72.603106 -9.01192)
				(arc
					(start 72.60336 -9.01192)
					(mid 72.841866 -9.727438)
					(end 73.557384 -9.488932)
				)
				(xy 73.557638 -9.488932)
			)
		)
	)
	(zone
		(layers "In1.Cu" "In4.Cu")
		(hatch none 0.5)
		(connect_pads
			(clearance 0)
		)
		(min_thickness 0.25)
		(keepout
			(tracks not_allowed)
			(vias allowed)
			(pads allowed)
			(copperpour not_allowed)
			(footprints allowed)
		)
		(placement
			(enabled no)
			(sheetname "")
		)
		(fill yes
			(thermal_gap 0.5)
			(thermal_bridge_width 0.5)
			(island_removal_mode 0)
		)
		(polygon
			(pts
				(arc
					(start 60.556394 -27.808936)
					(mid 60.31804 -27.093113)
					(end 59.60237 -27.33167)
				)
				(xy 59.602116 -27.33167) (xy 58.602626 -29.33192)
				(arc
					(start 58.60288 -29.33192)
					(mid 58.841386 -30.047438)
					(end 59.556904 -29.808932)
				)
				(xy 59.557158 -29.808932)
			)
		)
	)
	(zone
		(layers "In1.Cu" "In4.Cu")
		(hatch none 0.5)
		(connect_pads
			(clearance 0)
		)
		(min_thickness 0.25)
		(keepout
			(tracks not_allowed)
			(vias allowed)
			(pads allowed)
			(copperpour not_allowed)
			(footprints allowed)
		)
		(placement
			(enabled no)
			(sheetname "")
		)
		(fill yes
			(thermal_gap 0.5)
			(thermal_bridge_width 0.5)
			(island_removal_mode 0)
		)
		(polygon
			(pts
				(arc
					(start 112.849152 7.384542)
					(mid 113.207546 7.742555)
					(end 112.849406 8.100822)
				)
				(arc
					(start 111.833406 8.100822)
					(mid 111.475266 7.742682)
					(end 111.833406 7.384542)
				)
			)
		)
	)
	(zone
		(layers "In1.Cu" "In4.Cu")
		(hatch none 0.5)
		(connect_pads
			(clearance 0)
		)
		(min_thickness 0.25)
		(keepout
			(tracks not_allowed)
			(vias allowed)
			(pads allowed)
			(copperpour not_allowed)
			(footprints allowed)
		)
		(placement
			(enabled no)
			(sheetname "")
		)
		(fill yes
			(thermal_gap 0.5)
			(thermal_bridge_width 0.5)
			(island_removal_mode 0)
		)
		(polygon
			(pts
				(arc
					(start 86.557104 -7.01167)
					(mid 85.841586 -6.773164)
					(end 85.60308 -7.488682)
				)
				(xy 85.602826 -7.488682)
				(arc
					(start 86.602316 -9.488678)
					(mid 87.317986 -9.727616)
					(end 87.556594 -9.01192)
				)
				(xy 87.556848 -9.01192) (xy 86.557358 -7.01167)
			)
		)
	)
	(zone
		(layers "In1.Cu" "In4.Cu")
		(hatch none 0.5)
		(connect_pads
			(clearance 0)
		)
		(min_thickness 0.25)
		(keepout
			(tracks not_allowed)
			(vias allowed)
			(pads allowed)
			(copperpour not_allowed)
			(footprints allowed)
		)
		(placement
			(enabled no)
			(sheetname "")
		)
		(fill yes
			(thermal_gap 0.5)
			(thermal_bridge_width 0.5)
			(island_removal_mode 0)
		)
		(polygon
			(pts
				(arc
					(start 71.557134 -31.83128)
					(mid 70.841616 -31.592774)
					(end 70.60311 -32.308292)
				)
				(xy 70.602856 -32.308292)
				(arc
					(start 71.602346 -34.308288)
					(mid 72.318016 -34.547226)
					(end 72.556624 -33.83153)
				)
				(xy 72.556878 -33.83153) (xy 71.557388 -31.83128)
			)
		)
	)
	(zone
		(layers "In1.Cu" "In4.Cu")
		(hatch none 0.5)
		(connect_pads
			(clearance 0)
		)
		(min_thickness 0.25)
		(keepout
			(tracks not_allowed)
			(vias allowed)
			(pads allowed)
			(copperpour not_allowed)
			(footprints allowed)
		)
		(placement
			(enabled no)
			(sheetname "")
		)
		(fill yes
			(thermal_gap 0.5)
			(thermal_bridge_width 0.5)
			(island_removal_mode 0)
		)
		(polygon
			(pts
				(arc
					(start 98.557334 -7.01167)
					(mid 97.841816 -6.773164)
					(end 97.60331 -7.488682)
				)
				(xy 97.603056 -7.488682)
				(arc
					(start 98.602546 -9.488678)
					(mid 99.318216 -9.727616)
					(end 99.556824 -9.01192)
				)
				(xy 99.557078 -9.01192) (xy 98.557588 -7.01167)
			)
		)
	)
	(zone
		(layers "In1.Cu" "In4.Cu")
		(hatch none 0.5)
		(connect_pads
			(clearance 0)
		)
		(min_thickness 0.25)
		(keepout
			(tracks not_allowed)
			(vias allowed)
			(pads allowed)
			(copperpour not_allowed)
			(footprints allowed)
		)
		(placement
			(enabled no)
			(sheetname "")
		)
		(fill yes
			(thermal_gap 0.5)
			(thermal_bridge_width 0.5)
			(island_removal_mode 0)
		)
		(polygon
			(pts
				(arc
					(start 124.78766 8.100822)
					(mid 124.429266 7.742809)
					(end 124.787406 7.384542)
				)
				(arc
					(start 125.803406 7.384542)
					(mid 126.161546 7.742682)
					(end 125.803406 8.100822)
				)
			)
		)
	)
	(zone
		(layers "In1.Cu" "In4.Cu")
		(hatch none 0.5)
		(connect_pads
			(clearance 0)
		)
		(min_thickness 0.25)
		(keepout
			(tracks not_allowed)
			(vias allowed)
			(pads allowed)
			(copperpour not_allowed)
			(footprints allowed)
		)
		(placement
			(enabled no)
			(sheetname "")
		)
		(fill yes
			(thermal_gap 0.5)
			(thermal_bridge_width 0.5)
			(island_removal_mode 0)
		)
		(polygon
			(pts
				(arc
					(start 110.556294 -27.331416)
					(mid 109.840522 -27.093164)
					(end 109.60227 -27.808936)
				)
				(xy 110.602776 -29.808932)
				(arc
					(start 110.60303 -29.808932)
					(mid 111.31865 -30.047387)
					(end 111.557054 -29.331666)
				)
			)
		)
	)
	(zone
		(layers "In1.Cu" "In4.Cu")
		(hatch none 0.5)
		(connect_pads
			(clearance 0)
		)
		(min_thickness 0.25)
		(keepout
			(tracks not_allowed)
			(vias allowed)
			(pads allowed)
			(copperpour not_allowed)
			(footprints allowed)
		)
		(placement
			(enabled no)
			(sheetname "")
		)
		(fill yes
			(thermal_gap 0.5)
			(thermal_bridge_width 0.5)
			(island_removal_mode 0)
		)
		(polygon
			(pts
				(arc
					(start 82.486754 8.060182)
					(mid 82.128614 7.702042)
					(end 82.486754 7.343902)
				)
				(arc
					(start 83.5025 7.343902)
					(mid 83.860894 7.701915)
					(end 83.502754 8.060182)
				)
			)
		)
	)
	(zone
		(layers "In1.Cu" "In4.Cu")
		(hatch none 0.5)
		(connect_pads
			(clearance 0)
		)
		(min_thickness 0.25)
		(keepout
			(tracks not_allowed)
			(vias allowed)
			(pads allowed)
			(copperpour not_allowed)
			(footprints allowed)
		)
		(placement
			(enabled no)
			(sheetname "")
		)
		(fill yes
			(thermal_gap 0.5)
			(thermal_bridge_width 0.5)
			(island_removal_mode 0)
		)
		(polygon
			(pts
				(arc
					(start 85.556344 -32.308546)
					(mid 85.31799 -31.592723)
					(end 84.60232 -31.83128)
				)
				(xy 84.602066 -31.83128) (xy 83.602576 -33.83153)
				(arc
					(start 83.60283 -33.83153)
					(mid 83.841336 -34.547048)
					(end 84.556854 -34.308542)
				)
				(xy 84.557108 -34.308542)
			)
		)
	)
	(zone
		(layers "In1.Cu" "In4.Cu")
		(hatch none 0.5)
		(connect_pads
			(clearance 0)
		)
		(min_thickness 0.25)
		(keepout
			(tracks not_allowed)
			(vias allowed)
			(pads allowed)
			(copperpour not_allowed)
			(footprints allowed)
		)
		(placement
			(enabled no)
			(sheetname "")
		)
		(fill yes
			(thermal_gap 0.5)
			(thermal_bridge_width 0.5)
			(island_removal_mode 0)
		)
		(polygon
			(pts
				(arc
					(start 89.556844 -32.308546)
					(mid 89.31849 -31.592723)
					(end 88.60282 -31.83128)
				)
				(xy 88.602566 -31.83128) (xy 87.603076 -33.83153)
				(arc
					(start 87.60333 -33.83153)
					(mid 87.841836 -34.547048)
					(end 88.557354 -34.308542)
				)
				(xy 88.557608 -34.308542)
			)
		)
	)
	(zone
		(layers "In1.Cu" "In4.Cu")
		(hatch none 0.5)
		(connect_pads
			(clearance 0)
		)
		(min_thickness 0.25)
		(keepout
			(tracks not_allowed)
			(vias allowed)
			(pads allowed)
			(copperpour not_allowed)
			(footprints allowed)
		)
		(placement
			(enabled no)
			(sheetname "")
		)
		(fill yes
			(thermal_gap 0.5)
			(thermal_bridge_width 0.5)
			(island_removal_mode 0)
		)
		(polygon
			(pts
				(arc
					(start 128.393952 7.384542)
					(mid 128.752346 7.742555)
					(end 128.394206 8.100822)
				)
				(arc
					(start 127.378206 8.100822)
					(mid 127.020066 7.742682)
					(end 127.378206 7.384542)
				)
			)
		)
	)
	(zone
		(layers "In1.Cu" "In4.Cu")
		(hatch none 0.5)
		(connect_pads
			(clearance 0)
		)
		(min_thickness 0.25)
		(keepout
			(tracks not_allowed)
			(vias allowed)
			(pads allowed)
			(copperpour not_allowed)
			(footprints allowed)
		)
		(placement
			(enabled no)
			(sheetname "")
		)
		(fill yes
			(thermal_gap 0.5)
			(thermal_bridge_width 0.5)
			(island_removal_mode 0)
		)
		(polygon
			(pts
				(arc
					(start 70.556374 -27.808936)
					(mid 70.31802 -27.093113)
					(end 69.60235 -27.33167)
				)
				(xy 69.602096 -27.33167) (xy 68.602606 -29.33192)
				(arc
					(start 68.60286 -29.33192)
					(mid 68.841366 -30.047438)
					(end 69.556884 -29.808932)
				)
				(xy 69.557138 -29.808932)
			)
		)
	)
	(zone
		(layers "In1.Cu" "In4.Cu")
		(hatch none 0.5)
		(connect_pads
			(clearance 0)
		)
		(min_thickness 0.25)
		(keepout
			(tracks not_allowed)
			(vias allowed)
			(pads allowed)
			(copperpour not_allowed)
			(footprints allowed)
		)
		(placement
			(enabled no)
			(sheetname "")
		)
		(fill yes
			(thermal_gap 0.5)
			(thermal_bridge_width 0.5)
			(island_removal_mode 0)
		)
		(polygon
			(pts
				(arc
					(start 124.538486 4.848352)
					(mid 124.89688 5.206365)
					(end 124.53874 5.564632)
				)
				(arc
					(start 123.52274 5.564632)
					(mid 123.1646 5.206492)
					(end 123.52274 4.848352)
				)
			)
		)
	)
	(zone
		(layers "In1.Cu" "In4.Cu")
		(hatch none 0.5)
		(connect_pads
			(clearance 0)
		)
		(min_thickness 0.25)
		(keepout
			(tracks not_allowed)
			(vias allowed)
			(pads allowed)
			(copperpour not_allowed)
			(footprints allowed)
		)
		(placement
			(enabled no)
			(sheetname "")
		)
		(fill yes
			(thermal_gap 0.5)
			(thermal_bridge_width 0.5)
			(island_removal_mode 0)
		)
		(polygon
			(pts
				(arc
					(start 97.556574 -32.308546)
					(mid 97.31822 -31.592723)
					(end 96.60255 -31.83128)
				)
				(xy 96.602296 -31.83128) (xy 95.602806 -33.83153)
				(arc
					(start 95.60306 -33.83153)
					(mid 95.841566 -34.547048)
					(end 96.557084 -34.308542)
				)
				(xy 96.557338 -34.308542)
			)
		)
	)
	(zone
		(layers "In1.Cu" "In4.Cu")
		(hatch none 0.5)
		(connect_pads
			(clearance 0)
		)
		(min_thickness 0.25)
		(keepout
			(tracks not_allowed)
			(vias allowed)
			(pads allowed)
			(copperpour not_allowed)
			(footprints allowed)
		)
		(placement
			(enabled no)
			(sheetname "")
		)
		(fill yes
			(thermal_gap 0.5)
			(thermal_bridge_width 0.5)
			(island_removal_mode 0)
		)
		(polygon
			(pts
				(arc
					(start 85.556344 -11.988546)
					(mid 85.31799 -11.272723)
					(end 84.60232 -11.51128)
				)
				(xy 84.602066 -11.51128) (xy 83.602576 -13.51153)
				(arc
					(start 83.60283 -13.51153)
					(mid 83.841336 -14.227048)
					(end 84.556854 -13.988542)
				)
				(xy 84.557108 -13.988542)
			)
		)
	)
	(zone
		(layers "In1.Cu" "In4.Cu")
		(hatch none 0.5)
		(connect_pads
			(clearance 0)
		)
		(min_thickness 0.25)
		(keepout
			(tracks not_allowed)
			(vias allowed)
			(pads allowed)
			(copperpour not_allowed)
			(footprints allowed)
		)
		(placement
			(enabled no)
			(sheetname "")
		)
		(fill yes
			(thermal_gap 0.5)
			(thermal_bridge_width 0.5)
			(island_removal_mode 0)
		)
		(polygon
			(pts
				(arc
					(start 82.556604 -7.011416)
					(mid 81.840832 -6.773164)
					(end 81.60258 -7.488936)
				)
				(xy 82.603086 -9.488932)
				(arc
					(start 82.60334 -9.488932)
					(mid 83.31896 -9.727387)
					(end 83.557364 -9.011666)
				)
			)
		)
	)
	(zone
		(layers "In1.Cu" "In4.Cu")
		(hatch none 0.5)
		(connect_pads
			(clearance 0)
		)
		(min_thickness 0.25)
		(keepout
			(tracks not_allowed)
			(vias allowed)
			(pads allowed)
			(copperpour not_allowed)
			(footprints allowed)
		)
		(placement
			(enabled no)
			(sheetname "")
		)
		(fill yes
			(thermal_gap 0.5)
			(thermal_bridge_width 0.5)
			(island_removal_mode 0)
		)
		(polygon
			(pts
				(arc
					(start 71.557134 -11.51128)
					(mid 70.841616 -11.272774)
					(end 70.60311 -11.988292)
				)
				(xy 70.602856 -11.988292)
				(arc
					(start 71.602346 -13.988288)
					(mid 72.318016 -14.227226)
					(end 72.556624 -13.51153)
				)
				(xy 72.556878 -13.51153) (xy 71.557388 -11.51128)
			)
		)
	)
	(zone
		(layers "In1.Cu" "In4.Cu")
		(hatch none 0.5)
		(connect_pads
			(clearance 0)
		)
		(min_thickness 0.25)
		(keepout
			(tracks not_allowed)
			(vias allowed)
			(pads allowed)
			(copperpour not_allowed)
			(footprints allowed)
		)
		(placement
			(enabled no)
			(sheetname "")
		)
		(fill yes
			(thermal_gap 0.5)
			(thermal_bridge_width 0.5)
			(island_removal_mode 0)
		)
		(polygon
			(pts
				(arc
					(start 49.556924 -32.308546)
					(mid 49.31857 -31.592723)
					(end 48.6029 -31.83128)
				)
				(xy 48.602646 -31.83128) (xy 47.603156 -33.83153)
				(arc
					(start 47.60341 -33.83153)
					(mid 47.841916 -34.547048)
					(end 48.557434 -34.308542)
				)
				(xy 48.557688 -34.308542)
			)
		)
	)
	(zone
		(layers "In1.Cu" "In4.Cu")
		(hatch none 0.5)
		(connect_pads
			(clearance 0)
		)
		(min_thickness 0.25)
		(keepout
			(tracks not_allowed)
			(vias allowed)
			(pads allowed)
			(copperpour not_allowed)
			(footprints allowed)
		)
		(placement
			(enabled no)
			(sheetname "")
		)
		(fill yes
			(thermal_gap 0.5)
			(thermal_bridge_width 0.5)
			(island_removal_mode 0)
		)
		(polygon
			(pts
				(arc
					(start 129.720086 4.848352)
					(mid 130.07848 5.206365)
					(end 129.72034 5.564632)
				)
				(arc
					(start 128.70434 5.564632)
					(mid 128.3462 5.206492)
					(end 128.70434 4.848352)
				)
			)
		)
	)
	(zone
		(layers "In1.Cu" "In4.Cu")
		(hatch none 0.5)
		(connect_pads
			(clearance 0)
		)
		(min_thickness 0.25)
		(keepout
			(tracks not_allowed)
			(vias allowed)
			(pads allowed)
			(copperpour not_allowed)
			(footprints allowed)
		)
		(placement
			(enabled no)
			(sheetname "")
		)
		(fill yes
			(thermal_gap 0.5)
			(thermal_bridge_width 0.5)
			(island_removal_mode 0)
		)
		(polygon
			(pts
				(arc
					(start 88.994488 5.523992)
					(mid 88.636348 5.165852)
					(end 88.994488 4.807712)
				)
				(arc
					(start 90.010234 4.807712)
					(mid 90.368628 5.165725)
					(end 90.010488 5.523992)
				)
			)
		)
	)
	(zone
		(layers "In1.Cu" "In4.Cu")
		(hatch none 0.5)
		(connect_pads
			(clearance 0)
		)
		(min_thickness 0.25)
		(keepout
			(tracks not_allowed)
			(vias allowed)
			(pads allowed)
			(copperpour not_allowed)
			(footprints allowed)
		)
		(placement
			(enabled no)
			(sheetname "")
		)
		(fill yes
			(thermal_gap 0.5)
			(thermal_bridge_width 0.5)
			(island_removal_mode 0)
		)
		(polygon
			(pts
				(arc
					(start 77.305154 8.060182)
					(mid 76.947014 7.702042)
					(end 77.305154 7.343902)
				)
				(arc
					(start 78.3209 7.343902)
					(mid 78.679294 7.701915)
					(end 78.321154 8.060182)
				)
			)
		)
	)
	(zone
		(layers "In1.Cu" "In4.Cu")
		(hatch none 0.5)
		(connect_pads
			(clearance 0)
		)
		(min_thickness 0.25)
		(keepout
			(tracks not_allowed)
			(vias allowed)
			(pads allowed)
			(copperpour not_allowed)
			(footprints allowed)
		)
		(placement
			(enabled no)
			(sheetname "")
		)
		(fill yes
			(thermal_gap 0.5)
			(thermal_bridge_width 0.5)
			(island_removal_mode 0)
		)
		(polygon
			(pts
				(arc
					(start 102.556564 -7.011416)
					(mid 101.840792 -6.773164)
					(end 101.60254 -7.488936)
				)
				(xy 102.603046 -9.488932)
				(arc
					(start 102.6033 -9.488932)
					(mid 103.31892 -9.727387)
					(end 103.557324 -9.011666)
				)
			)
		)
	)
	(zone
		(layers "In1.Cu" "In4.Cu")
		(hatch none 0.5)
		(connect_pads
			(clearance 0)
		)
		(min_thickness 0.25)
		(keepout
			(tracks not_allowed)
			(vias allowed)
			(pads allowed)
			(copperpour not_allowed)
			(footprints allowed)
		)
		(placement
			(enabled no)
			(sheetname "")
		)
		(fill yes
			(thermal_gap 0.5)
			(thermal_bridge_width 0.5)
			(island_removal_mode 0)
		)
		(polygon
			(pts
				(arc
					(start 125.639576 -33.304226)
					(mid 125.078236 -33.865566)
					(end 125.639576 -34.426906)
				)
				(arc
					(start 126.51105 -34.426906)
					(mid 127.072644 -33.865693)
					(end 126.511304 -33.304226)
				)
			)
		)
	)
	(zone
		(net "P12V")
		(layer "In2.Cu")
		(hatch none 0.5)
		(connect_pads
			(clearance 0.5)
		)
		(min_thickness 0.25)
		(fill yes
			(thermal_gap 0.5)
			(thermal_bridge_width 0.5)
			(island_removal_mode 0)
		)
		(polygon
			(pts
				(xy 18.7325 9.5885) (xy 19.1516 9.1694) (xy 19.1516 -1.143) (xy 14.732 -5.5626) (xy 14.732 -11.557)
				(xy 15.7226 -12.5476) (xy 17.1196 -13.9446) (xy 17.1196 -15.1638) (xy 17.6022 -15.6464) (xy 17.6022 -15.7226)
				(xy 17.6022 -16.2052) (xy 17.5006 -16.3068) (xy 12.2682 -16.3068) (xy 11.9634 -16.6116) (xy 11.9634 -19.4564)
				(xy 13.081 -20.574) (xy 15.9258 -20.574) (xy 17.2847 -21.9329) (xy 19.6723 -21.9329) (xy 19.9136 -22.1742)
				(xy 19.9136 -22.8346) (xy 19.9136 -26.4922) (xy 18.2626 -28.1432) (xy 11.811 -28.1432) (xy 10.668 -27.0002)
				(xy 10.668 -24.3586) (xy 8.5598 -22.2504) (xy 8.5598 -13.081) (xy 8.5598 -12.9286) (xy 9.7028 -11.7856)
				(xy 9.7028 -5.842) (xy 10.6172 -4.9276) (xy 10.6553 -4.8895) (xy 14.6558 -0.889) (xy 15.4178 -0.127)
				(xy 15.4178 9.3726) (xy 15.6337 9.5885)
			)
		)
	)
	(zone
		(layer "In2.Cu")
		(hatch none 0.5)
		(connect_pads
			(clearance 0)
		)
		(min_thickness 0.25)
		(keepout
			(tracks allowed)
			(vias allowed)
			(pads allowed)
			(copperpour allowed)
			(footprints allowed)
		)
		(placement
			(enabled no)
			(sheetname "")
		)
		(fill
			(thermal_gap 0.5)
			(thermal_bridge_width 0.5)
			(island_removal_mode 0)
		)
		(polygon
			(pts
				(xy 51.0794 -21.0058) (xy 51.0794 -18.8214) (xy 51.6382 -18.2626) (xy 54.7116 -18.2626) (xy 55.1434 -18.6944)
				(xy 55.1434 -19.1516) (xy 52.8828 -21.4122) (xy 51.4858 -21.4122)
			)
		)
	)
	(zone
		(net "GND")
		(layer "In2.Cu")
		(hatch none 0.5)
		(connect_pads
			(clearance 0.5)
		)
		(min_thickness 0.25)
		(fill yes
			(thermal_gap 0.5)
			(thermal_bridge_width 0.5)
			(island_removal_mode 0)
		)
		(polygon
			(pts
				(xy 1.003046 -11.201654) (xy 0.812546 -11.392154) (xy 0.762 -11.4427)
				(arc
					(start 0.762 -31.782766)
					(mid 0.776831 -31.859043)
					(end 0.812546 -31.928054)
				)
				(arc
					(start 3.238246 -34.353754)
					(mid 3.306282 -34.40816)
					(end 3.390646 -34.429954)
				)
				(xy 26.123646 -34.429954) (xy 26.301446 -34.252154) (xy 26.301446 -33.934654) (xy 26.212546 -33.845754)
				(xy 13.156946 -33.845754) (xy 10.147046 -30.835854) (xy 10.147046 -30.721554) (xy 10.147046 -24.600154)
				(xy 8.019796 -22.472904) (xy 8.019796 -11.639804) (xy 7.581646 -11.201654)
			)
		)
	)
	(zone
		(net "P3V3_USB_HUB")
		(layer "In2.Cu")
		(hatch none 0.5)
		(connect_pads
			(clearance 0.5)
		)
		(min_thickness 0.25)
		(fill yes
			(thermal_gap 0.5)
			(thermal_bridge_width 0.5)
			(island_removal_mode 0)
		)
		(polygon
			(pts
				(xy 123.9774 -23.749) (xy 126.4666 -23.749) (xy 128.524 -25.8064) (xy 128.524 -30.8356) (xy 126.8984 -32.4612)
				(xy 121.8438 -32.4612) (xy 120.8024 -32.4612) (xy 119.507 -32.4612) (xy 117.8306 -30.7848) (xy 117.8306 -27.7368)
				(xy 118.3894 -27.178) (xy 120.2182 -27.178) (xy 120.6246 -27.178) (xy 121.6914 -28.2448) (xy 121.6914 -30.1752)
				(xy 122.047 -30.5308) (xy 125.2728 -30.5308) (xy 126.3904 -29.4132) (xy 126.3904 -26.7462) (xy 123.9774 -24.3332)
			)
		)
	)
	(zone
		(net "GND")
		(layer "In2.Cu")
		(hatch none 0.5)
		(connect_pads
			(clearance 0.5)
		)
		(min_thickness 0.25)
		(fill yes
			(thermal_gap 0.5)
			(thermal_bridge_width 0.5)
			(island_removal_mode 0)
		)
		(polygon
			(pts
				(xy 108.9025 11.8237) (xy 108.712254 11.633454) (xy 108.712254 8.5852) (xy 108.8771 8.420354) (xy 108.8771 8.4074)
				(xy 108.9025 8.382) (xy 128.8161 8.382) (xy 131.3561 5.842) (xy 131.3561 1.905) (xy 130.6068 1.1557)
				(xy 130.6068 -5.3975) (xy 133.0833 -7.874) (xy 133.0833 -8.382) (xy 133.1976 -8.4963) (xy 133.1976 -9.8552)
				(xy 131.8895 -11.1633) (xy 131.6355 -11.4173) (xy 131.6355 -11.4554) (xy 131.6482 -11.4681) (xy 131.6482 -19.6469)
				(xy 131.6482 -23.7744) (xy 130.7465 -24.6761) (xy 130.7465 -26.2255) (xy 129.4892 -27.4828) (xy 129.4892 -30.5181)
				(xy 129.4892 -31.3436) (xy 127.889 -32.9438) (xy 127.0635 -32.9438) (xy 118.4148 -32.9438) (xy 118.1354 -32.6644)
				(xy 114.9731 -32.6644) (xy 114.5667 -33.0708) (xy 114.5667 -33.4391) (xy 115.5573 -34.4297)
				(arc
					(start 144.0942 -34.4297)
					(mid 144.185537 -34.410669)
					(end 144.2593 -34.3535)
				)
				(arc
					(start 146.685 -31.9278)
					(mid 146.720289 -31.86826)
					(end 146.7358 -31.8008)
				)
				(xy 146.7358 -11.5316) (xy 145.3642 -10.16) (xy 139.4714 -10.16) (xy 138.0363 -8.7249)
				(arc
					(start 138.0363 -1.397)
					(mid 138.017871 -1.330712)
					(end 137.9855 -1.27)
				)
				(arc
					(start 137.541 -0.8255)
					(mid 137.460834 -0.780629)
					(end 137.37082 -0.762254)
				)
				(xy 133.399784 -0.762254)
				(arc
					(start 133.38937 -0.762254)
					(mid 132.68919 -0.463699)
					(end 132.4356 0.254)
				)
				(xy 132.4356 11.5951) (xy 132.207 11.8237)
			)
		)
	)
	(zone
		(net "P3V3_STBY")
		(layer "In2.Cu")
		(hatch none 0.5)
		(connect_pads
			(clearance 0.5)
		)
		(min_thickness 0.25)
		(fill yes
			(thermal_gap 0.5)
			(thermal_bridge_width 0.5)
			(island_removal_mode 0)
		)
		(polygon
			(pts
				(xy 42.9641 4.191) (xy 42.9641 2.667) (xy 42.9641 0.8382) (xy 43.9928 -0.1905) (xy 43.9928 -5.1943)
				(xy 43.0403 -6.1468) (xy 41.9227 -6.1468) (xy 41.783 -6.0071) (xy 41.783 -4.6228) (xy 41.783 -0.635)
				(xy 41.0464 0.1016) (xy 41.0464 3.0353) (xy 40.7289 3.3528) (xy 38.8493 5.2324) (xy 38.83025 5.25145)
				(xy 35.26155 5.25145) (xy 35.2425 5.2324) (xy 35.179 5.1689) (xy 34.4932 4.4831) (xy 34.3154 4.3053)
				(xy 32.9438 4.3053) (xy 32.5755 4.3053) (xy 32.385 4.4958) (xy 32.385 6.1722) (xy 33.10255 6.88975)
				(xy 33.58515 6.88975) (xy 40.26535 6.88975)
			)
		)
	)
	(zone
		(net "P12V_ATX")
		(layer "In2.Cu")
		(hatch none 0.5)
		(connect_pads
			(clearance 0.5)
		)
		(min_thickness 0.25)
		(fill yes
			(thermal_gap 0.5)
			(thermal_bridge_width 0.5)
			(island_removal_mode 0)
		)
		(polygon
			(pts
				(xy 26.797 -33.1978) (xy 25.273 -33.1978) (xy 15.1384 -33.1978) (xy 14.5034 -32.5628) (xy 14.5034 -29.7688)
				(xy 15.6972 -28.575) (xy 18.8976 -28.575) (xy 19.3294 -29.0068) (xy 20.9296 -29.0068) (xy 20.955 -29.0322)
				(xy 23.368 -29.0322) (xy 23.4188 -29.083) (xy 25.2476 -29.083) (xy 25.273 -29.0576) (xy 27.0002 -27.3304)
				(xy 27.6606 -27.3304) (xy 27.9781 -27.6479) (xy 27.9781 -32.0167) (xy 27.5082 -32.4866)
			)
		)
	)
	(zone
		(net "P3V3_MB")
		(layer "In2.Cu")
		(hatch none 0.5)
		(connect_pads
			(clearance 0.5)
		)
		(min_thickness 0.25)
		(fill yes
			(thermal_gap 0.5)
			(thermal_bridge_width 0.5)
			(island_removal_mode 0)
		)
		(polygon
			(pts
				(xy 23.2918 9.4488) (xy 24.4475 9.4488) (xy 26.1747 7.7216) (xy 30.6451 7.7216) (xy 31.0642 7.7216)
				(xy 32.131 6.6548) (xy 32.131 4.48945) (xy 31.6992 4.05765) (xy 24.75865 4.05765) (xy 23.06955 5.74675)
				(xy 23.06955 6.99135) (xy 23.06955 9.22655)
			)
		)
	)
	(zone
		(net "P12V_SLOT2")
		(layer "In2.Cu")
		(hatch none 0.5)
		(connect_pads
			(clearance 0.5)
		)
		(min_thickness 0.25)
		(fill yes
			(thermal_gap 0.5)
			(thermal_bridge_width 0.5)
			(island_removal_mode 0)
		)
		(polygon
			(pts
				(xy 22.7838 -12.8778) (xy 27.2034 -12.8778) (xy 27.6098 -13.2842) (xy 27.6098 -16.8656) (xy 26.543 -17.9324)
				(xy 20.7264 -17.9324) (xy 18.5801 -20.0787) (xy 13.1191 -20.0787) (xy 12.5095 -19.4691) (xy 12.5095 -17.0053)
				(xy 12.7254 -16.7894) (xy 18.8722 -16.7894) (xy 19.2659 -16.3957) (xy 21.3106 -14.351)
			)
		)
	)
	(zone
		(net "GND")
		(layer "In2.Cu")
		(hatch none 0.5)
		(connect_pads
			(clearance 0.5)
		)
		(min_thickness 0.25)
		(fill yes
			(thermal_gap 0.5)
			(thermal_bridge_width 0.5)
			(island_removal_mode 0)
		)
		(polygon
			(pts
				(xy 44.551346 11.823446) (xy 44.348146 11.620246)
				(arc
					(start 44.348146 9.334246)
					(mid 42.379646 7.349935)
					(end 40.411146 9.334246)
				)
				(xy 40.411146 11.582146) (xy 40.182546 11.810746) (xy 20.865846 11.810746) (xy 19.862546 10.807446)
				(xy 19.862546 6.552946) (xy 20.294346 6.121146) (xy 20.700746 6.121146) (xy 21.132546 6.552946)
				(xy 21.132546 6.718046) (xy 20.764246 7.086346) (xy 20.535646 7.086346) (xy 20.192746 7.429246)
				(xy 20.192746 8.534146) (xy 20.357846 8.699246) (xy 20.5232 8.699246) (xy 22.669754 10.8458) (xy 24.6126 10.8458)
				(xy 26.72715 8.73125) (xy 27.3431 8.1153) (xy 31.9151 8.1153) (xy 32.759904 7.270496) (xy 35.985196 7.270496)
				(xy 40.468804 7.270496) (xy 40.665654 7.073646) (xy 40.665654 7.010146) (xy 43.4086 4.2672) (xy 43.4086 1.8288)
				(xy 43.1165 1.5367) (xy 43.1165 1.1049) (xy 43.4721 0.7493) (xy 43.4975 0.7493) (xy 44.2595 -0.0127)
				(xy 44.2595 -4.2037) (xy 44.7802 -4.7244) (xy 54.102 -4.7244) (xy 56.0197 -2.8067) (xy 56.0197 -0.2413)
				(xy 51.1048 4.6736) (xy 51.1048 6.0833) (xy 51.308 6.2865) (xy 52.451 6.2865) (xy 53.4924 5.2451)
				(xy 57.658 1.0795) (xy 57.9882 0.7493) (xy 57.9882 -1.778) (xy 58.039 -1.8288) (xy 59.2836 -1.8288)
				(xy 66.421 5.3086) (xy 67.5259 5.3086) (xy 73.9521 5.3086) (xy 77.1144 8.4709) (xy 96.5327 8.4709)
				(xy 97.2566 7.747) (xy 97.2566 6.1722) (xy 97.6376 5.7912) (xy 98.0059 5.7912) (xy 98.5393 5.2578)
				(xy 98.5393 4.699) (xy 98.7806 4.4577) (xy 100.2792 4.4577) (xy 100.5586 4.1783) (xy 103.3653 4.1783)
				(xy 103.8479 4.6609) (xy 103.8479 5.4483) (xy 103.5812 5.715) (xy 98.767392 5.715) (xy 98.640646 5.841746)
				(xy 98.221546 6.260846) (xy 98.221546 11.518646) (xy 97.916746 11.823446)
			)
		)
	)
	(zone
		(net "P3V3")
		(layer "In2.Cu")
		(hatch none 0.5)
		(connect_pads
			(clearance 0.5)
		)
		(min_thickness 0.25)
		(fill yes
			(thermal_gap 0.5)
			(thermal_bridge_width 0.5)
			(island_removal_mode 0)
		)
		(polygon
			(pts
				(xy 27.7368 -7.5184) (xy 27.7368 -17.145) (xy 29.05125 -18.45945) (xy 29.05125 -20.16125) (xy 28.5623 -20.6502)
				(xy 28.5623 -34.0995) (xy 28.900628 -34.437828) (xy 40.466772 -34.437828) (xy 41.783 -33.1216) (xy 41.783 -15.9512)
				(xy 41.402 -15.5702) (xy 41.402 -4.9276) (xy 39.3954 -2.921) (xy 39.3954 0.9779) (xy 37.2745 3.0988)
				(xy 31.9151 3.0988) (xy 31.09595 2.27965) (xy 31.09595 -3.39725) (xy 27.7368 -6.7564)
			)
		)
	)
	(zone
		(net "P12V_SLOT3")
		(layer "In3.Cu")
		(hatch none 0.5)
		(connect_pads
			(clearance 0.5)
		)
		(min_thickness 0.25)
		(fill yes
			(thermal_gap 0.5)
			(thermal_bridge_width 0.5)
			(island_removal_mode 0)
		)
		(polygon
			(pts
				(xy 28.2702 -30.2768) (xy 31.7246 -26.8224) (xy 32.5628 -26.8224) (xy 34.0614 -28.321) (xy 34.0614 -33.1216)
				(xy 32.766 -34.417) (xy 27.6352 -34.417) (xy 26.7208 -33.5026) (xy 26.543 -33.3248) (xy 13.3477 -33.3248)
				(xy 12.2428 -32.2199) (xy 12.2428 -24.638) (xy 12.6492 -24.2316) (xy 14.351 -24.2316) (xy 14.4018 -24.2824)
				(xy 14.4018 -29.5148) (xy 14.4018 -29.7688) (xy 15.0114 -30.3784) (xy 28.1686 -30.3784)
			)
		)
	)
	(zone
		(net "P3V3_STBY")
		(layer "In3.Cu")
		(hatch none 0.5)
		(connect_pads
			(clearance 0.5)
		)
		(min_thickness 0.25)
		(fill yes
			(thermal_gap 0.5)
			(thermal_bridge_width 0.5)
			(island_removal_mode 0)
		)
		(polygon
			(pts
				(xy 27.7749 8.1661) (xy 27.92095 8.02005) (xy 28.0543 7.8867) (xy 33.0327 7.8867) (xy 33.274 7.8867)
				(xy 34.7345 6.4262) (xy 34.7345 6.1849) (xy 34.7345 4.9911) (xy 34.163 4.4196) (xy 32.8549 4.4196)
				(xy 32.83585 4.43865) (xy 32.59455 4.43865) (xy 32.3342 4.699) (xy 32.3342 6.2484) (xy 32.1183 6.4643)
				(xy 27.2542 6.4643) (xy 25.26665 8.45185) (xy 25.26665 8.4582) (xy 24.9555 8.76935) (xy 24.9555 9.6012)
				(xy 24.9555 9.8806) (xy 25.2349 10.16) (xy 27.2161 10.16) (xy 27.7749 9.6012)
			)
		)
	)
	(zone
		(net "P3V3_STBY")
		(layer "In3.Cu")
		(hatch none 0.5)
		(connect_pads
			(clearance 0.5)
		)
		(min_thickness 0.25)
		(fill yes
			(thermal_gap 0.5)
			(thermal_bridge_width 0.5)
			(island_removal_mode 0)
		)
		(polygon
			(pts
				(xy 118.0973 -10.6045) (xy 116.7892 -9.2964) (xy 116.3066 -9.2964) (xy 115.0366 -8.0264) (xy 115.0366 -6.9342)
				(xy 114.3508 -6.2484) (xy 43.3578 -6.2484) (xy 43.0276 -6.5786) (xy 43.0276 -7.2898) (xy 44.3992 -8.6614)
				(xy 44.3992 -13.1826) (xy 44.9072 -13.6906) (xy 44.9072 -14.859) (xy 44.704 -15.0622) (xy 42.9514 -15.0622)
				(xy 41.9608 -15.0622) (xy 41.402 -15.621) (xy 39.3446 -15.621) (xy 38.5826 -16.383) (xy 32.258 -16.383)
				(xy 31.7754 -15.9004) (xy 31.7754 -7.4422) (xy 34.63925 -4.57835) (xy 114.68735 -4.57835) (xy 115.7732 -5.6642)
				(xy 116.713 -6.604) (xy 116.84 -6.731) (xy 118.3132 -6.731) (xy 119.1514 -6.731) (xy 121.7676 -9.3472)
				(xy 122.3518 -9.3472) (xy 131.5593 -9.3472) (xy 132.2197 -8.6868) (xy 132.842 -8.6868) (xy 132.969 -8.8138)
				(xy 132.969 -9.7282) (xy 132.4864 -10.2108) (xy 131.2037 -11.4935) (xy 131.0259 -11.4935) (xy 130.4544 -10.922)
				(xy 128.8796 -10.922) (xy 127.9144 -11.8872) (xy 126.3142 -11.8872) (xy 126.0856 -12.1158) (xy 126.0856 -13.1318)
				(xy 126.0856 -13.3096) (xy 125.73 -13.6652) (xy 124.7902 -13.6652) (xy 124.7648 -13.6398) (xy 121.1326 -13.6398)
				(xy 119.7864 -12.2936) (xy 118.4148 -10.922)
			)
		)
	)
	(zone
		(net "P3V3_VR")
		(layer "In3.Cu")
		(hatch none 0.5)
		(connect_pads
			(clearance 0.5)
		)
		(min_thickness 0.25)
		(fill yes
			(thermal_gap 0.5)
			(thermal_bridge_width 0.5)
			(island_removal_mode 0)
		)
		(polygon
			(pts
				(xy 26.2636 1.7526) (xy 26.5684 1.4478) (xy 29.1084 1.4478) (xy 29.9593 0.5969) (xy 29.9593 -0.5207)
				(xy 28.5369 -1.9431) (xy 25.9842 -1.9431) (xy 25.1333 -1.0922) (xy 25.1333 0.1778) (xy 25.13965 0.18415)
				(xy 25.13965 1.44145) (xy 25.2222 1.524) (xy 25.4508 1.7526)
			)
		)
	)
	(zone
		(layer "In3.Cu")
		(hatch none 0.5)
		(connect_pads
			(clearance 0)
		)
		(min_thickness 0.25)
		(keepout
			(tracks allowed)
			(vias allowed)
			(pads allowed)
			(copperpour allowed)
			(footprints allowed)
		)
		(placement
			(enabled no)
			(sheetname "")
		)
		(fill
			(thermal_gap 0.5)
			(thermal_bridge_width 0.5)
			(island_removal_mode 0)
		)
		(polygon
			(pts
				(xy 23.0124 -22.7584) (xy 23.0124 -20.2184) (xy 27.1526 -16.0782) (xy 41.021 -16.0782) (xy 41.91 -15.1892)
				(xy 51.5112 -15.1892) (xy 54.102 -17.78) (xy 54.102 -20.955) (xy 53.4924 -21.5646) (xy 51.9684 -21.5646)
				(xy 50.2158 -19.812) (xy 50.2158 -17.0942) (xy 49.8094 -16.6878) (xy 42.3926 -16.6878) (xy 41.6306 -17.4498)
				(xy 28.4988 -17.4498) (xy 25.0952 -20.8534) (xy 25.0952 -23.0886) (xy 24.6888 -23.495) (xy 23.749 -23.495)
			)
		)
	)
	(zone
		(net "GND")
		(layer "In3.Cu")
		(hatch none 0.5)
		(connect_pads
			(clearance 0.5)
		)
		(min_thickness 0.25)
		(fill yes
			(thermal_gap 0.5)
			(thermal_bridge_width 0.5)
			(island_removal_mode 0)
		)
		(polygon
			(pts
				(xy 1.0033 -11.2014) (xy 0.8128 -11.3919) (xy 0.762254 -11.442446)
				(arc
					(start 0.762254 -31.782512)
					(mid 0.777085 -31.858789)
					(end 0.8128 -31.9278)
				)
				(arc
					(start 3.2385 -34.3535)
					(mid 3.306536 -34.407906)
					(end 3.3909 -34.4297)
				)
				(xy 26.1239 -34.4297) (xy 26.3017 -34.2519) (xy 26.3017 -33.9344) (xy 26.2128 -33.8455) (xy 13.1572 -33.8455)
				(xy 10.1473 -30.8356) (xy 10.1473 -30.7213) (xy 10.1473 -24.5999) (xy 8.02005 -22.47265) (xy 8.02005 -11.63955)
				(xy 7.5819 -11.2014)
			)
		)
	)
	(zone
		(net "GND")
		(layer "In3.Cu")
		(hatch none 0.5)
		(connect_pads
			(clearance 0.5)
		)
		(min_thickness 0.25)
		(fill yes
			(thermal_gap 0.5)
			(thermal_bridge_width 0.5)
			(island_removal_mode 0)
		)
		(polygon
			(pts
				(xy 44.5516 11.8237) (xy 44.3484 11.6205)
				(arc
					(start 44.3484 9.3345)
					(mid 42.3799 7.350189)
					(end 40.4114 9.3345)
				)
				(xy 40.4114 11.5824) (xy 40.1828 11.811) (xy 20.8661 11.811) (xy 19.8628 10.8077) (xy 19.8628 6.5532)
				(xy 20.2946 6.1214) (xy 20.701 6.1214) (xy 21.1328 6.5532) (xy 21.1328 6.7183) (xy 20.7645 7.0866)
				(xy 20.5359 7.0866) (xy 20.193 7.4295) (xy 20.193 8.5344) (xy 20.3581 8.6995) (xy 21.1963 8.6995)
				(xy 23.2156 10.7188) (xy 29.0449 10.7188) (xy 30.7594 9.0043) (xy 34.2519 9.0043) (xy 36.20135 7.05485)
				(xy 36.2204 7.0739) (xy 51.6255 7.0739) (xy 54.3687 4.3307) (xy 98.3488 4.3307) (xy 98.6409 4.6228)
				(xy 98.6409 5.842) (xy 98.2218 6.2611) (xy 98.2218 11.5189) (xy 97.917 11.8237)
			)
		)
	)
	(zone
		(net "P12V_SLOT2")
		(layer "In3.Cu")
		(hatch none 0.5)
		(connect_pads
			(clearance 0.5)
		)
		(min_thickness 0.25)
		(fill yes
			(thermal_gap 0.5)
			(thermal_bridge_width 0.5)
			(island_removal_mode 0)
		)
		(polygon
			(pts
				(xy 23.3934 -12.8778) (xy 27.178 -12.8778) (xy 27.559 -13.2588) (xy 27.559 -16.8656) (xy 26.4922 -17.9324)
				(xy 20.7264 -17.9324) (xy 20.5486 -18.1102) (xy 18.5801 -20.0787) (xy 13.0683 -20.0787) (xy 12.4968 -19.5072)
				(xy 12.4968 -16.9926) (xy 12.7 -16.7894) (xy 18.7706 -16.7894) (xy 19.0754 -16.4846) (xy 21.2471 -14.3129)
				(xy 22.6822 -12.8778)
			)
		)
	)
	(zone
		(net "GND")
		(layer "In3.Cu")
		(hatch none 0.5)
		(connect_pads
			(clearance 0.5)
		)
		(min_thickness 0.25)
		(fill yes
			(thermal_gap 0.5)
			(thermal_bridge_width 0.5)
			(island_removal_mode 0)
		)
		(polygon
			(pts
				(xy 108.9025 11.8237) (xy 108.712254 11.633454) (xy 108.712254 6.729984)
				(arc
					(start 108.712 6.704584)
					(mid 108.44199 6.052838)
					(end 107.7976 5.7658)
				)
				(xy 106.6673 5.7658) (xy 105.6386 4.7371) (xy 103.7336 4.7371) (xy 103.505 4.9657) (xy 102.8573 4.9657)
				(xy 102.7303 4.8387) (xy 102.7303 3.9243) (xy 103.0224 3.6322) (xy 111.4933 3.6322) (xy 112.1918 2.9337)
				(xy 120.7262 2.9337) (xy 122.2248 1.4351) (xy 124.3584 1.4351) (xy 126.4031 -0.6096) (xy 126.4031 -5.8801)
				(xy 124.5743 -7.7089) (xy 122.8725 -7.7089) (xy 122.5042 -7.3406) (xy 121.7803 -7.3406) (xy 121.6152 -7.5057)
				(xy 121.6152 -8.1534) (xy 122.555 -9.0932) (xy 131.2545 -9.0932) (xy 131.3561 -8.9916) (xy 131.3561 -8.9535)
				(xy 131.9276 -8.382) (xy 133.0833 -8.382) (xy 133.1976 -8.4963) (xy 133.1976 -9.8552) (xy 131.8895 -11.1633)
				(xy 131.8895 -16.7259) (xy 133.4135 -18.2499) (xy 133.4135 -19.177) (xy 132.9436 -19.6469) (xy 125.6411 -19.6469)
				(xy 124.9172 -18.923) (xy 123.8631 -18.923) (xy 123.5329 -19.2532) (xy 123.5329 -20.3581) (xy 124.0409 -20.8661)
				(xy 127.7239 -20.8661) (xy 132.7404 -25.8826) (xy 132.7404 -26.3144) (xy 131.572 -27.4828) (xy 126.3904 -27.4828)
				(xy 123.8504 -24.9428) (xy 118.999 -24.9428) (xy 117.7671 -26.1747) (xy 117.7671 -27.9654) (xy 121.0564 -31.2547)
				(xy 127.127 -31.2547) (xy 128.4351 -32.5628) (xy 128.4351 -33.0581) (xy 127.9525 -33.5407) (xy 127.3302 -33.5407)
				(xy 126.4539 -32.6644) (xy 114.9731 -32.6644) (xy 114.5667 -33.0708) (xy 114.5667 -33.4391) (xy 115.5573 -34.4297)
				(arc
					(start 144.0942 -34.4297)
					(mid 144.185537 -34.410669)
					(end 144.2593 -34.3535)
				)
				(arc
					(start 146.685 -31.9278)
					(mid 146.720289 -31.86826)
					(end 146.7358 -31.8008)
				)
				(xy 146.7358 -11.5316) (xy 145.3642 -10.16) (xy 139.4714 -10.16) (xy 138.0363 -8.7249)
				(arc
					(start 138.0363 -1.397)
					(mid 138.017871 -1.330712)
					(end 137.9855 -1.27)
				)
				(arc
					(start 137.541 -0.8255)
					(mid 137.460834 -0.780629)
					(end 137.37082 -0.762254)
				)
				(xy 133.399784 -0.762254)
				(arc
					(start 133.38937 -0.762254)
					(mid 132.68919 -0.463699)
					(end 132.4356 0.254)
				)
				(xy 132.4356 11.5951) (xy 132.207 11.8237)
			)
		)
	)
	(zone
		(net "P12V")
		(layer "In3.Cu")
		(hatch none 0.5)
		(connect_pads
			(clearance 0.5)
		)
		(min_thickness 0.25)
		(fill yes
			(thermal_gap 0.5)
			(thermal_bridge_width 0.5)
			(island_removal_mode 0)
		)
		(polygon
			(pts
				(xy 18.7325 9.5885) (xy 19.1516 9.1694) (xy 19.1516 -0.9144) (xy 13.8176 -6.2484) (xy 13.8176 -6.477)
				(xy 13.8176 -10.6426) (xy 15.7226 -12.5476) (xy 17.1704 -13.9954) (xy 17.1704 -14.9606) (xy 17.1704 -15.2654)
				(xy 17.6784 -15.7734) (xy 17.6784 -16.0528) (xy 17.4879 -16.2433) (xy 12.3317 -16.2433) (xy 11.9634 -16.6116)
				(xy 11.9634 -19.4564) (xy 13.081 -20.574) (xy 15.9258 -20.574) (xy 17.3736 -22.0218) (xy 19.7104 -22.0218)
				(xy 19.9136 -22.225) (xy 19.9136 -22.5298) (xy 19.9136 -22.8346) (xy 19.9136 -26.4922) (xy 18.2626 -28.1432)
				(xy 11.811 -28.1432) (xy 10.668 -27.0002) (xy 10.668 -24.3586) (xy 8.5598 -22.2504) (xy 8.5598 -12.954)
				(xy 9.69645 -11.81735) (xy 9.69645 -5.97535) (xy 10.6426 -5.0292) (xy 14.7828 -0.889) (xy 15.4305 -0.2413)
				(xy 15.4178 -0.2286) (xy 15.4178 9.3726) (xy 15.6337 9.5885)
			)
		)
	)
	(zone
		(net "GND")
		(layer "In4.Cu")
		(hatch none 0.5)
		(connect_pads
			(clearance 0.5)
		)
		(min_thickness 0.25)
		(fill yes
			(thermal_gap 0.5)
			(thermal_bridge_width 0.5)
			(island_removal_mode 0)
		)
		(polygon
			(pts
				(xy 15.312898 10.73277) (xy 15.312898 0.199898) (xy 15.311882 0.155702) (xy 15.311882 -0.115824)
				(arc
					(start 15.224506 -0.2032)
					(mid 15.030894 -0.481012)
					(end 14.753082 -0.674624)
				)
				(xy 14.665706 -0.762) (xy 14.39418 -0.762) (xy 14.349984 -0.763016)
				(arc
					(start 10.113772 -0.763016)
					(mid 10.023303 -0.781069)
					(end 9.94664 -0.832358)
				)
				(arc
					(start 9.532366 -1.246632)
					(mid 9.481154 -1.323326)
					(end 9.463024 -1.413764)
				)
				(xy 9.463024 -7.590028) (xy 9.462008 -7.66064) (xy 9.462008 -7.90575)
				(arc
					(start 9.439656 -7.927848)
					(mid 6.999986 -10.052976)
					(end 4.560316 -7.927848)
				)
				(xy 4.537964 -7.90575) (xy 4.537964 -7.66064) (xy 4.536948 -7.590028)
				(arc
					(start 4.536948 -1.413764)
					(mid 4.518895 -1.323295)
					(end 4.467606 -1.246632)
				)
				(arc
					(start 4.053332 -0.832358)
					(mid 3.976638 -0.781146)
					(end 3.8862 -0.763016)
				)
				(arc
					(start 0.999998 -0.763016)
					(mid 0.832426 -0.832426)
					(end 0.763016 -0.999998)
				)
				(arc
					(start 0.763016 -31.786322)
					(mid 0.781152 -31.876738)
					(end 0.832358 -31.953454)
				)
				(arc
					(start 3.246628 -34.367724)
					(mid 3.323307 -34.419019)
					(end 3.41376 -34.437066)
				)
				(arc
					(start 45.69333 -34.437066)
					(mid 45.643492 -34.376139)
					(end 45.60316 -34.308542)
				)
				(xy 45.602906 -34.308542)
				(arc
					(start 44.6024 -32.308546)
					(mid 44.840652 -31.592774)
					(end 45.556424 -31.831026)
				)
				(arc
					(start 46.557184 -33.831276)
					(mid 46.60782 -34.148359)
					(end 46.467268 -34.437066)
				)
				(arc
					(start 47.69358 -34.437066)
					(mid 47.552979 -34.148531)
					(end 47.60341 -33.83153)
				)
				(xy 47.603156 -33.83153) (xy 48.602646 -31.83128)
				(arc
					(start 48.6029 -31.83128)
					(mid 49.31852 -31.592825)
					(end 49.556924 -32.308546)
				)
				(xy 48.557688 -34.308542)
				(arc
					(start 48.557434 -34.308542)
					(mid 48.517104 -34.37614)
					(end 48.467264 -34.437066)
				)
				(arc
					(start 53.692806 -34.437066)
					(mid 53.642948 -34.376019)
					(end 53.602636 -34.308288)
				)
				(xy 52.603146 -32.308292)
				(arc
					(start 52.6034 -32.308292)
					(mid 52.841906 -31.592774)
					(end 53.557424 -31.83128)
				)
				(xy 53.557678 -31.83128) (xy 54.557168 -33.83153)
				(arc
					(start 54.556914 -33.83153)
					(mid 54.607421 -34.148454)
					(end 54.466998 -34.437066)
				)
				(arc
					(start 57.69356 -34.437066)
					(mid 57.643722 -34.376139)
					(end 57.60339 -34.308542)
				)
				(xy 57.603136 -34.308542)
				(arc
					(start 56.60263 -32.308546)
					(mid 56.840882 -31.592774)
					(end 57.556654 -31.831026)
				)
				(arc
					(start 58.557414 -33.831276)
					(mid 58.60805 -34.148359)
					(end 58.467498 -34.437066)
				)
				(arc
					(start 61.692536 -34.437066)
					(mid 61.642678 -34.376019)
					(end 61.602366 -34.308288)
				)
				(xy 60.602876 -32.308292)
				(arc
					(start 60.60313 -32.308292)
					(mid 60.841636 -31.592774)
					(end 61.557154 -31.83128)
				)
				(xy 61.557408 -31.83128) (xy 62.556898 -33.83153)
				(arc
					(start 62.556644 -33.83153)
					(mid 62.607151 -34.148454)
					(end 62.466728 -34.437066)
				)
				(arc
					(start 63.69304 -34.437066)
					(mid 63.552439 -34.148531)
					(end 63.60287 -33.83153)
				)
				(xy 63.602616 -33.83153) (xy 64.602106 -31.83128)
				(arc
					(start 64.60236 -31.83128)
					(mid 65.31798 -31.592825)
					(end 65.556384 -32.308546)
				)
				(xy 64.557148 -34.308542)
				(arc
					(start 64.556894 -34.308542)
					(mid 64.516564 -34.37614)
					(end 64.466724 -34.437066)
				)
				(arc
					(start 67.69354 -34.437066)
					(mid 67.643702 -34.376139)
					(end 67.60337 -34.308542)
				)
				(xy 67.603116 -34.308542)
				(arc
					(start 66.60261 -32.308546)
					(mid 66.840862 -31.592774)
					(end 67.556634 -31.831026)
				)
				(arc
					(start 68.557394 -33.831276)
					(mid 68.60803 -34.148359)
					(end 68.467478 -34.437066)
				)
				(arc
					(start 71.692516 -34.437066)
					(mid 71.642658 -34.376019)
					(end 71.602346 -34.308288)
				)
				(xy 70.602856 -32.308292)
				(arc
					(start 70.60311 -32.308292)
					(mid 70.841616 -31.592774)
					(end 71.557134 -31.83128)
				)
				(xy 71.557388 -31.83128) (xy 72.556878 -33.83153)
				(arc
					(start 72.556624 -33.83153)
					(mid 72.607131 -34.148454)
					(end 72.466708 -34.437066)
				)
				(arc
					(start 75.69327 -34.437066)
					(mid 75.643432 -34.376139)
					(end 75.6031 -34.308542)
				)
				(xy 75.602846 -34.308542)
				(arc
					(start 74.60234 -32.308546)
					(mid 74.840592 -31.592774)
					(end 75.556364 -31.831026)
				)
				(arc
					(start 76.557124 -33.831276)
					(mid 76.60776 -34.148359)
					(end 76.467208 -34.437066)
				)
				(arc
					(start 79.692246 -34.437066)
					(mid 79.642388 -34.376019)
					(end 79.602076 -34.308288)
				)
				(xy 78.602586 -32.308292)
				(arc
					(start 78.60284 -32.308292)
					(mid 78.841346 -31.592774)
					(end 79.556864 -31.83128)
				)
				(xy 79.557118 -31.83128) (xy 80.556608 -33.83153)
				(arc
					(start 80.556354 -33.83153)
					(mid 80.606861 -34.148454)
					(end 80.466438 -34.437066)
				)
				(arc
					(start 83.693 -34.437066)
					(mid 83.552399 -34.148531)
					(end 83.60283 -33.83153)
				)
				(xy 83.602576 -33.83153) (xy 84.602066 -31.83128)
				(arc
					(start 84.60232 -31.83128)
					(mid 85.31794 -31.592825)
					(end 85.556344 -32.308546)
				)
				(xy 84.557108 -34.308542)
				(arc
					(start 84.556854 -34.308542)
					(mid 84.516524 -34.37614)
					(end 84.466684 -34.437066)
				)
				(arc
					(start 87.6935 -34.437066)
					(mid 87.552899 -34.148531)
					(end 87.60333 -33.83153)
				)
				(xy 87.603076 -33.83153) (xy 88.602566 -31.83128)
				(arc
					(start 88.60282 -31.83128)
					(mid 89.31844 -31.592825)
					(end 89.556844 -32.308546)
				)
				(xy 88.557608 -34.308542)
				(arc
					(start 88.557354 -34.308542)
					(mid 88.517024 -34.37614)
					(end 88.467184 -34.437066)
				)
				(arc
					(start 91.692476 -34.437066)
					(mid 91.551917 -34.14836)
					(end 91.60256 -33.831276)
				)
				(arc
					(start 92.60332 -31.831026)
					(mid 93.319092 -31.592774)
					(end 93.557344 -32.308546)
				)
				(xy 93.557344 -32.3088)
				(arc
					(start 92.556584 -34.308796)
					(mid 92.516357 -34.376247)
					(end 92.466668 -34.437066)
				)
				(arc
					(start 95.69323 -34.437066)
					(mid 95.552629 -34.148531)
					(end 95.60306 -33.83153)
				)
				(xy 95.602806 -33.83153) (xy 96.602296 -31.83128)
				(arc
					(start 96.60255 -31.83128)
					(mid 97.31817 -31.592825)
					(end 97.556574 -32.308546)
				)
				(xy 96.557338 -34.308542)
				(arc
					(start 96.557084 -34.308542)
					(mid 96.516754 -34.37614)
					(end 96.466914 -34.437066)
				)
				(arc
					(start 99.692206 -34.437066)
					(mid 99.551647 -34.14836)
					(end 99.60229 -33.831276)
				)
				(arc
					(start 100.60305 -31.831026)
					(mid 101.318822 -31.592774)
					(end 101.557074 -32.308546)
				)
				(xy 101.557074 -32.3088)
				(arc
					(start 100.556314 -34.308796)
					(mid 100.516087 -34.376247)
					(end 100.466398 -34.437066)
				)
				(arc
					(start 103.69296 -34.437066)
					(mid 103.552359 -34.148531)
					(end 103.60279 -33.83153)
				)
				(xy 103.602536 -33.83153) (xy 104.602026 -31.83128)
				(arc
					(start 104.60228 -31.83128)
					(mid 105.3179 -31.592825)
					(end 105.556304 -32.308546)
				)
				(xy 104.557068 -34.308542)
				(arc
					(start 104.556814 -34.308542)
					(mid 104.516484 -34.37614)
					(end 104.466644 -34.437066)
				)
				(arc
					(start 107.69346 -34.437066)
					(mid 107.552859 -34.148531)
					(end 107.60329 -33.83153)
				)
				(xy 107.603036 -33.83153) (xy 108.602526 -31.83128)
				(arc
					(start 108.60278 -31.83128)
					(mid 109.3184 -31.592825)
					(end 109.556804 -32.308546)
				)
				(xy 108.557568 -34.308542)
				(arc
					(start 108.557314 -34.308542)
					(mid 108.516984 -34.37614)
					(end 108.467144 -34.437066)
				)
				(arc
					(start 111.692436 -34.437066)
					(mid 111.551877 -34.14836)
					(end 111.60252 -33.831276)
				)
				(arc
					(start 112.60328 -31.831026)
					(mid 113.319052 -31.592774)
					(end 113.557304 -32.308546)
				)
				(xy 113.557304 -32.3088)
				(arc
					(start 112.556544 -34.308796)
					(mid 112.516317 -34.376247)
					(end 112.466628 -34.437066)
				)
				(arc
					(start 144.086072 -34.437066)
					(mid 144.176624 -34.418978)
					(end 144.253458 -34.367724)
				)
				(arc
					(start 146.667728 -31.953454)
					(mid 146.719072 -31.876657)
					(end 146.73707 -31.786068)
				)
				(arc
					(start 146.73707 -0.999998)
					(mid 146.66766 -0.832426)
					(end 146.500088 -0.763016)
				)
				(arc
					(start 143.613632 -0.763016)
					(mid 143.523216 -0.781152)
					(end 143.4465 -0.832358)
				)
				(arc
					(start 143.032734 -1.246632)
					(mid 142.981337 -1.323414)
					(end 142.963138 -1.414018)
				)
				(xy 142.963138 -7.590028) (xy 142.962122 -7.66064) (xy 142.962122 -7.90575)
				(arc
					(start 142.93977 -7.927848)
					(mid 140.5001 -10.052976)
					(end 138.06043 -7.927848)
				)
				(xy 138.038078 -7.90575) (xy 138.038078 -7.66064) (xy 138.037062 -7.590028)
				(arc
					(start 138.037062 -1.413764)
					(mid 138.018926 -1.323348)
					(end 137.96772 -1.246632)
				)
				(arc
					(start 137.553446 -0.832358)
					(mid 137.476767 -0.781063)
					(end 137.386314 -0.763016)
				)
				(xy 133.399784 -0.763016) (xy 133.355588 -0.762) (xy 133.084316 -0.762)
				(arc
					(start 132.997194 -0.674624)
					(mid 132.719143 -0.481053)
					(end 132.525262 -0.2032)
				)
				(xy 132.437886 -0.115824) (xy 132.437886 0.155702) (xy 132.43687 0.199644) (xy 132.43687 10.73277)
				(xy 108.713016 10.73277) (xy 108.713016 6.729984) (xy 108.712 6.685788) (xy 108.712 6.414262)
				(arc
					(start 108.624624 6.326886)
					(mid 108.431012 6.049074)
					(end 108.1532 5.855462)
				)
				(xy 108.065824 5.768086) (xy 107.794298 5.768086) (xy 107.750102 5.76707) (xy 99.199954 5.76707)
				(xy 99.155758 5.768086) (xy 98.884232 5.768086)
				(arc
					(start 98.796856 5.855462)
					(mid 98.519044 6.049074)
					(end 98.325432 6.326886)
				)
				(xy 98.238056 6.414262) (xy 98.238056 6.685788) (xy 98.23704 6.729984) (xy 98.23704 10.73277) (xy 44.343066 10.73277)
				(xy 44.343066 9.329928) (xy 44.34205 9.266682) (xy 44.34205 9.014206)
				(arc
					(start 44.312586 8.984742)
					(mid 42.380132 7.366908)
					(end 40.447468 8.984742)
				)
				(xy 40.418004 9.014206) (xy 40.418004 9.266682) (xy 40.416988 9.329928) (xy 40.416988 10.73277)
			)
		)
		(polygon
			(pts
				(arc
					(start 126.511558 -34.426906)
					(mid 127.072644 -33.865439)
					(end 126.511304 -33.304226)
				)
				(arc
					(start 125.639576 -33.304226)
					(mid 125.078236 -33.865566)
					(end 125.639576 -34.426906)
				)
			)
		)
		(polygon
			(pts
				(arc
					(start 116.675408 -33.986978)
					(mid 117.222778 -33.412176)
					(end 116.647976 -32.864806)
				)
				(xy 116.647976 -32.862266) (xy 115.784884 -32.883348) (xy 115.78463 -32.883602)
				(arc
					(start 115.78463 -32.885888)
					(mid 115.23726 -33.46069)
					(end 115.812062 -34.00806)
				)
				(xy 115.812062 -34.0106) (xy 116.675408 -33.989518)
			)
		)
		(polygon
			(pts
				(arc
					(start 106.557064 -27.33167)
					(mid 105.841546 -27.093164)
					(end 105.60304 -27.808682)
				)
				(xy 105.602786 -27.808682)
				(arc
					(start 106.602276 -29.808678)
					(mid 107.317946 -30.047616)
					(end 107.556554 -29.33192)
				)
				(xy 107.556808 -29.33192) (xy 106.557318 -27.33167)
			)
		)
		(polygon
			(pts
				(arc
					(start 98.557334 -27.33167)
					(mid 97.841816 -27.093164)
					(end 97.60331 -27.808682)
				)
				(xy 97.603056 -27.808682)
				(arc
					(start 98.602546 -29.808678)
					(mid 99.318216 -30.047616)
					(end 99.556824 -29.33192)
				)
				(xy 99.557078 -29.33192) (xy 98.557588 -27.33167)
			)
		)
		(polygon
			(pts
				(arc
					(start 94.556834 -27.33167)
					(mid 93.841316 -27.093164)
					(end 93.60281 -27.808682)
				)
				(xy 93.602556 -27.808682)
				(arc
					(start 94.602046 -29.808678)
					(mid 95.317716 -30.047616)
					(end 95.556324 -29.33192)
				)
				(xy 95.556578 -29.33192) (xy 94.557088 -27.33167)
			)
		)
		(polygon
			(pts
				(arc
					(start 86.557104 -27.33167)
					(mid 85.841586 -27.093164)
					(end 85.60308 -27.808682)
				)
				(xy 85.602826 -27.808682)
				(arc
					(start 86.602316 -29.808678)
					(mid 87.317986 -30.047616)
					(end 87.556594 -29.33192)
				)
				(xy 87.556848 -29.33192) (xy 86.557358 -27.33167)
			)
		)
		(polygon
			(pts
				(arc
					(start 46.557184 -27.33167)
					(mid 45.841666 -27.093164)
					(end 45.60316 -27.808682)
				)
				(xy 45.602906 -27.808682)
				(arc
					(start 46.602396 -29.808678)
					(mid 47.318066 -30.047616)
					(end 47.556674 -29.33192)
				)
				(xy 47.556928 -29.33192) (xy 46.557438 -27.33167)
			)
		)
		(polygon
			(pts
				(arc
					(start 74.556874 -27.808936)
					(mid 74.31852 -27.093113)
					(end 73.60285 -27.33167)
				)
				(xy 73.602596 -27.33167) (xy 72.603106 -29.33192)
				(arc
					(start 72.60336 -29.33192)
					(mid 72.841866 -30.047438)
					(end 73.557384 -29.808932)
				)
				(xy 73.557638 -29.808932)
			)
		)
		(polygon
			(pts
				(arc
					(start 70.556374 -27.808936)
					(mid 70.31802 -27.093113)
					(end 69.60235 -27.33167)
				)
				(xy 69.602096 -27.33167) (xy 68.602606 -29.33192)
				(arc
					(start 68.60286 -29.33192)
					(mid 68.841366 -30.047438)
					(end 69.556884 -29.808932)
				)
				(xy 69.557138 -29.808932)
			)
		)
		(polygon
			(pts
				(arc
					(start 60.556394 -27.808936)
					(mid 60.31804 -27.093113)
					(end 59.60237 -27.33167)
				)
				(xy 59.602116 -27.33167) (xy 58.602626 -29.33192)
				(arc
					(start 58.60288 -29.33192)
					(mid 58.841386 -30.047438)
					(end 59.556904 -29.808932)
				)
				(xy 59.557158 -29.808932)
			)
		)
		(polygon
			(pts
				(arc
					(start 52.556664 -27.808936)
					(mid 52.31831 -27.093113)
					(end 51.60264 -27.33167)
				)
				(xy 51.602386 -27.33167) (xy 50.602896 -29.33192)
				(arc
					(start 50.60315 -29.33192)
					(mid 50.841656 -30.047438)
					(end 51.557174 -29.808932)
				)
				(xy 51.557428 -29.808932)
			)
		)
		(polygon
			(pts
				(arc
					(start 110.556294 -27.331416)
					(mid 109.840522 -27.093164)
					(end 109.60227 -27.808936)
				)
				(xy 110.602776 -29.808932)
				(arc
					(start 110.60303 -29.808932)
					(mid 111.31865 -30.047387)
					(end 111.557054 -29.331666)
				)
			)
		)
		(polygon
			(pts
				(arc
					(start 102.556564 -27.331416)
					(mid 101.840792 -27.093164)
					(end 101.60254 -27.808936)
				)
				(xy 102.603046 -29.808932)
				(arc
					(start 102.6033 -29.808932)
					(mid 103.31892 -30.047387)
					(end 103.557324 -29.331666)
				)
			)
		)
		(polygon
			(pts
				(arc
					(start 90.556334 -27.331416)
					(mid 89.840562 -27.093164)
					(end 89.60231 -27.808936)
				)
				(xy 90.602816 -29.808932)
				(arc
					(start 90.60307 -29.808932)
					(mid 91.31869 -30.047387)
					(end 91.557094 -29.331666)
				)
			)
		)
		(polygon
			(pts
				(arc
					(start 82.556604 -27.331416)
					(mid 81.840832 -27.093164)
					(end 81.60258 -27.808936)
				)
				(xy 82.603086 -29.808932)
				(arc
					(start 82.60334 -29.808932)
					(mid 83.31896 -30.047387)
					(end 83.557364 -29.331666)
				)
			)
		)
		(polygon
			(pts
				(arc
					(start 78.557374 -27.808936)
					(mid 78.319122 -27.093164)
					(end 77.60335 -27.331416)
				)
				(arc
					(start 76.60259 -29.331666)
					(mid 76.840842 -30.047438)
					(end 77.556614 -29.809186)
				)
				(xy 78.557374 -27.80919)
			)
		)
		(polygon
			(pts
				(arc
					(start 66.557144 -27.808936)
					(mid 66.318892 -27.093164)
					(end 65.60312 -27.331416)
				)
				(arc
					(start 64.60236 -29.331666)
					(mid 64.840612 -30.047438)
					(end 65.556384 -29.809186)
				)
				(xy 66.557144 -27.80919)
			)
		)
		(polygon
			(pts
				(arc
					(start 56.557164 -27.808936)
					(mid 56.318912 -27.093164)
					(end 55.60314 -27.331416)
				)
				(arc
					(start 54.60238 -29.331666)
					(mid 54.840632 -30.047438)
					(end 55.556404 -29.809186)
				)
				(xy 56.557164 -27.80919)
			)
		)
		(polygon
			(pts
				(arc
					(start 79.556864 -11.51128)
					(mid 78.841346 -11.272774)
					(end 78.60284 -11.988292)
				)
				(xy 78.602586 -11.988292)
				(arc
					(start 79.602076 -13.988288)
					(mid 80.317746 -14.227226)
					(end 80.556354 -13.51153)
				)
				(xy 80.556608 -13.51153) (xy 79.557118 -11.51128)
			)
		)
		(polygon
			(pts
				(arc
					(start 71.557134 -11.51128)
					(mid 70.841616 -11.272774)
					(end 70.60311 -11.988292)
				)
				(xy 70.602856 -11.988292)
				(arc
					(start 71.602346 -13.988288)
					(mid 72.318016 -14.227226)
					(end 72.556624 -13.51153)
				)
				(xy 72.556878 -13.51153) (xy 71.557388 -11.51128)
			)
		)
		(polygon
			(pts
				(arc
					(start 61.557154 -11.51128)
					(mid 60.841636 -11.272774)
					(end 60.60313 -11.988292)
				)
				(xy 60.602876 -11.988292)
				(arc
					(start 61.602366 -13.988288)
					(mid 62.318036 -14.227226)
					(end 62.556644 -13.51153)
				)
				(xy 62.556898 -13.51153) (xy 61.557408 -11.51128)
			)
		)
		(polygon
			(pts
				(arc
					(start 53.557424 -11.51128)
					(mid 52.841906 -11.272774)
					(end 52.6034 -11.988292)
				)
				(xy 52.603146 -11.988292)
				(arc
					(start 53.602636 -13.988288)
					(mid 54.318306 -14.227226)
					(end 54.556914 -13.51153)
				)
				(xy 54.557168 -13.51153) (xy 53.557678 -11.51128)
			)
		)
		(polygon
			(pts
				(arc
					(start 109.556804 -11.988546)
					(mid 109.31845 -11.272723)
					(end 108.60278 -11.51128)
				)
				(xy 108.602526 -11.51128) (xy 107.603036 -13.51153)
				(arc
					(start 107.60329 -13.51153)
					(mid 107.841796 -14.227048)
					(end 108.557314 -13.988542)
				)
				(xy 108.557568 -13.988542)
			)
		)
		(polygon
			(pts
				(arc
					(start 105.556304 -11.988546)
					(mid 105.31795 -11.272723)
					(end 104.60228 -11.51128)
				)
				(xy 104.602026 -11.51128) (xy 103.602536 -13.51153)
				(arc
					(start 103.60279 -13.51153)
					(mid 103.841296 -14.227048)
					(end 104.556814 -13.988542)
				)
				(xy 104.557068 -13.988542)
			)
		)
		(polygon
			(pts
				(arc
					(start 97.556574 -11.988546)
					(mid 97.31822 -11.272723)
					(end 96.60255 -11.51128)
				)
				(xy 96.602296 -11.51128) (xy 95.602806 -13.51153)
				(arc
					(start 95.60306 -13.51153)
					(mid 95.841566 -14.227048)
					(end 96.557084 -13.988542)
				)
				(xy 96.557338 -13.988542)
			)
		)
		(polygon
			(pts
				(arc
					(start 89.556844 -11.988546)
					(mid 89.31849 -11.272723)
					(end 88.60282 -11.51128)
				)
				(xy 88.602566 -11.51128) (xy 87.603076 -13.51153)
				(arc
					(start 87.60333 -13.51153)
					(mid 87.841836 -14.227048)
					(end 88.557354 -13.988542)
				)
				(xy 88.557608 -13.988542)
			)
		)
		(polygon
			(pts
				(arc
					(start 85.556344 -11.988546)
					(mid 85.31799 -11.272723)
					(end 84.60232 -11.51128)
				)
				(xy 84.602066 -11.51128) (xy 83.602576 -13.51153)
				(arc
					(start 83.60283 -13.51153)
					(mid 83.841336 -14.227048)
					(end 84.556854 -13.988542)
				)
				(xy 84.557108 -13.988542)
			)
		)
		(polygon
			(pts
				(arc
					(start 65.556384 -11.988546)
					(mid 65.31803 -11.272723)
					(end 64.60236 -11.51128)
				)
				(xy 64.602106 -11.51128) (xy 63.602616 -13.51153)
				(arc
					(start 63.60287 -13.51153)
					(mid 63.841376 -14.227048)
					(end 64.556894 -13.988542)
				)
				(xy 64.557148 -13.988542)
			)
		)
		(polygon
			(pts
				(arc
					(start 49.556924 -11.988546)
					(mid 49.31857 -11.272723)
					(end 48.6029 -11.51128)
				)
				(xy 48.602646 -11.51128) (xy 47.603156 -13.51153)
				(arc
					(start 47.60341 -13.51153)
					(mid 47.841916 -14.227048)
					(end 48.557434 -13.988542)
				)
				(xy 48.557688 -13.988542)
			)
		)
		(polygon
			(pts
				(arc
					(start 113.557304 -11.988546)
					(mid 113.319052 -11.272774)
					(end 112.60328 -11.511026)
				)
				(arc
					(start 111.60252 -13.511276)
					(mid 111.840772 -14.227048)
					(end 112.556544 -13.988796)
				)
				(xy 113.557304 -11.9888)
			)
		)
		(polygon
			(pts
				(arc
					(start 101.557074 -11.988546)
					(mid 101.318822 -11.272774)
					(end 100.60305 -11.511026)
				)
				(arc
					(start 99.60229 -13.511276)
					(mid 99.840542 -14.227048)
					(end 100.556314 -13.988796)
				)
				(xy 101.557074 -11.9888)
			)
		)
		(polygon
			(pts
				(arc
					(start 93.557344 -11.988546)
					(mid 93.319092 -11.272774)
					(end 92.60332 -11.511026)
				)
				(arc
					(start 91.60256 -13.511276)
					(mid 91.840812 -14.227048)
					(end 92.556584 -13.988796)
				)
				(xy 93.557344 -11.9888)
			)
		)
		(polygon
			(pts
				(arc
					(start 75.556364 -11.511026)
					(mid 74.840592 -11.272774)
					(end 74.60234 -11.988546)
				)
				(xy 75.602846 -13.988542)
				(arc
					(start 75.6031 -13.988542)
					(mid 76.31872 -14.226997)
					(end 76.557124 -13.511276)
				)
			)
		)
		(polygon
			(pts
				(arc
					(start 67.556634 -11.511026)
					(mid 66.840862 -11.272774)
					(end 66.60261 -11.988546)
				)
				(xy 67.603116 -13.988542)
				(arc
					(start 67.60337 -13.988542)
					(mid 68.31899 -14.226997)
					(end 68.557394 -13.511276)
				)
			)
		)
		(polygon
			(pts
				(arc
					(start 57.556654 -11.511026)
					(mid 56.840882 -11.272774)
					(end 56.60263 -11.988546)
				)
				(xy 57.603136 -13.988542)
				(arc
					(start 57.60339 -13.988542)
					(mid 58.31901 -14.226997)
					(end 58.557414 -13.511276)
				)
			)
		)
		(polygon
			(pts
				(arc
					(start 45.556424 -11.511026)
					(mid 44.840652 -11.272774)
					(end 44.6024 -11.988546)
				)
				(xy 45.602906 -13.988542)
				(arc
					(start 45.60316 -13.988542)
					(mid 46.31878 -14.226997)
					(end 46.557184 -13.511276)
				)
			)
		)
		(polygon
			(pts
				(arc
					(start 106.557064 -7.01167)
					(mid 105.841546 -6.773164)
					(end 105.60304 -7.488682)
				)
				(xy 105.602786 -7.488682)
				(arc
					(start 106.602276 -9.488678)
					(mid 107.317946 -9.727616)
					(end 107.556554 -9.01192)
				)
				(xy 107.556808 -9.01192) (xy 106.557318 -7.01167)
			)
		)
		(polygon
			(pts
				(arc
					(start 98.557334 -7.01167)
					(mid 97.841816 -6.773164)
					(end 97.60331 -7.488682)
				)
				(xy 97.603056 -7.488682)
				(arc
					(start 98.602546 -9.488678)
					(mid 99.318216 -9.727616)
					(end 99.556824 -9.01192)
				)
				(xy 99.557078 -9.01192) (xy 98.557588 -7.01167)
			)
		)
		(polygon
			(pts
				(arc
					(start 94.556834 -7.01167)
					(mid 93.841316 -6.773164)
					(end 93.60281 -7.488682)
				)
				(xy 93.602556 -7.488682)
				(arc
					(start 94.602046 -9.488678)
					(mid 95.317716 -9.727616)
					(end 95.556324 -9.01192)
				)
				(xy 95.556578 -9.01192) (xy 94.557088 -7.01167)
			)
		)
		(polygon
			(pts
				(arc
					(start 86.557104 -7.01167)
					(mid 85.841586 -6.773164)
					(end 85.60308 -7.488682)
				)
				(xy 85.602826 -7.488682)
				(arc
					(start 86.602316 -9.488678)
					(mid 87.317986 -9.727616)
					(end 87.556594 -9.01192)
				)
				(xy 87.556848 -9.01192) (xy 86.557358 -7.01167)
			)
		)
		(polygon
			(pts
				(arc
					(start 46.557184 -7.01167)
					(mid 45.841666 -6.773164)
					(end 45.60316 -7.488682)
				)
				(xy 45.602906 -7.488682)
				(arc
					(start 46.602396 -9.488678)
					(mid 47.318066 -9.727616)
					(end 47.556674 -9.01192)
				)
				(xy 47.556928 -9.01192) (xy 46.557438 -7.01167)
			)
		)
		(polygon
			(pts
				(arc
					(start 74.556874 -7.488936)
					(mid 74.31852 -6.773113)
					(end 73.60285 -7.01167)
				)
				(xy 73.602596 -7.01167) (xy 72.603106 -9.01192)
				(arc
					(start 72.60336 -9.01192)
					(mid 72.841866 -9.727438)
					(end 73.557384 -9.488932)
				)
				(xy 73.557638 -9.488932)
			)
		)
		(polygon
			(pts
				(arc
					(start 70.556374 -7.488936)
					(mid 70.31802 -6.773113)
					(end 69.60235 -7.01167)
				)
				(xy 69.602096 -7.01167) (xy 68.602606 -9.01192)
				(arc
					(start 68.60286 -9.01192)
					(mid 68.841366 -9.727438)
					(end 69.556884 -9.488932)
				)
				(xy 69.557138 -9.488932)
			)
		)
		(polygon
			(pts
				(arc
					(start 60.556394 -7.488936)
					(mid 60.31804 -6.773113)
					(end 59.60237 -7.01167)
				)
				(xy 59.602116 -7.01167) (xy 58.602626 -9.01192)
				(arc
					(start 58.60288 -9.01192)
					(mid 58.841386 -9.727438)
					(end 59.556904 -9.488932)
				)
				(xy 59.557158 -9.488932)
			)
		)
		(polygon
			(pts
				(arc
					(start 52.556664 -7.488936)
					(mid 52.31831 -6.773113)
					(end 51.60264 -7.01167)
				)
				(xy 51.602386 -7.01167) (xy 50.602896 -9.01192)
				(arc
					(start 50.60315 -9.01192)
					(mid 50.841656 -9.727438)
					(end 51.557174 -9.488932)
				)
				(xy 51.557428 -9.488932)
			)
		)
		(polygon
			(pts
				(arc
					(start 110.556294 -7.011416)
					(mid 109.840522 -6.773164)
					(end 109.60227 -7.488936)
				)
				(xy 110.602776 -9.488932)
				(arc
					(start 110.60303 -9.488932)
					(mid 111.31865 -9.727387)
					(end 111.557054 -9.011666)
				)
			)
		)
		(polygon
			(pts
				(arc
					(start 102.556564 -7.011416)
					(mid 101.840792 -6.773164)
					(end 101.60254 -7.488936)
				)
				(xy 102.603046 -9.488932)
				(arc
					(start 102.6033 -9.488932)
					(mid 103.31892 -9.727387)
					(end 103.557324 -9.011666)
				)
			)
		)
		(polygon
			(pts
				(arc
					(start 90.556334 -7.011416)
					(mid 89.840562 -6.773164)
					(end 89.60231 -7.488936)
				)
				(xy 90.602816 -9.488932)
				(arc
					(start 90.60307 -9.488932)
					(mid 91.31869 -9.727387)
					(end 91.557094 -9.011666)
				)
			)
		)
		(polygon
			(pts
				(arc
					(start 82.556604 -7.011416)
					(mid 81.840832 -6.773164)
					(end 81.60258 -7.488936)
				)
				(xy 82.603086 -9.488932)
				(arc
					(start 82.60334 -9.488932)
					(mid 83.31896 -9.727387)
					(end 83.557364 -9.011666)
				)
			)
		)
		(polygon
			(pts
				(arc
					(start 78.557374 -7.488936)
					(mid 78.319122 -6.773164)
					(end 77.60335 -7.011416)
				)
				(arc
					(start 76.60259 -9.011666)
					(mid 76.840842 -9.727438)
					(end 77.556614 -9.489186)
				)
				(xy 78.557374 -7.48919)
			)
		)
		(polygon
			(pts
				(arc
					(start 66.557144 -7.488936)
					(mid 66.318892 -6.773164)
					(end 65.60312 -7.011416)
				)
				(arc
					(start 64.60236 -9.011666)
					(mid 64.840612 -9.727438)
					(end 65.556384 -9.489186)
				)
				(xy 66.557144 -7.48919)
			)
		)
		(polygon
			(pts
				(arc
					(start 56.557164 -7.488936)
					(mid 56.318912 -6.773164)
					(end 55.60314 -7.011416)
				)
				(arc
					(start 54.60238 -9.011666)
					(mid 54.840632 -9.727438)
					(end 55.556404 -9.489186)
				)
				(xy 56.557164 -7.48919)
			)
		)
		(polygon
			(pts
				(arc
					(start 97.783142 4.807712)
					(mid 98.141028 5.165979)
					(end 97.782888 5.523992)
				)
				(arc
					(start 96.766888 5.523992)
					(mid 96.408748 5.165852)
					(end 96.766888 4.807712)
				)
			)
		)
		(polygon
			(pts
				(arc
					(start 95.192342 4.807712)
					(mid 95.550228 5.165979)
					(end 95.192088 5.523992)
				)
				(arc
					(start 94.176088 5.523992)
					(mid 93.817948 5.165852)
					(end 94.176088 4.807712)
				)
			)
		)
		(polygon
			(pts
				(arc
					(start 92.601542 4.807712)
					(mid 92.959428 5.165979)
					(end 92.601288 5.523992)
				)
				(arc
					(start 91.585288 5.523992)
					(mid 91.227148 5.165852)
					(end 91.585288 4.807712)
				)
			)
		)
		(polygon
			(pts
				(arc
					(start 90.010742 4.807712)
					(mid 90.368628 5.165979)
					(end 90.010488 5.523992)
				)
				(arc
					(start 88.994488 5.523992)
					(mid 88.636348 5.165852)
					(end 88.994488 4.807712)
				)
			)
		)
		(polygon
			(pts
				(arc
					(start 87.419942 4.807712)
					(mid 87.777828 5.165979)
					(end 87.419688 5.523992)
				)
				(arc
					(start 86.403688 5.523992)
					(mid 86.045548 5.165852)
					(end 86.403688 4.807712)
				)
			)
		)
		(polygon
			(pts
				(arc
					(start 84.829142 4.807712)
					(mid 85.187028 5.165979)
					(end 84.828888 5.523992)
				)
				(arc
					(start 83.812888 5.523992)
					(mid 83.454748 5.165852)
					(end 83.812888 4.807712)
				)
			)
		)
		(polygon
			(pts
				(arc
					(start 82.238342 4.807712)
					(mid 82.596228 5.165979)
					(end 82.238088 5.523992)
				)
				(arc
					(start 81.222088 5.523992)
					(mid 80.863948 5.165852)
					(end 81.222088 4.807712)
				)
			)
		)
		(polygon
			(pts
				(arc
					(start 79.647542 4.807712)
					(mid 80.005428 5.165979)
					(end 79.647288 5.523992)
				)
				(arc
					(start 78.631288 5.523992)
					(mid 78.273148 5.165852)
					(end 78.631288 4.807712)
				)
			)
		)
		(polygon
			(pts
				(arc
					(start 129.720594 4.848352)
					(mid 130.07848 5.206619)
					(end 129.72034 5.564632)
				)
				(arc
					(start 128.70434 5.564632)
					(mid 128.3462 5.206492)
					(end 128.70434 4.848352)
				)
			)
		)
		(polygon
			(pts
				(arc
					(start 127.129794 4.848352)
					(mid 127.48768 5.206619)
					(end 127.12954 5.564632)
				)
				(arc
					(start 126.11354 5.564632)
					(mid 125.7554 5.206492)
					(end 126.11354 4.848352)
				)
			)
		)
		(polygon
			(pts
				(arc
					(start 124.538994 4.848352)
					(mid 124.89688 5.206619)
					(end 124.53874 5.564632)
				)
				(arc
					(start 123.52274 5.564632)
					(mid 123.1646 5.206492)
					(end 123.52274 4.848352)
				)
			)
		)
		(polygon
			(pts
				(arc
					(start 121.948194 4.848352)
					(mid 122.30608 5.206619)
					(end 121.94794 5.564632)
				)
				(arc
					(start 120.93194 5.564632)
					(mid 120.5738 5.206492)
					(end 120.93194 4.848352)
				)
			)
		)
		(polygon
			(pts
				(arc
					(start 119.357394 4.848352)
					(mid 119.71528 5.206619)
					(end 119.35714 5.564632)
				)
				(arc
					(start 118.34114 5.564632)
					(mid 117.983 5.206492)
					(end 118.34114 4.848352)
				)
			)
		)
		(polygon
			(pts
				(arc
					(start 116.766594 4.848352)
					(mid 117.12448 5.206619)
					(end 116.76634 5.564632)
				)
				(arc
					(start 115.75034 5.564632)
					(mid 115.3922 5.206492)
					(end 115.75034 4.848352)
				)
			)
		)
		(polygon
			(pts
				(arc
					(start 114.175794 4.848352)
					(mid 114.53368 5.206619)
					(end 114.17554 5.564632)
				)
				(arc
					(start 113.15954 5.564632)
					(mid 112.8014 5.206492)
					(end 113.15954 4.848352)
				)
			)
		)
		(polygon
			(pts
				(arc
					(start 111.584994 4.848352)
					(mid 111.94288 5.206619)
					(end 111.58474 5.564632)
				)
				(arc
					(start 110.56874 5.564632)
					(mid 110.2106 5.206492)
					(end 110.56874 4.848352)
				)
			)
		)
		(polygon
			(pts
				(arc
					(start 96.457008 7.343902)
					(mid 96.814894 7.702169)
					(end 96.456754 8.060182)
				)
				(arc
					(start 95.440754 8.060182)
					(mid 95.082614 7.702042)
					(end 95.440754 7.343902)
				)
			)
		)
		(polygon
			(pts
				(arc
					(start 93.866208 7.343902)
					(mid 94.224094 7.702169)
					(end 93.865954 8.060182)
				)
				(arc
					(start 92.849954 8.060182)
					(mid 92.491814 7.702042)
					(end 92.849954 7.343902)
				)
			)
		)
		(polygon
			(pts
				(arc
					(start 91.275408 7.343902)
					(mid 91.633294 7.702169)
					(end 91.275154 8.060182)
				)
				(arc
					(start 90.259154 8.060182)
					(mid 89.901014 7.702042)
					(end 90.259154 7.343902)
				)
			)
		)
		(polygon
			(pts
				(arc
					(start 88.684608 7.343902)
					(mid 89.042494 7.702169)
					(end 88.684354 8.060182)
				)
				(arc
					(start 87.668354 8.060182)
					(mid 87.310214 7.702042)
					(end 87.668354 7.343902)
				)
			)
		)
		(polygon
			(pts
				(arc
					(start 86.093808 7.343902)
					(mid 86.451694 7.702169)
					(end 86.093554 8.060182)
				)
				(arc
					(start 85.077554 8.060182)
					(mid 84.719414 7.702042)
					(end 85.077554 7.343902)
				)
			)
		)
		(polygon
			(pts
				(arc
					(start 83.503008 7.343902)
					(mid 83.860894 7.702169)
					(end 83.502754 8.060182)
				)
				(arc
					(start 82.486754 8.060182)
					(mid 82.128614 7.702042)
					(end 82.486754 7.343902)
				)
			)
		)
		(polygon
			(pts
				(arc
					(start 80.912208 7.343902)
					(mid 81.270094 7.702169)
					(end 80.911954 8.060182)
				)
				(arc
					(start 79.895954 8.060182)
					(mid 79.537814 7.702042)
					(end 79.895954 7.343902)
				)
			)
		)
		(polygon
			(pts
				(arc
					(start 78.321408 7.343902)
					(mid 78.679294 7.702169)
					(end 78.321154 8.060182)
				)
				(arc
					(start 77.305154 8.060182)
					(mid 76.947014 7.702042)
					(end 77.305154 7.343902)
				)
			)
		)
		(polygon
			(pts
				(arc
					(start 128.39446 7.384542)
					(mid 128.752346 7.742809)
					(end 128.394206 8.100822)
				)
				(arc
					(start 127.378206 8.100822)
					(mid 127.020066 7.742682)
					(end 127.378206 7.384542)
				)
			)
		)
		(polygon
			(pts
				(arc
					(start 125.803406 7.384542)
					(mid 126.161546 7.742682)
					(end 125.803406 8.100822)
				)
				(arc
					(start 124.787152 8.100822)
					(mid 124.429266 7.742555)
					(end 124.787406 7.384542)
				)
			)
		)
		(polygon
			(pts
				(arc
					(start 123.21286 7.384542)
					(mid 123.570746 7.742809)
					(end 123.212606 8.100822)
				)
				(arc
					(start 122.196606 8.100822)
					(mid 121.838466 7.742682)
					(end 122.196606 7.384542)
				)
			)
		)
		(polygon
			(pts
				(arc
					(start 120.62206 7.384542)
					(mid 120.979946 7.742809)
					(end 120.621806 8.100822)
				)
				(arc
					(start 119.605806 8.100822)
					(mid 119.247666 7.742682)
					(end 119.605806 7.384542)
				)
			)
		)
		(polygon
			(pts
				(arc
					(start 118.03126 7.384542)
					(mid 118.389146 7.742809)
					(end 118.031006 8.100822)
				)
				(arc
					(start 117.015006 8.100822)
					(mid 116.656866 7.742682)
					(end 117.015006 7.384542)
				)
			)
		)
		(polygon
			(pts
				(arc
					(start 115.44046 7.384542)
					(mid 115.798346 7.742809)
					(end 115.440206 8.100822)
				)
				(arc
					(start 114.424206 8.100822)
					(mid 114.066066 7.742682)
					(end 114.424206 7.384542)
				)
			)
		)
		(polygon
			(pts
				(arc
					(start 112.84966 7.384542)
					(mid 113.207546 7.742809)
					(end 112.849406 8.100822)
				)
				(arc
					(start 111.833406 8.100822)
					(mid 111.475266 7.742682)
					(end 111.833406 7.384542)
				)
			)
		)
		(polygon
			(pts
				(arc
					(start 110.25886 7.384542)
					(mid 110.616746 7.742809)
					(end 110.258606 8.100822)
				)
				(arc
					(start 109.242606 8.100822)
					(mid 108.884466 7.742682)
					(end 109.242606 7.384542)
				)
			)
		)
	)
	(zone
		(layer "Cmts.User")
		(hatch none 0.5)
		(connect_pads
			(clearance 0)
		)
		(min_thickness 0.25)
		(keepout
			(tracks allowed)
			(vias allowed)
			(pads allowed)
			(copperpour allowed)
			(footprints allowed)
		)
		(placement
			(enabled no)
			(sheetname "")
		)
		(fill
			(thermal_gap 0.5)
			(thermal_bridge_width 0.5)
			(island_removal_mode 0)
		)
		(polygon
			(pts
				(xy 76.6064 5.969) (xy 76.6064 7.0104) (xy 97.3836 7.0104) (xy 98.0694 7.0104) (xy 98.298 6.7818)
				(xy 98.298 6.2738) (xy 98.298 5.969)
			)
		)
	)
	(zone
		(layer "Cmts.User")
		(hatch none 0.5)
		(connect_pads
			(clearance 0)
		)
		(min_thickness 0.25)
		(keepout
			(tracks allowed)
			(vias allowed)
			(pads allowed)
			(copperpour allowed)
			(footprints allowed)
		)
		(placement
			(enabled no)
			(sheetname "")
		)
		(fill
			(thermal_gap 0.5)
			(thermal_bridge_width 0.5)
			(island_removal_mode 0)
		)
		(polygon
			(pts
				(xy 122.7328 -29.3878) (xy 122.7328 -26.8478) (xy 125.8951 -26.8478) (xy 125.8951 -29.3878)
			)
		)
	)
	(zone
		(layer "Cmts.User")
		(hatch none 0.5)
		(connect_pads
			(clearance 0)
		)
		(min_thickness 0.25)
		(keepout
			(tracks allowed)
			(vias allowed)
			(pads allowed)
			(copperpour allowed)
			(footprints allowed)
		)
		(placement
			(enabled no)
			(sheetname "")
		)
		(fill
			(thermal_gap 0.5)
			(thermal_bridge_width 0.5)
			(island_removal_mode 0)
		)
		(polygon
			(pts
				(xy 20.4978 -25.6032) (xy 20.4978 -23.0378) (xy 23.1902 -23.0378) (xy 23.1902 -25.6032)
			)
		)
	)
	(zone
		(layer "Cmts.User")
		(hatch none 0.5)
		(connect_pads
			(clearance 0)
		)
		(min_thickness 0.25)
		(keepout
			(tracks allowed)
			(vias allowed)
			(pads allowed)
			(copperpour allowed)
			(footprints allowed)
		)
		(placement
			(enabled no)
			(sheetname "")
		)
		(fill
			(thermal_gap 0.5)
			(thermal_bridge_width 0.5)
			(island_removal_mode 0)
		)
		(polygon
			(pts
				(xy 108.6358 6.096) (xy 108.6358 7.2263) (xy 130.3655 7.2263) (xy 130.3782 7.2136) (xy 130.3782 6.096)
			)
		)
	)
	(zone
		(layer "Cmts.User")
		(hatch none 0.5)
		(connect_pads
			(clearance 0)
		)
		(min_thickness 0.25)
		(keepout
			(tracks allowed)
			(vias allowed)
			(pads allowed)
			(copperpour allowed)
			(footprints allowed)
		)
		(placement
			(enabled no)
			(sheetname "")
		)
		(fill
			(thermal_gap 0.5)
			(thermal_bridge_width 0.5)
			(island_removal_mode 0)
		)
		(polygon
			(pts
				(xy 21.3868 -26.1112) (xy 23.0632 -26.1112) (xy 23.1394 -26.1874) (xy 23.1394 -27.8384) (xy 23.0886 -27.8892)
				(xy 21.463 -27.8892) (xy 21.4122 -27.8892) (xy 21.3868 -27.8638) (xy 21.3868 -27.813)
			)
		)
	)
	(zone
		(layer "Cmts.User")
		(hatch none 0.5)
		(connect_pads
			(clearance 0)
		)
		(min_thickness 0.25)
		(keepout
			(tracks allowed)
			(vias allowed)
			(pads allowed)
			(copperpour allowed)
			(footprints allowed)
		)
		(placement
			(enabled no)
			(sheetname "")
		)
		(fill
			(thermal_gap 0.5)
			(thermal_bridge_width 0.5)
			(island_removal_mode 0)
		)
		(polygon
			(pts
				(xy 18.8214 -21.4884) (xy 18.8214 -16.3576) (xy 24.0538 -16.3576) (xy 24.0538 -21.4884) (xy 24.0538 -21.6916)
				(xy 23.7998 -21.9456) (xy 18.9484 -21.9456) (xy 18.8214 -21.8186)
			)
		)
	)
)
